FILE_TYPE = MULTI_PHYS_TABLE;

PART 'Q_CAP'

{========================================================================================}
:VALUE      | VOLTAGE | TOLERANCE | PACK_TYPE   | MATERIAL  | PART_NUMBER        = STANDARD        | LIFECYCLE          | ASS_PART | PART_NUMBER       | JEDEC_TYPE                | ALT_SYMBOLS                                                          | VALUE      | RATED_VOLTAGE | TOL      | CLASS      | DESCRIPTION                                                    | COMPONENT_TYPE | LEAD_LENGTH | LPID | DATE       ;
{========================================================================================}
 '1UF'      | '25V'   | '10%'     | '0603'      | 'COG'     | 'TMP_QCH5104K9906'(!) = 'End of Design' | 'Comp-Release Qty' | ''       | 'CH5104K9906'     |'C0603'| '(SMC0603AW)'                                                        | '1UF'      | '25V'         | '10%'    | 'DISCRETE' | 'CHIP0603'                                                     | 'CHIP0603'     | ''          | ''   | ''        
 '1UF'      | '25V'   | '10%'     | '0603'      | 'EMPTY'   | 'TMP_QCH5104K9906'(!) = 'End of Design' | 'Comp-Release Qty' | ''       | 'CH5104K9906'     |'C0603'| '(SMC0603AW)'                                                        | 'NA'       | '25V'         | '10%'    | 'IO'       | 'CHIP0603'                                                     | 'CHIP0603'     | ''          | ''   | ''        
 '0.1UF'    | '25V'   | '10%'     | '0603'      | 'X7R'     | 'TMP_QCH41004K910'(!) = 'End of Design' | 'Comp-Approve'     | ''       | 'CH41004K910'     |'C0603'| '(SMC0603AW)'                                                        | '0.1UF'    | '25V'         | '10%'    | 'DISCRETE' | 'CHIP0603'                                                     | 'CHIP0603'     | ''          | ''   | ''        
 '0.1UF'    | '25V'   | '10%'     | '0603'      | 'EMPTY'   | 'TMP_QCH41004K910'(!) = 'End of Design' | 'Comp-Approve'     | ''       | 'CH41004K910'     |'C0603'| '(SMC0603AW)'                                                        | 'NA'       | '25V'         | '10%'    | 'IO'       | 'CHIP0603'                                                     | 'CHIP0603'     | ''          | ''   | ''        
 '15PF'     | '50V'   | '5%'      | '0603'      | 'X7R'     | 'TMP_QCH0156J0910'(!) = 'End of Design' | 'Comp-Approve'     | ''       | 'CH0156J0910'     |'C0603'| '(SMC0603AW)'                                                        | '15PF'     | '50V'         | '5%'     | 'DISCRETE' | 'CHIP0603'                                                     | 'CHIP0603'     | ''          | ''   | ''        
 '15PF'     | '50V'   | '5%'      | '0603'      | 'EMPTY'   | 'TMP_QCH0156J0910'(!) = 'End of Design' | 'Comp-Approve'     | ''       | 'CH0156J0910'     |'C0603'| '(SMC0603AW)'                                                        | 'NA'       | '50V'         | '5%'     | 'IO'       | 'CHIP0603'                                                     | 'CHIP0603'     | ''          | ''   | ''        
 '3300PF'   | '50V'   | '10%'     | '0402'      | 'X7R'     | 'TMP_QCH2336K1B12'(!) = ''              | ''                 | ''       | 'CH2336K1B12'     |'C0402'| '(C0402-0201)'                                                       | '3300PF'   | '50V'         | '10%'    | 'DISCRETE' | 'CHIP0402'                                                     | 'CHIP0402'     | ''          | ''   | ''        
 '3300PF'   | '50V'   | '10%'     | '0402'      | 'EMPTY'   | 'TMP_QCH2336K1B12'(!) = ''              | ''                 | ''       | 'CH2336K1B12'     |'C0402'| '(C0402-0201)'                                                       | 'NA'       | '50V'         | '10%'    | 'IO'       | 'CHIP0402'                                                     | 'CHIP0402'     | ''          | ''   | ''        
 '10UF'     | '25V'   | '20%'     | '1206'      | 'X6S'     | 'TMP_QCH61004M2E8'(!) = 'End of Design' | 'Comp-Approve'     | ''       | 'CH61004M2E8'     |'C1206_H76'| '(SMC1206AW)'                                                        | '10UF'     | '25V'         | '20%'    | 'DISCRETE' | 'CHIP1206'                                                     | 'CHIP1206'     | ''          | ''   | ''        
 '10UF'     | '25V'   | '20%'     | '1206'      | 'EMPTY'   | 'TMP_QCH61004M2E8'(!) = 'End of Design' | 'Comp-Approve'     | ''       | 'CH61004M2E8'     |'C1206_H76'| '(SMC1206AW)'                                                        | 'NA'       | '25V'         | '20%'    | 'IO'       | 'CHIP1206'                                                     | 'CHIP1206'     | ''          | ''   | ''        
 '1UF'      | '16V'   | '10%'     | '0402'      | 'X5R'     | 'TMP_QCH5103K9B00'(!) = 'End of Design' | 'Comp-Approve'     | ''       | 'CH5103K9B00'     |'C0402'| '(C0402-0201)'                                                       | '1UF'      | '16V'         | '10%'    | 'DISCRETE' | 'CHIP0402'                                                     | 'CHIP0402'     | ''          | ''   | ''        
 '1UF'      | '16V'   | '10%'     | '0402'      | 'EMPTY'   | 'TMP_QCH5103K9B00'(!) = 'End of Design' | 'Comp-Approve'     | ''       | 'CH5103K9B00'     |'C0402'| '(C0402-0201)'                                                       | 'NA'       | '16V'         | '10%'    | 'IO'       | 'CHIP0402'                                                     | 'CHIP0402'     | ''          | ''   | ''        
 '1UF'      | '25V'   | '10%'     | '0805'      | 'X7R'     | 'TMP_QCH51004KE12'(!) = 'End of Design' | 'Comp-Approve'     | ''       | 'CH51004KE12'     |'C0805_H61'| '(SMC0805AW)'                                                        | '1UF'      | '25V'         | '10%'    | 'DISCRETE' | 'CHIP0805'                                                     | 'CHIP0805'     | ''          | ''   | ''        
 '1UF'      | '25V'   | '10%'     | '0805'      | 'EMPTY'   | 'TMP_QCH51004KE12'(!) = 'End of Design' | 'Comp-Approve'     | ''       | 'CH51004KE12'     |'C0805_H61'| '(SMC0805AW)'                                                        | 'NA'       | '25V'         | '10%'    | 'IO'       | 'CHIP0805'                                                     | 'CHIP0805'     | ''          | ''   | ''        
 '1UF'      | '50V'   | '10%'     | '1206'      | 'X7R'     | 'TMP_QCH5106K1200'(!) = 'End of Design' | 'Comp-Approve'     | ''       | 'CH5106K1200'     |'C1206_H56'| '(SMC1206AW)'                                                        | '1UF'      | '50V'         | '10%'    | 'DISCRETE' | 'CHIP1206'                                                     | 'CHIP1206'     | ''          | ''   | ''        
 '1UF'      | '50V'   | '10%'     | '1206'      | 'EMPTY'   | 'TMP_QCH5106K1200'(!) = 'End of Design' | 'Comp-Approve'     | ''       | 'CH5106K1200'     |'C1206_H56'| '(SMC1206AW)'                                                        | 'NA'       | '50V'         | '10%'    | 'IO'       | 'CHIP1206'                                                     | 'CHIP1206'     | ''          | ''   | ''        
 '0.47UF'   | '25V'   | '10%'     | '0805'      | 'X7R'     | 'TMP_QCH44704KE14'(!) = ''              | ''                 | ''       | 'CH44704KE14'     |'C0805_H61'| '(SMC0805AW)'                                                        | '0.47UF'   | '25V'         | '10%'    | 'DISCRETE' | 'CHIP0805'                                                     | 'CHIP0805'     | ''          | ''   | ''        
 '0.47UF'   | '25V'   | '10%'     | '0805'      | 'EMPTY'   | 'TMP_QCH44704KE14'(!) = ''              | ''                 | ''       | 'CH44704KE14'     |'C0805_H61'| '(SMC0805AW)'                                                        | 'NA'       | '25V'         | '10%'    | 'IO'       | 'CHIP0805'                                                     | 'CHIP0805'     | ''          | ''   | ''        
 '0.22UF'   | '25V'   | '20%'     | '0805'      | 'X7R'     | 'TMP_QCH42204ME13'(!) = 'End of Design' | 'Comp-Approve'     | ''       | 'CH5106K1200'     |'C0805_H43'| '(SMC0805AW)'                                                        | '0.22UF'   | '25V'         | '20%'    | 'DISCRETE' | 'CHIP0805'                                                     | 'CHIP0805'     | ''          | ''   | ''        
 '0.22UF'   | '25V'   | '20%'     | '0805'      | 'EMPTY'   | 'TMP_QCH42204ME13'(!) = 'End of Design' | 'Comp-Approve'     | ''       | 'CH5106K1200'     |'C0805_H43'| '(SMC0805AW)'                                                        | 'NA'       | '25V'         | '20%'    | 'IO'       | 'CHIP0805'                                                     | 'CHIP0805'     | ''          | ''   | ''        
 '100PF'    | '50V'   | '10%'     | '0402'      | 'X7R'     | 'TMP_QCH1106K1B00'(!) = 'End of Design' | 'Comp-Approve'     | ''       | 'CH1106K1B00'     |'C0402'| '(C0402-0201)'                                                       | '100PF'    | '50V'         | '10%'    | 'DISCRETE' | 'CHIP0402'                                                     | 'CHIP0402'     | ''          | ''   | ''        
 '100PF'    | '50V'   | '10%'     | '0402'      | 'EMPTY'   | 'TMP_QCH1106K1B00'(!) = 'End of Design' | 'Comp-Approve'     | ''       | 'CH1106K1B00'     |'C0402'| '(C0402-0201)'                                                       | 'NA'       | '50V'         | '10%'    | 'IO'       | 'CHIP0402'                                                     | 'CHIP0402'     | ''          | ''   | ''        
 '150PF'    | '50V'   | '5%'      | '0402'      | 'NPO'     | 'TMP_QCH11506JB08'(!) = ''              | ''                 | ''       | 'CH11506JB08'     |'C0402'| '(C0402-0201)'                                                       | '150PF'    | '50V'         | '5%'     | 'DISCRETE' | 'CHIP0402'                                                     | 'CHIP0402'     | ''          | ''   | ''        
 '150PF'    | '50V'   | '5%'      | '0402'      | 'EMPTY'   | 'TMP_QCH11506JB08'(!) = ''              | ''                 | ''       | 'CH11506JB08'     |'C0402'| '(C0402-0201)'                                                       | 'NA'       | '50V'         | '5%'     | 'IO'       | 'CHIP0402'                                                     | 'CHIP0402'     | ''          | ''   | ''        
 '100PF'    | '50V'   | '5%'      | '0603'      | 'NPO'     | 'TMP_QCH11006J901'(!) = 'End of Design' | 'Comp-Approve'     | ''       | 'CH11006J901'     |'C0603'| '(SMC0603AW)'                                                        | '100PF'    | '50V'         | '5%'     | 'DISCRETE' | 'CHIP0603'                                                     | 'CHIP0603'     | ''          | ''   | ''        
 '100PF'    | '50V'   | '5%'      | '0603'      | 'EMPTY'   | 'TMP_QCH11006J901'(!) = 'End of Design' | 'Comp-Approve'     | ''       | 'CH11006J901'     |'C0603'| '(SMC0603AW)'                                                        | 'NA'       | '50V'         | '5%'     | 'IO'       | 'CHIP0603'                                                     | 'CHIP0603'     | ''          | ''   | ''        
 '220PF'    | '50V'   | '5%'      | '0603'      | 'NPO'     | 'TMP_QCH12206J901'(!) = 'End of Design' | 'Comp-Approve'     | ''       | 'CH12206J901'     |'C0603'| '(SMC0603AW)'                                                        | '220PF'    | '50V'         | '5%'     | 'DISCRETE' | 'CHIP0603'                                                     | 'CHIP0603'     | ''          | ''   | ''        
 '220PF'    | '50V'   | '5%'      | '0603'      | 'EMPTY'   | 'TMP_QCH12206J901'(!) = 'End of Design' | 'Comp-Approve'     | ''       | 'CH12206J901'     |'C0603'| '(SMC0603AW)'                                                        | 'NA'       | '50V'         | '5%'     | 'IO'       | 'CHIP0603'                                                     | 'CHIP0603'     | ''          | ''   | ''        
 '470PF'    | '50V'   | '5%'      | '0603'      | 'NPO'     | 'TMP_QCH14706J904'(!) = 'End of Design' | 'Comp-Release Qty' | ''       | 'CH14706J904'     |'C0603'| '(SMC0603AW)'                                                        | '470PF'    | '50V'         | '5%'     | 'DISCRETE' | 'CHIP0603'                                                     | 'CHIP0603'     | ''          | ''   | ''        
 '470PF'    | '50V'   | '5%'      | '0603'      | 'EMPTY'   | 'TMP_QCH14706J904'(!) = 'End of Design' | 'Comp-Release Qty' | ''       | 'CH14706J904'     |'C0603'| '(SMC0603AW)'                                                        | 'NA'       | '50V'         | '5%'     | 'IO'       | 'CHIP0603'                                                     | 'CHIP0603'     | ''          | ''   | ''        
 '680PF'    | '50V'   | '10%'     | '0603'      | 'X7R'     | 'TMP_QCH16806K918'(!) = ''              | ''                 | ''       | 'CH16806K918'     |'C0603'| '(SMC0603AW)'                                                        | '680PF'    | '50V'         | '10%'    | 'DISCRETE' | 'CHIP0603'                                                     | 'CHIP0603'     | ''          | ''   | ''        
 '680PF'    | '50V'   | '10%'     | '0603'      | 'EMPTY'   | 'TMP_QCH16806K918'(!) = ''              | ''                 | ''       | 'CH16806K918'     |'C0603'| '(SMC0603AW)'                                                        | 'NA'       | '50V'         | '10%'    | 'IO'       | 'CHIP0603'                                                     | 'CHIP0603'     | ''          | ''   | ''        
 '0.022UF'  | '25V'   | '10%'     | '0603'      | 'X7R'     | 'TMP_QCH32204K918'(!) = 'End of Design' | 'Comp-Approve'     | ''       | 'CH32204K918'     |'C0603'| '(SMC0603AW)'                                                        | '0.022UF'  | '25V'         | '10%'    | 'DISCRETE' | 'CHIP0603'                                                     | 'CHIP0603'     | ''          | ''   | ''        
 '0.022UF'  | '25V'   | '10%'     | '0603'      | 'EMPTY'   | 'TMP_QCH32204K918'(!) = 'End of Design' | 'Comp-Approve'     | ''       | 'CH32204K918'     |'C0603'| '(SMC0603AW)'                                                        | 'NA'       | '25V'         | '10%'    | 'IO'       | 'CHIP0603'                                                     | 'CHIP0603'     | ''          | ''   | ''        
 '0.22UF'   | '25V'   | '10%'     | '0603'      | 'X7R'     | 'TMP_QCH4224K1900'(!) = 'End of Design' | 'Comp-Release Qty' | ''       | 'CH4224K1900'     |'C0603'| '(SMC0603AW)'                                                        | '0.22UF'   | '25V'         | '10%'    | 'DISCRETE' | 'CHIP0603'                                                     | 'CHIP0603'     | ''          | ''   | ''        
 '0.22UF'   | '25V'   | '10%'     | '0603'      | 'EMPTY'   | 'TMP_QCH4224K1900'(!) = 'End of Design' | 'Comp-Release Qty' | ''       | 'CH4224K1900'     |'C0603'| '(SMC0603AW)'                                                        | 'NA'       | '25V'         | '10%'    | 'IO'       | 'CHIP0603'                                                     | 'CHIP0603'     | ''          | ''   | ''        
 '10UF'     | '10V'   | '10%'     | '0805'      | 'X7R'     | 'TMP_QCH6102K1A00'(!) = ''              | ''                 | ''       | 'CH6102K1A00'     |'C0805_H61'| '(SMC0805AW)'                                                        | '10UFF'    | '10V'         | '10%'    | 'DISCRETE' | 'CHIP0805'                                                     | 'CHIP0805'     | ''          | ''   | ''        
 '10UF'     | '10V'   | '10%'     | '0805'      | 'EMPTY'   | 'TMP_QCH6102K1A00'(!) = ''              | ''                 | ''       | 'CH6102K1A00'     |'C0805_H61'| '(SMC0805AW)'                                                        | 'NA'       | '10V'         | '10%'    | 'IO'       | 'CHIP0805'                                                     | 'CHIP0805'     | ''          | ''   | ''        
 '10UF'     | '10V'   | '10%'     | '1206'      | 'X5R'     | 'TMP_QCH61002K297'(!) = 'End of Design' | 'Comp-Approve'     | ''       | 'CH61002K297'     |'C1206_H76'| '(SMC1206AW)'                                                        | '10UF'     | '10V'         | '10%'    | 'DISCRETE' | 'CHIP1206'                                                     | 'CHIP1206'     | ''          | ''   | ''        
 '10UF'     | '10V'   | '10%'     | '1206'      | 'EMPTY'   | 'TMP_QCH61002K297'(!) = 'End of Design' | 'Comp-Approve'     | ''       | 'CH61002K297'     |'C1206_H76'| '(SMC1206AW)'                                                        | 'NA'       | '10V'         | '10%'    | 'IO'       | 'CHIP1206'                                                     | 'CHIP1206'     | ''          | ''   | ''        
 '1UF'      | '10V'   | '10%'     | '0603'      | 'X7R'     | 'TMP_QCH5102K1906'(!) = 'End of Design' | 'Comp-Approve'     | ''       | 'CH5102K1906'     |'C0603'| '(SMC0603AW)'                                                        | '1UF'      | '10V'         | '10%'    | 'DISCRETE' | 'CHIP0603'                                                     | 'CHIP0603'     | ''          | ''   | ''        
 '1UF'      | '10V'   | '10%'     | '0603'      | 'EMPTY'   | 'TMP_QCH5102K1906'(!) = 'End of Design' | 'Comp-Approve'     | ''       | 'CH5102K1906'     |'C0603'| '(SMC0603AW)'                                                        | 'NA'       | '10V'         | '10%'    | 'IO'       | 'CHIP0603'                                                     | 'CHIP0603'     | ''          | ''   | ''        
 '47UF'     | '4V'    | '20%'     | '1206'      | 'X6S'     | 'TMP_QCH647KME200'(!) = 'End of Design' | 'Comp-Approve'     | ''       | 'CH647KME200'     |'C1206_H66'| '(SMC1206AW)'                                                        | '47UF'     | '4V'          | '20%'    | 'DISCRETE' | 'CHIP1206'                                                     | 'CHIP1206'     | ''          | ''   | ''        
 '47UF'     | '4V'    | '20%'     | '1206'      | 'EMPTY'   | 'TMP_QCH647KME200'(!) = 'End of Design' | 'Comp-Approve'     | ''       | 'CH647KME200'     |'C1206_H66'| '(SMC1206AW)'                                                        | 'NA'       | '4V'          | '20%'    | 'IO'       | 'CHIP1206'                                                     | 'CHIP1206'     | ''          | ''   | ''        
 '22UF'     | '6.3V'  | '20%'     | '0805'      | 'X5R'     | 'TMP_QCH6221M9A02'(!) = 'End of Design' | 'End of Life'      | ''       | 'CH6221M9A02'     |'C0805_H61_EOL'| '(SMC0805AW)'                                                        | '22UF'     | '6.3V'        | '20%'    | 'DISCRETE' | 'CHIP0805'                                                     | 'CHIP0805'     | ''          | ''   | ''        
 '22UF'     | '6.3V'  | '20%'     | '0805'      | 'EMPTY'   | 'TMP_QCH6221M9A02'(!) = 'End of Design' | 'End of Life'      | ''       | 'CH6221M9A02'     |'C0805_H61_EOL'| '(SMC0805AW)'                                                        | 'NA'       | '6.3V'        | '20%'    | 'IO'       | 'CHIP0805'                                                     | 'CHIP0805'     | ''          | ''   | ''        
 '22UF'     | '6.3V'  | '20%'     | '1206'      | 'X7R'     | 'TMP_QCH6221M1203'(!) = 'End of Design' | 'Comp-Approve'     | ''       | 'CH6221M1203'     |'C1206_H76'| '(SMC1206AW)'                                                        | '22UF'     | '6.3V'        | '20%'    | 'DISCRETE' | 'CHIP1206'                                                     | 'CHIP1206'     | ''          | ''   | ''        
 '22UF'     | '6.3V'  | '20%'     | '1206'      | 'EMPTY'   | 'TMP_QCH6221M1203'(!) = 'End of Design' | 'Comp-Approve'     | ''       | 'CH6221M1203'     |'C1206_H76'| '(SMC1206AW)'                                                        | 'NA'       | '6.3V'        | '20%'    | 'IO'       | 'CHIP1206'                                                     | 'CHIP1206'     | ''          | ''   | ''        
 '22UF'     | '4V'    | '20%'     | '0805'      | 'X6S'     | 'TMP_QCH622KMEA01'(!) = 'End of Design' | 'Comp-Approve'     | ''       | 'CH622KMEA01'     |'C0805_H61'| '(SMC0805AW)'                                                        | '22UF'     | '4V'          | '20%'    | 'DISCRETE' | 'CHIP0805'                                                     | 'CHIP0805'     | ''          | ''   | ''        
 '22UF'     | '4V'    | '20%'     | '0805'      | 'EMPTY'   | 'TMP_QCH622KMEA01'(!) = 'End of Design' | 'Comp-Approve'     | ''       | 'CH622KMEA01'     |'C0805_H61'| '(SMC0805AW)'                                                        | 'NA'       | '4V'          | '20%'    | 'IO'       | 'CHIP0805'                                                     | 'CHIP0805'     | ''          | ''   | ''        
 '0.22UF'   | '16V'   | '10%'     | '0603'      | 'X7R'     | 'TMP_QCH4223K1909'(!) = 'End of Design' | 'Comp-Approve'     | ''       | 'CH4223K1909'     |'C0603'| '(SMC0603AW)'                                                        | '0.22UF'   | '16V'         | '10%'    | 'DISCRETE' | 'CHIP0603'                                                     | 'CHIP0603'     | ''          | ''   | ''        
 '0.22UF'   | '16V'   | '10%'     | '0603'      | 'EMPTY'   | 'TMP_QCH4223K1909'(!) = 'End of Design' | 'Comp-Approve'     | ''       | 'CH4223K1909'     |'C0603'| '(SMC0603AW)'                                                        | 'NA'       | '16V'         | '10%'    | 'IO'       | 'CHIP0603'                                                     | 'CHIP0603'     | ''          | ''   | ''        
 '0.47UF'   | '16V'   | '10%'     | '0603'      | 'X7R'     | 'TMP_QCH4473K1902'(!) = 'End of Design' | 'Comp-Approve'     | ''       | 'CH4473K1902'     |'C0603'| '(SMC0603AW)'                                                        | '0.47UF'   | '16V'         | '10%'    | 'DISCRETE' | 'CHIP0603'                                                     | 'CHIP0603'     | ''          | ''   | ''        
 '0.47UF'   | '16V'   | '10%'     | '0603'      | 'EMPTY'   | 'TMP_QCH4473K1902'(!) = 'End of Design' | 'Comp-Approve'     | ''       | 'CH4473K1902'     |'C0603'| '(SMC0603AW)'                                                        | 'NA'       | '16V'         | '10%'    | 'IO'       | 'CHIP0603'                                                     | 'CHIP0603'     | ''          | ''   | ''        
 '10UF'     | '16V'   | '10%'     | '1206'      | 'X7R'     | 'TMP_QCH6103K1201'(!) = 'End of Design' | 'Comp-Approve'     | ''       | 'CH6103K1201'     |'C1206_H66'| '(SMC1206AW)'                                                        | '10UF'     | '16V'         | '10%'    | 'DISCRETE' | 'CHIP1206'                                                     | 'CHIP1206'     | ''          | ''   | ''        
 '10UF'     | '16V'   | '10%'     | '1206'      | 'EMPTY'   | 'TMP_QCH6103K1201'(!) = 'End of Design' | 'Comp-Approve'     | ''       | 'CH6103K1201'     |'C1206_H66'| '(SMC1206AW)'                                                        | 'NA'       | '16V'         | '10%'    | 'IO'       | 'CHIP1206'                                                     | 'CHIP1206'     | ''          | ''   | ''        
 '2.2UF'    | '16V'   | '10%'     | '0603'      | 'X5R'     | 'TMP_QCH5223K9901'(!) = 'End of Design' | 'Comp-Release Qty' | ''       | 'CH5223K9901'     |'C0603'| '(SMC0603AW)'                                                        | '2.2UF'    | '16V'         | '10%'    | 'DISCRETE' | 'CHIP0603'                                                     | 'CHIP0603'     | ''          | ''   | ''        
 '2.2UF'    | '16V'   | '10%'     | '0603'      | 'EMPTY'   | 'TMP_QCH5223K9901'(!) = 'End of Design' | 'Comp-Release Qty' | ''       | 'CH5223K9901'     |'C0603'| '(SMC0603AW)'                                                        | 'NA'       | '16V'         | '10%'    | 'IO'       | 'CHIP0603'                                                     | 'CHIP0603'     | ''          | ''   | ''        
 '0.22UF'   | '10V'   | '10%'     | '0402'      | 'X5R'     | 'TMP_QCH4222K9B04'(!) = 'End of Design' | 'Comp-Release Qty' | ''       | 'CH4222K9B04'     |'C0402'| '(C0402-0201)'                                                       | '0.22UF'   | '10V'         | '10%'    | 'DISCRETE' | 'CHIP0402'                                                     | 'CHIP0402'     | ''          | ''   | ''        
 '0.22UF'   | '10V'   | '10%'     | '0402'      | 'EMPTY'   | 'TMP_QCH4222K9B04'(!) = 'End of Design' | 'Comp-Release Qty' | ''       | 'CH4222K9B04'     |'C0402'| '(C0402-0201)'                                                       | 'NA'       | '10V'         | '10%'    | 'IO'       | 'CHIP0402'                                                     | 'CHIP0402'     | ''          | ''   | ''        
 '1800PF'   | '50V'   | '10%'     | '0603'      | 'X7R'     | 'TMP_QCH21806K916'(!) = 'End of Design' | 'Comp-Approve'     | ''       | 'CH21806K916'     |'C0603'| '(SMC0603AW)'                                                        | '1800PF'   | '50V'         | '10%'    | 'DISCRETE' | 'CHIP0603'                                                     | 'CHIP0603'     | ''          | ''   | ''        
 '1800PF'   | '50V'   | '10%'     | '0603'      | 'EMPTY'   | 'TMP_QCH21806K916'(!) = 'End of Design' | 'Comp-Approve'     | ''       | 'CH21806K916'     |'C0603'| '(SMC0603AW)'                                                        | 'NA'       | '50V'         | '10%'    | 'IO'       | 'CHIP0603'                                                     | 'CHIP0603'     | ''          | ''   | ''        
 '10PF'     | '50V'   | '1%'      | '0402'      | 'NPO'     | 'TMP_QCH0106F0B00'(!) = ''              | ''                 | ''       | 'CH0106F0B00'     |'C0402'| '(C0402-0201)'                                                       | '10PF'     | '50V'         | '1%'     | 'DISCRETE' | 'CHIP0402'                                                     | 'CHIP0402'     | ''          | ''   | ''        
 '10PF'     | '50V'   | '1%'      | '0402'      | 'EMPTY'   | 'TMP_QCH0106F0B00'(!) = ''              | ''                 | ''       | 'CH0106F0B00'     |'C0402'| '(C0402-0201)'                                                       | 'NA'       | '50V'         | '1%'     | 'IO'       | 'CHIP0402'                                                     | 'CHIP0402'     | ''          | ''   | ''        
 '1000PF'   | '16V'   | '10%'     | '0402'      | 'X7R'     | 'TMP_QCH2103K1B04'(!) = ''              | ''                 | ''       | 'CH2103K1B04'     |'C0402'| '(C0402-0201,C0402_OCTAGONXA)'                                       | '1000PF'   | '16V'         | '10%'    | 'DISCRETE' | 'CHIP0402'                                                     | 'CHIP0402'     | ''          | ''   | ''        
 '1000PF'   | '16V'   | '10%'     | '0402'      | 'EMPTY'   | 'TMP_QCH2103K1B04'(!) = ''              | ''                 | ''       | 'CH2103K1B04'     |'C0402'| '(C0402-0201,C0402_OCTAGONXA)'                                       | 'NA'       | '16V'         | '10%'    | 'IO'       | 'CHIP0402'                                                     | 'CHIP0402'     | ''          | ''   | ''        
 '0.01UF'   | '16V'   | '10%'     | '0402'      | 'X7R'     | 'TMP_QCH31003KB11'(!) = 'End of Design' | 'Comp-Approve'     | ''       | 'CH31003KB11'     |'C0402'| '(C0402-0201)'                                                       | '0.01UF'   | '16V'         | '10%'    | 'DISCRETE' | 'CHIP0402'                                                     | 'CHIP0402'     | ''          | ''   | ''        
 '0.01UF'   | '16V'   | '10%'     | '0402'      | 'EMPTY'   | 'TMP_QCH31003KB11'(!) = 'End of Design' | 'Comp-Approve'     | ''       | 'CH31003KB11'     |'C0402'| '(C0402-0201)'                                                       | 'NA'       | '16V'         | '10%'    | 'IO'       | 'CHIP0402'                                                     | 'CHIP0402'     | ''          | ''   | ''        
 '4.7UF'    | '16V'   | '20%'     | '0805'      | 'X7R'     | 'TMP_QCH5473M1A00'(!) = 'End of Design' | 'Comp-Approve'     | ''       | 'CH5473M1A00'     |'C0805_H61'| '(SMC0805AW)'                                                        | '4.7UF'    | '16V'         | '20%'    | 'DISCRETE' | 'CHIP0805'                                                     | 'CHIP0805'     | ''          | ''   | ''        
 '4.7UF'    | '16V'   | '20%'     | '0805'      | 'EMPTY'   | 'TMP_QCH5473M1A00'(!) = 'End of Design' | 'Comp-Approve'     | ''       | 'CH5473M1A00'     |'C0805_H61'| '(SMC0805AW)'                                                        | 'NA'       | '16V'         | '20%'    | 'IO'       | 'CHIP0805'                                                     | 'CHIP0805'     | ''          | ''   | ''        
 '470PF'    | '50V'   | '10%'     | '0402'      | 'X7R'     | 'TMP_QCH14706KB18'(!) = ''              | ''                 | ''       | 'CH14706KB18'     |'C0402'| '(C0402-0201)'                                                       | '470PF'    | '50V'         | '10%'    | 'DISCRETE' | 'CHIP0402'                                                     | 'CHIP0402'     | ''          | ''   | ''        
 '470PF'    | '50V'   | '10%'     | '0402'      | 'EMPTY'   | 'TMP_QCH14706KB18'(!) = ''              | ''                 | ''       | 'CH14706KB18'     |'C0402'| '(C0402-0201)'                                                       | 'NA'       | '50V'         | '10%'    | 'IO'       | 'CHIP0402'                                                     | 'CHIP0402'     | ''          | ''   | ''        
 '1500PF'   | '50V'   | '10%'     | '0402'      | 'X7R'     | 'TMP_QCH21506KB14'(!) = ''              | ''                 | ''       | 'CH21506KB14'     |'C0402'| '(C0402-0201)'                                                       | '1500PF'   | '50V'         | '10%'    | 'DISCRETE' | 'CHIP0402'                                                     | 'CHIP0402'     | ''          | ''   | ''        
 '1500PF'   | '50V'   | '10%'     | '0402'      | 'EMPTY'   | 'TMP_QCH21506KB14'(!) = ''              | ''                 | ''       | 'CH21506KB14'     |'C0402'| '(C0402-0201)'                                                       | 'NA'       | '50V'         | '10%'    | 'IO'       | 'CHIP0402'                                                     | 'CHIP0402'     | ''          | ''   | ''        
 '22PF'     | '50V'   | '5%'      | '0402'      | 'NPO'     | 'TMP_QCH02206JB08'(!) = ''              | ''                 | ''       | 'CH02206JB08'     |'C0402'| '(C0402-0201)'                                                       | '22PF'     | '50V'         | '5%'     | 'DISCRETE' | 'CHIP0402'                                                     | 'CHIP0402'     | ''          | ''   | ''        
 '22PF'     | '50V'   | '5%'      | '0402'      | 'EMPTY'   | 'TMP_QCH02206JB08'(!) = ''              | ''                 | ''       | 'CH02206JB08'     |'C0402'| '(C0402-0201)'                                                       | 'NA'       | '50V'         | '5%'     | 'IO'       | 'CHIP0402'                                                     | 'CHIP0402'     | ''          | ''   | ''        
 '33PF'     | '50V'   | '5%'      | '0402'      | 'NPO'     | 'TMP_QCH03306JB04'(!) = ''              | ''                 | ''       | 'CH03306JB04'     |'C0402'| '(C0402-0201)'                                                       | '33PF'     | '50V'         | '15%'    | 'DISCRETE' | 'CHIP0402'                                                     | 'CHIP0402'     | ''          | ''   | ''        
 '33PF'     | '50V'   | '5%'      | '0402'      | 'EMPTY'   | 'TMP_QCH03306JB04'(!) = ''              | ''                 | ''       | 'CH03306JB04'     |'C0402'| '(C0402-0201)'                                                       | 'NA'       | '50V'         | '5%'     | 'IO'       | 'CHIP0402'                                                     | 'CHIP0402'     | ''          | ''   | ''        
 '47PF'     | '50V'   | '5%'      | '0402'      | 'NPO'     | 'TMP_QCH04706JB01'(!) = ''              | ''                 | ''       | 'CH04706JB01'     |'C0402'| '(C0402-0201)'                                                       | '47PF'     | '50V'         | '5%'     | 'DISCRETE' | 'CHIP0402'                                                     | 'CHIP0402'     | ''          | ''   | ''        
 '47PF'     | '50V'   | '5%'      | '0402'      | 'EMPTY'   | 'TMP_QCH04706JB01'(!) = ''              | ''                 | ''       | 'CH04706JB01'     |'C0402'| '(C0402-0201)'                                                       | 'NA'       | '50V'         | '5%'     | 'IO'       | 'CHIP0402'                                                     | 'CHIP0402'     | ''          | ''   | ''        
 '680PF'    | '50V'   | '10%'     | '0402'      | 'X7R'     | 'TMP_QCH16806KB17'(!) = ''              | ''                 | ''       | 'CH16806KB17'     |'C0402'| '(C0402-0201)'                                                       | '680PF'    | '50V'         | '10%'    | 'DISCRETE' | 'CAP CHIP 680P 50V(+-10%,X7R,0402)'                            | 'CHIP0402'     | ''          | ''   | ''        
 '680PF'    | '50V'   | '10%'     | '0402'      | 'EMPTY'   | 'TMP_QCH16806KB17'(!) = ''              | ''                 | ''       | 'CH16806KB17'     |'C0402'| '(C0402-0201)'                                                       | 'NA'       | '50V'         | '10%'    | 'IO'       | 'CAP CHIP 680P 50V(+-10%,X7R,0402)'                            | 'CHIP0402'     | ''          | ''   | ''        
 '1UF'      | '10V'   | '10%'     | '0603'      | 'X5R'     | 'TMP_QCH51002K996'(!) = 'End of Design' | 'Comp-Approve'     | ''       | 'CH51002K996'     |'C0603'| '(SMC0603AW)'                                                        | '1UF'      | '10V'         | '10%'    | 'DISCRETE' | 'CHIP0603'                                                     | 'CHIP0603'     | ''          | ''   | ''        
 '1UF'      | '10V'   | '10%'     | '0603'      | 'EMPTY'   | 'TMP_QCH51002K996'(!) = 'End of Design' | 'Comp-Approve'     | ''       | 'CH51002K996'     |'C0603'| '(SMC0603AW)'                                                        | 'NA'       | '10V'         | '10%'    | 'IO'       | 'CHIP0603'                                                     | 'CHIP0603'     | ''          | ''   | ''        
 '10UF'     | '6.3V'  | '10%'     | '0805'      | 'X5R'     | 'TMP_QCH61001ME96'(!) = 'End of Design' | 'Comp-Approve'     | ''       | 'CH61001ME96'     |'C0805_H64'| '(SMC0805AW)'                                                        | '10UF'     | '6.3V'        | '10%'    | 'DISCRETE' | 'CHIP0805'                                                     | 'CHIP0805'     | ''          | ''   | ''        
 '10UF'     | '6.3V'  | '10%'     | '0805'      | 'EMPTY'   | 'TMP_QCH61001ME96'(!) = 'End of Design' | 'Comp-Approve'     | ''       | 'CH61001ME96'     |'C0805_H64'| '(SMC0805AW)'                                                        | 'NA'       | '6.3V'        | '10%'    | 'IO'       | 'CHIP0805'                                                     | 'CHIP0805'     | ''          | ''   | ''        
 '10UF'     | '10V'   | '20%'     | '0805'      | 'X5R'     | 'TMP_QCH6102M9A01'(!) = 'End of Design' | 'Comp-Approve'     | ''       | 'CH6102M9A01'     |'C0805_H64'| '(SMC0805AW)'                                                        | '10UF'     | '10V'         | '20%'    | 'DISCRETE' | 'CAP CHIP 10U,10V(+-20%,X5R,0805)'                             | 'CHIP0805'     | ''          | ''   | ''        
 '10UF'     | '10V'   | '20%'     | '0805'      | 'EMPTY'   | 'TMP_QCH6102M9A01'(!) = 'End of Design' | 'Comp-Approve'     | ''       | 'CH6102M9A01'     |'C0805_H64'| '(SMC0805AW)'                                                        | 'NA'       | '10V'         | '20%'    | 'IO'       | 'CAP CHIP 10U,10V(+-20%,X5R,0805)'                             | 'CHIP0805'     | ''          | ''   | ''        
 '0.1UF'    | '10V'   | '10%'     | '0402'      | 'X5R'     | 'TMP_QCH41002KB93'(!) = 'End of Design' | 'Comp-Approve'     | ''       | 'CH41002KB93'     |'C0402'| '(C0402-0201)'                                                       | '0.1UF'    | '10V'         | '10%'    | 'DISCRETE' | 'CAP CHIP 0.1U 10V(+-10%,X5R,0402)'                            | 'CHIP0402'     | ''          | ''   | ''        
 '0.1UF'    | '10V'   | '10%'     | '0402'      | 'EMPTY'   | 'TMP_QCH41002KB93'(!) = 'End of Design' | 'Comp-Approve'     | ''       | 'CH41002KB93'     |'C0402'| '(C0402-0201)'                                                       | 'NA'       | '10V'         | '10%'    | 'IO'       | 'CAP CHIP 0.1U 10V(+-10%,X5R,0402)'                            | 'CHIP0402'     | ''          | ''   | ''        
 '4.7UF'    | '10V'   | '10%'     | '0805'      | 'X5R'     | 'TMP_QCH5472K9A02'(!) = 'End of Design' | 'Comp-Approve'     | ''       | 'CH5472K9A02'     |'C0805_H61'| '(SMC0805AW)'                                                        | '4.7UF'    | '10V'         | '10%'    | 'DISCRETE' | 'CAP CHIP 4.7U 10V(+-10%,X5R,0805)'                            | 'CHIP0805'     | ''          | ''   | ''        
 '4.7UF'    | '10V'   | '10%'     | '0805'      | 'EMPTY'   | 'TMP_QCH5472K9A02'(!) = 'End of Design' | 'Comp-Approve'     | ''       | 'CH5472K9A02'     |'C0805_H61'| '(SMC0805AW)'                                                        | 'NA'       | '10V'         | '10%'    | 'IO'       | 'CAP CHIP 4.7U 10V(+-10%,X5R,0805)'                            | 'CHIP0805'     | ''          | ''   | ''        
 '6800PF'   | '25V'   | '10%'     | '0402'      | 'X7R'     | 'TMP_QCH26804KB18'(!) = 'End of Design' | 'Comp-Approve'     | ''       | 'CH26804KB18'     |'C0402'| '(C0402-0201)'                                                       | '6800PF'   | '25V'         | '10%'    | 'DISCRETE' | 'CAP CHIP 6800P 25V(+-10% X7R 0402)'                           | 'CHIP0402'     | ''          | ''   | ''        
 '6800PF'   | '25V'   | '10%'     | '0402'      | 'EMPTY'   | 'TMP_QCH26804KB18'(!) = 'End of Design' | 'Comp-Approve'     | ''       | 'CH26804KB18'     |'C0402'| '(C0402-0201)'                                                       | 'NA'       | '25V'         | '10%'    | 'IO'       | 'CAP CHIP 6800P 25V(+-10% X7R 0402)'                           | 'CHIP0402'     | ''          | ''   | ''        
 '4.7UF'    | '4V'    | '20%'     | '0402'      | 'X5R'     | 'TMP_QCH547KM9B00'(!) = 'End of Design' | 'Comp-Approve'     | ''       | 'CH547KM9B00'     |'C0402'| '(C0402-0201)'                                                       | '4.7UF'    | '4V'          | '20%'    | 'DISCRETE' | 'CAP CHIP 4.7U 4V(+-20%,X5R,0402)HF'                           | 'CHIP0402'     | ''          | ''   | ''        
 '4.7UF'    | '4V'    | '20%'     | '0402'      | 'EMPTY'   | 'TMP_QCH547KM9B00'(!) = 'End of Design' | 'Comp-Approve'     | ''       | 'CH547KM9B00'     |'C0402'| '(C0402-0201)'                                                       | 'NA'       | '4V'          | '20%'    | 'IO'       | 'CAP CHIP 4.7U 4V(+-20%,X5R,0402)HF'                           | 'CHIP0402'     | ''          | ''   | ''        
 '2PF'      | '50V'   | '.25PF'   | '0402'      | 'COG'     | 'TMP_QCH-206C0B01'(!) = ''              | ''                 | ''       | 'CH-206C0B01'     |'C0402'| '(C0402-0201)'                                                       | '2PF'      | '50V'         | '.25PF'  | 'DISCRETE' | 'CAP CHIP 2P 50V(+-0.25PF,COG,0402)HI-Q'                       | 'CHIP0402'     | ''          | ''   | ''        
 '2PF'      | '50V'   | '.25PF'   | '0402'      | 'EMPTY'   | 'TMP_QCH-206C0B01'(!) = ''              | ''                 | ''       | 'CH-206C0B01'     |'C0402'| '(C0402-0201)'                                                       | 'NA'       | '50V'         | '.25PF'  | 'IO'       | 'CAP CHIP 2P 50V(+-0.25PF,COG,0402)HI-Q'                       | 'CHIP0402'     | ''          | ''   | ''        
 '5.0PF'    | '50V'   | '.25PF'   | '0402'      | 'COG'     | 'TMP_QCH-5006TB09'(!) = ''              | ''                 | ''       | 'CH-5006TB09'     |'C0402'| '(C0402-0201)'                                                       | '5.0PF'    | '50V'         | '.25PF'  | 'DISCRETE' | 'CAP CHIP 5.0P 50V(+-0.25P,COG,0402)EP'                        | 'CHIP0402'     | ''          | ''   | ''        
 '5.0PF'    | '50V'   | '.25PF'   | '0402'      | 'EMPTY'   | 'TMP_QCH-5006TB09'(!) = ''              | ''                 | ''       | 'CH-5006TB09'     |'C0402'| '(C0402-0201)'                                                       | 'NA'       | '50V'         | '.25PF'  | 'IO'       | 'CAP CHIP 5.0P 50V(+-0.25P,COG,0402)EP'                        | 'CHIP0402'     | ''          | ''   | ''        
 '0.022UF'  | '16V'   | '10%'     | '0402'      | 'X7R'     | 'TMP_QCH32203KB11'(!) = ''              | ''                 | ''       | 'CH32203KB11'     |'C0402'| '(C0402-0201,C0402_OCTAGONXA)'                                       | '0.022UF'  | '16V'         | '10%'    | 'DISCRETE' | 'CAP CHIP 0.022U 16V(+-10%,X7R,0402)'                          | 'CHIP0402'     | ''          | ''   | ''        
 '0.022UF'  | '16V'   | '10%'     | '0402'      | 'EMPTY'   | 'TMP_QCH32203KB11'(!) = ''              | ''                 | ''       | 'CH32203KB11'     |'C0402'| '(C0402-0201,C0402_OCTAGONXA)'                                       | 'NA'       | '16V'         | '10%'    | 'IO'       | 'CAP CHIP 0.022U 16V(+-10%,X7R,0402)'                          | 'CHIP0402'     | ''          | ''   | ''        
 '2.2UF'    | '10V'   | '20%'     | '0402'      | 'X5R'     | 'TMP_QCH5222M9B07'(!) = 'End of Design' | 'Comp-Approve'     | ''       | 'CH5222M9B07'     |'C0402'| '(C0402-0201)'                                                       | '2.2UF'    | '10V'         | '20%'    | 'DISCRETE' | 'CAP CHIP 2.2UF 10V(+-20%,X5R,0402)'                           | 'CHIP0402'     | ''          | ''   | ''        
 '2.2UF'    | '10V'   | '20%'     | '0402'      | 'EMPTY'   | 'TMP_QCH5222M9B07'(!) = 'End of Design' | 'Comp-Approve'     | ''       | 'CH5222M9B07'     |'C0402'| '(C0402-0201)'                                                       | 'NA'       | '10V'         | '20%'    | 'IO'       | 'CAP CHIP 2.2UF 10V(+-20%,X5R,0402)'                           | 'CHIP0402'     | ''          | ''   | ''        
 '10UF'     | '10V'   | '10%'     | '0805'      | 'X5R'     | 'TMP_QCH6102K9A01'(!) = 'End of Design' | 'Comp-Release Qty' | ''       | 'CH6102K9A01'     |'C0805_H61'| '(SMC0805AW)'                                                        | '10UF'     | '10V'         | '10%'    | 'DISCRETE' | 'CAP CHIP 10U 10V(+-10%,X5R,0805)'                             | 'CHIP0805'     | ''          | ''   | ''        
 '10UF'     | '10V'   | '10%'     | '0805'      | 'EMPTY'   | 'TMP_QCH6102K9A01'(!) = 'End of Design' | 'Comp-Release Qty' | ''       | 'CH6102K9A01'     |'C0805_H61'| '(SMC0805AW)'                                                        | 'NA'       | '10V'         | '10%'    | 'IO'       | 'CAP CHIP 10U 10V(+-10%,X5R,0805)'                             | 'CHIP0805'     | ''          | ''   | ''        
 '6.8PF'    | '50V'   | '0.5P'    | '0402'      | 'NPO'     | 'TMP_QCH-6806TB01'(!) = ''              | ''                 | ''       | 'CH-6806TB01'     |'C0402'| '(C0402-0201)'                                                       | '6.8PF'    | '50V'         | '0.5P'   | 'DISCRETE' | 'CAP CHIP 6.8P 50V(+-0.5P 0402 NPO)'                           | 'CHIP0402'     | ''          | ''   | ''        
 '6.8PF'    | '50V'   | '0.5P'    | '0402'      | 'EMPTY'   | 'TMP_QCH-6806TB01'(!) = ''              | ''                 | ''       | 'CH-6806TB01'     |'C0402'| '(C0402-0201)'                                                       | 'NA'       | '50V'         | '0.5P'   | 'IO'       | 'CAP CHIP 6.8P 50V(+-0.5P 0402 NPO)'                           | 'CHIP0402'     | ''          | ''   | ''        
 '4700PF'   | '50V'   | '10%'     | '0402'      | 'X7R'     | 'TMP_QCH2476K1B00'(!) = ''              | ''                 | ''       | 'CH2476K1B00'     |'C0402'| '(C0402-0201,C0402_OCTAGONXA)'                                       | '4700PF'   | '50V'         | '10%'    | 'DISCRETE' | 'CAP CHIP 4700PF 50V(10%,X7R,0402)'                            | 'CHIP0402'     | ''          | ''   | ''        
 '4700PF'   | '50V'   | '10%'     | '0402'      | 'EMPTY'   | 'TMP_QCH2476K1B00'(!) = ''              | ''                 | ''       | 'CH2476K1B00'     |'C0402'| '(C0402-0201,C0402_OCTAGONXA)'                                       | 'NA'       | '50V'         | '10%'    | 'IO'       | 'CAP CHIP 4700PF 50V(10%,X7R,0402)'                            | 'CHIP0402'     | ''          | ''   | ''        
 '1200PF'   | '50V'   | '10%'     | '0402'      | 'X7R'     | 'TMP_QCH21206KB13'(!) = 'End of Design' | 'End of Life'      | ''       | 'CH21206KB13'     |'C0402_EOL'| '(C0402-0201)'                                                       | '1200PF'   | '50V'         | '10%'    | 'DISCRETE' | 'CAP CHIP 1200P 50V(+-10%,X7R,0402)'                           | 'CHIP0402'     | ''          | ''   | ''        
 '1200PF'   | '50V'   | '10%'     | '0402'      | 'EMPTY'   | 'TMP_QCH21206KB13'(!) = 'End of Design' | 'End of Life'      | ''       | 'CH21206KB13'     |'C0402_EOL'| '(C0402-0201)'                                                       | 'NA'       | '50V'         | '10%'    | 'IO'       | 'CAP CHIP 1200P 50V(+-10%,X7R,0402)'                           | 'CHIP0402'     | ''          | ''   | ''        
 '2.2UF'    | '6.3V'  | '10%'     | '0603'      | 'X7R'     | 'TMP_QCH5221K1900'(!) = 'End of Design' | 'Comp-Approve'     | ''       | 'CH5221K1900'     |'C0603'| '(SMC0603AW)'                                                        | '2.2UF'    | '6.3V'        | '10%'    | 'DISCRETE' | 'CAP CHIP 2.2UF 6.3V(+-10%,X7R,0603)'                          | 'CHIP0603'     | ''          | ''   | ''        
 '2.2UF'    | '6.3V'  | '10%'     | '0603'      | 'EMPTY'   | 'TMP_QCH5221K1900'(!) = 'End of Design' | 'Comp-Approve'     | ''       | 'CH5221K1900'     |'C0603'| '(SMC0603AW)'                                                        | 'NA'       | '6.3V'        | '10%'    | 'IO'       | 'CAP CHIP 2.2UF 6.3V(+-10%,X7R,0603)'                          | 'CHIP0603'     | ''          | ''   | ''        
 '10UF'     | '25V'   | '10%'     | '1206'      | 'X7R'     | 'TMP_QCH6104K1206'(!) = 'End of Design' | 'Comp-Approve'     | ''       | 'CH6104K1206'     |'C1206_H76'| '(SMC1206AW)'                                                        | '10UF'     | '25V'         | '10%'    | 'DISCRETE' | 'CAP CHIP 10U,25V(+-10%,X7R,1206)H1.6'                         | 'CHIP1206'     | ''          | ''   | ''        
 '10UF'     | '25V'   | '10%'     | '1206'      | 'EMPTY'   | 'TMP_QCH6104K1206'(!) = 'End of Design' | 'Comp-Approve'     | ''       | 'CH6104K1206'     |'C1206_H76'| '(SMC1206AW)'                                                        | 'NA'       | '25V'         | '10%'    | 'IO'       | 'CAP CHIP 10U,25V(+-10%,X7R,1206)H1.6'                         | 'CHIP1206'     | ''          | ''   | ''        
 '2700PF'   | '50V'   | '10%'     | '0402'      | 'X7R'     | 'TMP_QCH22706KB14'(!) = ''              | ''                 | ''       | 'CH22706KB14'     |'C0402'| '(C0402-0201)'                                                       | '2700PF'   | '50V'         | '10%'    | 'DISCRETE' | 'CAP CHIP 2700P 50V(+-10%,X7R,0402)'                           | 'CHIP0402'     | ''          | ''   | ''        
 '2700PF'   | '50V'   | '10%'     | '0402'      | 'EMPTY'   | 'TMP_QCH22706KB14'(!) = ''              | ''                 | ''       | 'CH22706KB14'     |'C0402'| '(C0402-0201)'                                                       | 'NA'       | '50V'         | '10%'    | 'IO'       | 'CAP CHIP 2700P 50V(+-10%,X7R,0402)'                           | 'CHIP0402'     | ''          | ''   | ''        
 '4.7UF'    | '6.3V'  | '10%'     | '0603'      | 'X6S'     | 'TMP_QCH5471KE901'(!) = 'End of Design' | 'Comp-Approve'     | ''       | 'CH5471KE901'     |'C0603'| '(SMC0603AW)'                                                        | '4.7UF'    | '6.3V'        | '10%'    | 'DISCRETE' | 'CAP CHIP 4.7U 6.3V(+-10%,X6S,0603)'                           | 'CHIP0603'     | ''          | ''   | ''        
 '4.7UF'    | '6.3V'  | '10%'     | '0603'      | 'EMPTY'   | 'TMP_QCH5471KE901'(!) = 'End of Design' | 'Comp-Approve'     | ''       | 'CH5471KE901'     |'C0603'| '(SMC0603AW)'                                                        | 'NA'       | '6.3V'        | '10%'    | 'IO'       | 'CAP CHIP 4.7U 6.3V(+-10%,X6S,0603)'                           | 'CHIP0603'     | ''          | ''   | ''        
 '4.7UF'    | '6.3V'  | '10%'     | '0805'      | 'X7R'     | 'TMP_QCH5471K1A00'(!) = 'End of Design' | 'Comp-Approve'     | ''       | 'CH5471K1A00'     |'C0805_H61'| '(SMC0805AW)'                                                        | '4.7UF'    | '6.3V'        | '10%'    | 'DISCRETE' | 'CAP CHIP 4.7UF 6.3V(+-10%,X7R,0805)H1.25'                     | 'CHIP0805'     | ''          | ''   | ''        
 '4.7UF'    | '6.3V'  | '10%'     | '0805'      | 'EMPTY'   | 'TMP_QCH5471K1A00'(!) = 'End of Design' | 'Comp-Approve'     | ''       | 'CH5471K1A00'     |'C0805_H61'| '(SMC0805AW)'                                                        | 'NA'       | '6.3V'        | '10%'    | 'IO'       | 'CAP CHIP 4.7UF 6.3V(+-10%,X7R,0805)H1.25'                     | 'CHIP0805'     | ''          | ''   | ''        
 '10UF'     | '25V'   | '10%'     | '0805'      | 'X5R'     | 'TMP_QCH6104K9A00'(!) = 'End of Design' | 'Comp-Release Qty' | ''       | 'CH6104K9A00'     |'C0805_H61'| '(SMC0805AW)'                                                        | '10UF'     | '25V'         | '10%'    | 'DISCRETE' | 'CAP CHIP 10U 25V(+-10%,X5R,0805,H1.25)'                       | 'CHIP0805'     | ''          | ''   | ''        
 '10UF'     | '25V'   | '10%'     | '0805'      | 'EMPTY'   | 'TMP_QCH6104K9A00'(!) = 'End of Design' | 'Comp-Release Qty' | ''       | 'CH6104K9A00'     |'C0805_H61'| '(SMC0805AW)'                                                        | 'NA'       | '25V'         | '10%'    | 'IO'       | 'CAP CHIP 10U 25V(+-10%,X5R,0805,H1.25)'                       | 'CHIP0805'     | ''          | ''   | ''        
 '56PF'     | '50V'   | '5%'      | '0402'      | 'NPO'     | 'TMP_QCH05606JB01'(!) = ''              | ''                 | ''       | 'CH05606JB01'     |'C0402'| '(C0402-0201)'                                                       | '56PF'     | '50V'         | '5%'     | 'DISCRETE' | 'CAP CHIP 56P 50V(+-5%,NPO,0402)'                              | 'CHIP0402'     | ''          | ''   | ''        
 '56PF'     | '50V'   | '5%'      | '0402'      | 'EMPTY'   | 'TMP_QCH05606JB01'(!) = ''              | ''                 | ''       | 'CH05606JB01'     |'C0402'| '(C0402-0201)'                                                       | 'NA'       | '50V'         | '5%'     | 'IO'       | 'CAP CHIP 56P 50V(+-5%,NPO,0402)'                              | 'CHIP0402'     | ''          | ''   | ''        
 '220PF'    | '50V'   | '10%'     | '0402'      | 'X7R'     | 'TMP_QCH12206KB14'(!) = ''              | ''                 | ''       | 'CH12206KB14'     |'C0402'| '(C0402-0201)'                                                       | '220PF'    | '50V'         | '10%'    | 'DISCRETE' | 'CAP CHIP 220P 50V(+-10%,X7R,0402)'                            | 'CHIP0402'     | ''          | ''   | ''        
 '220PF'    | '50V'   | '10%'     | '0402'      | 'EMPTY'   | 'TMP_QCH12206KB14'(!) = ''              | ''                 | ''       | 'CH12206KB14'     |'C0402'| '(C0402-0201)'                                                       | 'NA'       | '50V'         | '10%'    | 'IO'       | 'CAP CHIP 220P 50V(+-10%,X7R,0402)'                            | 'CHIP0402'     | ''          | ''   | ''        
 '2200PF'   | '50V'   | '10%'     | '0402'      | 'X7R'     | 'TMP_QCH22206KB16'(!) = ''              | ''                 | ''       | 'CH22206KB16'     |'C0402'| '(C0402-0201)'                                                       | '2200PF'   | '50V'         | '10%'    | 'DISCRETE' | 'CAP CHIP 2200P 50V(+-10%,X7R,0402)'                           | 'CHIP0402'     | ''          | ''   | ''        
 '2200PF'   | '50V'   | '10%'     | '0402'      | 'EMPTY'   | 'TMP_QCH22206KB16'(!) = ''              | ''                 | ''       | 'CH22206KB16'     |'C0402'| '(C0402-0201)'                                                       | 'NA'       | '50V'         | '10%'    | 'IO'       | 'CAP CHIP 2200P 50V(+-10%,X7R,0402)'                           | 'CHIP0402'     | ''          | ''   | ''        
 '4700PF'   | '25V'   | '10%'     | '0402'      | 'X7R'     | 'TMP_QCH24704KB19'(!) = ''              | ''                 | ''       | 'CH24704KB19'     |'C0402'| '(C0402-0201)'                                                       | '4700PF'   | '25V'         | '10%'    | 'DISCRETE' | 'CAP CHIP 4700P 25V(+-10%,X7R,0402)'                           | 'CHIP0402'     | ''          | ''   | ''        
 '4700PF'   | '25V'   | '10%'     | '0402'      | 'EMPTY'   | 'TMP_QCH24704KB19'(!) = ''              | ''                 | ''       | 'CH24704KB19'     |'C0402'| '(C0402-0201)'                                                       | 'NA'       | '25V'         | '10%'    | 'IO'       | 'CAP CHIP 4700P 25V(+-10%,X7R,0402)'                           | 'CHIP0402'     | ''          | ''   | ''        
 '0.47UF'   | '6.3V'  | '10%'     | '0402'      | 'X5R'     | 'TMP_QCH4471K9B03'(!) = 'End of Design' | 'Comp-Release Qty' | ''       | 'CH4471K9B03'     |'C0402'| '(C0402-0201)'                                                       | '0.47UF'   | '6.3V'        | '10%'    | 'DISCRETE' | 'CAP CHIP 0.47U 6.3V(+-10%,X5R,0402)'                          | 'CHIP0402'     | ''          | ''   | ''        
 '0.47UF'   | '6.3V'  | '10%'     | '0402'      | 'EMPTY'   | 'TMP_QCH4471K9B03'(!) = 'End of Design' | 'Comp-Release Qty' | ''       | 'CH4471K9B03'     |'C0402'| '(C0402-0201)'                                                       | 'NA'       | '6.3V'        | '10%'    | 'IO'       | 'CAP CHIP 0.47U 6.3V(+-10%,X5R,0402)'                          | 'CHIP0402'     | ''          | ''   | ''        
 '0.47UF'   | '10V'   | '10%'     | '0402'      | 'X5R'     | 'TMP_QCH4472K9B00'(!) = ''              | ''                 | ''       | 'CH4472K9B00'     |'C0402'| '(C0402-0201)'                                                       | '0.47UF'   | '10V'         | '10%'    | 'DISCRETE' | 'CAP CHIP 0.47UF 10V(+-10%,X5R,0402)'                          | 'CHIP0402'     | ''          | ''   | ''        
 '0.47UF'   | '10V'   | '10%'     | '0402'      | 'EMPTY'   | 'TMP_QCH4472K9B00'(!) = ''              | ''                 | ''       | 'CH4472K9B00'     |'C0402'| '(C0402-0201)'                                                       | 'NA'       | '10V'         | '10%'    | 'IO'       | 'CAP CHIP 0.47UF 10V(+-10%,X5R,0402)'                          | 'CHIP0402'     | ''          | ''   | ''        
 '4.7UF'    | '6.3V'  | '20%'     | '0603'      | 'X5R'     | 'TMP_QCH5471M9907'(!) = 'End of Design' | 'Comp-Approve'     | ''       | 'CH5471M9907'     |'C0603'| '(SMC0603AW)'                                                        | '4.7UF'    | '6.3V'        | '20%'    | 'DISCRETE' | 'CAP CHIP 4.7U 6.3V(+-20%,X5R,0603)'                           | 'CHIP0603'     | ''          | ''   | ''        
 '4.7UF'    | '6.3V'  | '20%'     | '0603'      | 'EMPTY'   | 'TMP_QCH5471M9907'(!) = 'End of Design' | 'Comp-Approve'     | ''       | 'CH5471M9907'     |'C0603'| '(SMC0603AW)'                                                        | 'NA'       | '6.3V'        | '20%'    | 'IO'       | 'CAP CHIP 4.7U 6.3V(+-20%,X5R,0603)'                           | 'CHIP0603'     | ''          | ''   | ''        
 '10UF'     | '4V'    | '20%'     | '0603'      | 'X5R'     | 'TMP_QCH610KM9905'(!) = 'End of Design' | 'Comp-Approve'     | ''       | 'CH610KM9905'     |'C0603'| '(SMC0603AW)'                                                        | '10UF'     | '4V'          | '20%'    | 'DISCRETE' | 'CAP CHIP 10U,4V(+-20%,X5R,0603)'                              | 'CHIP0603'     | ''          | ''   | ''        
 '10UF'     | '4V'    | '20%'     | '0603'      | 'EMPTY'   | 'TMP_QCH610KM9905'(!) = 'End of Design' | 'Comp-Approve'     | ''       | 'CH610KM9905'     |'C0603'| '(SMC0603AW)'                                                        | 'NA'       | '4V'          | '20%'    | 'IO'       | 'CAP CHIP 10U,4V(+-20%,X5R,0603)'                              | 'CHIP0603'     | ''          | ''   | ''        
 '0.33UF'   | '16V'   | '10%'     | '0603'      | 'X7R'     | 'TMP_QCH4333K1905'(!) = 'End of Design' | 'Comp-Approve'     | ''       | 'CH4333K1905'     |'C0603'| '(SMC0603AW)'                                                        | '0.33UF'   | '16V'         | '10%'    | 'DISCRETE' | 'CAP CHIP 0.33UF 16V(+-10%,X7R,0603)'                          | 'CHIP0603'     | ''          | ''   | ''        
 '0.33UF'   | '16V'   | '10%'     | '0603'      | 'EMPTY'   | 'TMP_QCH4333K1905'(!) = 'End of Design' | 'Comp-Approve'     | ''       | 'CH4333K1905'     |'C0603'| '(SMC0603AW)'                                                        | 'NA'       | '16V'         | '10%'    | 'IO'       | 'CAP CHIP 0.33UF 16V(+-10%,X7R,0603)'                          | 'CHIP0603'     | ''          | ''   | ''        
 '0.1UF'    | '10V'   | '10%'     | '0402'      | 'X7R'     | 'TMP_QCH4102K1B03'(!) = 'End of Design' | 'Comp-Approve'     | ''       | 'CH4102K1B03'     |'C0402'| '(C0402-0201)'                                                       | '0.1UF'    | '10V'         | '10%'    | 'DISCRETE' | 'CAP CHIP 0.1U 10V(+-10%,X7R,0402)'                            | 'CHIP0402'     | ''          | ''   | ''        
 '0.1UF'    | '10V'   | '10%'     | '0402'      | 'EMPTY'   | 'TMP_QCH4102K1B03'(!) = 'End of Design' | 'Comp-Approve'     | ''       | 'CH4102K1B03'     |'C0402'| '(C0402-0201)'                                                       | 'NA'       | '10V'         | '10%'    | 'IO'       | 'CAP CHIP 0.1U 10V(+-10%,X7R,0402)'                            | 'CHIP0402'     | ''          | ''   | ''        
 '1UF'      | '6.3V'  | '20%'     | '0402'      | 'X5R'     | 'TMP_QCH5101M9B02'(!) = 'End of Design' | 'Comp-Approve'     | ''       | 'CH5101M9B02'     |'C0402'| '(C0402-0201)'                                                       | '1UF'      | '6.3V'        | '20%'    | 'DISCRETE' | 'CAP CHIP 1U 6.3V(+-20%,X5R,0402)'                             | 'CHIP0402'     | ''          | ''   | ''        
 '1UF'      | '6.3V'  | '20%'     | '0402'      | 'EMPTY'   | 'TMP_QCH5101M9B02'(!) = 'End of Design' | 'Comp-Approve'     | ''       | 'CH5101M9B02'     |'C0402'| '(C0402-0201)'                                                       | 'NA'       | '6.3V'        | '20%'    | 'IO'       | 'CAP CHIP 1U 6.3V(+-20%,X5R,0402)'                             | 'CHIP0402'     | ''          | ''   | ''        
 '0.1UF'    | '25V'   | '10%'     | '0402'      | 'X5R'     | 'TMP_QCH4104K9B03'(!) = 'End of Design' | 'Comp-Approve'     | ''       | 'CH4104K9B03'     |'C0402'| '(C0402-0201)'                                                       | '0.1UF'    | '25V'         | '10%'    | 'DISCRETE' | 'CAP CHIP 0.1U 25V(10%,X5R,0402)'                              | 'CHIP0402'     | ''          | ''   | ''        
 '0.1UF'    | '25V'   | '10%'     | '0402'      | 'EMPTY'   | 'TMP_QCH4104K9B03'(!) = 'End of Design' | 'Comp-Approve'     | ''       | 'CH4104K9B03'     |'C0402'| '(C0402-0201)'                                                       | 'NA'       | '25V'         | '10%'    | 'IO'       | 'CAP CHIP 0.1U 25V(10%,X5R,0402)'                              | 'CHIP0402'     | ''          | ''   | ''        
 '47UF'     | '4V'    | '20%'     | '0805'      | 'X5R'     | 'TMP_QCH647KM9A00'(!) = 'End of Design' | 'Comp-Approve'     | ''       | 'CH647KM9A00'     |'C0805_H61'| '(SMC0805AW)'                                                        | '47UF'     | '4V'          | '20%'    | 'DISCRETE' | 'CAP CHIP 47U 4V(+-20%,X5R,0805)H1.25'                         | 'CHIP0805'     | ''          | ''   | ''        
 '47UF'     | '4V'    | '20%'     | '0805'      | 'EMPTY'   | 'TMP_QCH647KM9A00'(!) = 'End of Design' | 'Comp-Approve'     | ''       | 'CH647KM9A00'     |'C0805_H61'| '(SMC0805AW)'                                                        | 'NA'       | '4V'          | '20%'    | 'IO'       | 'CAP CHIP 47U 4V(+-20%,X5R,0805)H1.25'                         | 'CHIP0805'     | ''          | ''   | ''        
 '47UF'     | '4V'    | '20%'     | '0805_FAC'  | 'X5R'     | 'CH647KM9A00'(!)   = 'End of Design' | 'Comp-Approve'     | ''       | 'CH647KM9A00'     |'C0805_H61'| '(SMC0805AW)'                                                        | '47UF'     | '4V'          | '20%'    | 'DISCRETE' | 'CAP CHIP 47U 4V(+-20%,X5R,0805)H1.25_FOR FAC ONLY'            | 'CHIP0805'     | ''          | ''   | '20100813'
 '47UF'     | '4V'    | '20%'     | '0805_FAC'  | 'EMPTY'   | 'CH647KM9A00'(!)   = 'End of Design' | 'Comp-Approve'     | ''       | 'CH647KM9A00'     |'C0805_H61'| '(SMC0805AW)'                                                        | 'NA'       | '4V'          | '20%'    | 'IO'       | 'CAP CHIP 47U 4V(+-20%,X5R,0805)H1.25_FOR FAC ONLY'            | 'CHIP0805'     | ''          | ''   | '20100813'
 '100UF'    | '6.3V'  | '20%'     | '1206'      | 'X5R'     | 'TMP_QCH7101M9200'(!) = 'End of Design' | 'Comp-Release Qty' | ''       | 'CH7101M9200'     |'C1206_H66'| '(SMC1206AW)'                                                        | '100UF'    | '6.3V'        | '20%'    | 'DISCRETE' | 'CAP CHIP 100U 6.3V(+-20%,X5R,1206)H1.6'                       | 'CHIP1206'     | ''          | ''   | ''        
 '100UF'    | '6.3V'  | '20%'     | '1206'      | 'EMPTY'   | 'TMP_QCH7101M9200'(!) = 'End of Design' | 'Comp-Release Qty' | ''       | 'CH7101M9200'     |'C1206_H66'| '(SMC1206AW)'                                                        | 'NA'       | '6.3V'        | '20%'    | 'IO'       | 'CAP CHIP 100U 6.3V(+-20%,X5R,1206)H1.6'                       | 'CHIP1206'     | ''          | ''   | ''        
 '47UF'     | '6.3V'  | '20%'     | '1206'      | 'X5R'     | 'TMP_QCH6471M9208'(!) = 'End of Design' | 'Comp-Approve'     | ''       | 'CH6471M9208'     |'C1206_H66'| '(SMC1206AW)'                                                        | '47UF'     | '6.3V'        | '20%'    | 'DISCRETE' | 'CAP CHIP 47U 6.3V(+-20%,X5R,1206)'                            | 'CHIP1206'     | ''          | ''   | ''        
 '47UF'     | '6.3V'  | '20%'     | '1206'      | 'EMPTY'   | 'TMP_QCH6471M9208'(!) = 'End of Design' | 'Comp-Approve'     | ''       | 'CH6471M9208'     |'C1206_H66'| '(SMC1206AW)'                                                        | 'NA'       | '6.3V'        | '20%'    | 'IO'       | 'CAP CHIP 47U 6.3V(+-20%,X5R,1206)'                            | 'CHIP1206'     | ''          | ''   | ''        
 '1UF'      | '10V'   | '10%'     | '0402'      | 'X7R'     | 'TMP_QCH5102K1B05'(!) = 'End of Design' | 'Comp-Approve'     | ''       | 'CH5102K1B05'     |'C0402'| '(C0402-0201)'                                                       | '1UF'      | '10V'         | '10%'    | 'DISCRETE' | 'CAP CHIP 1U,10V(+-10%,X7R,0402)'                              | 'CHIP0402'     | ''          | ''   | ''        
 '1UF'      | '10V'   | '10%'     | '0402'      | 'EMPTY'   | 'TMP_QCH5102K1B05'(!) = 'End of Design' | 'Comp-Approve'     | ''       | 'CH5102K1B05'     |'C0402'| '(C0402-0201)'                                                       | 'NA'       | '10V'         | '10%'    | 'IO'       | 'CAP CHIP 1U,10V(+-10%,X7R,0402)'                              | 'CHIP0402'     | ''          | ''   | ''        
 '0.047UF'  | '16V'   | '10%'     | '0603'      | 'X7R'     | 'TMP_QCH34703K916'(!) = ''              | ''                 | ''       | 'CH34703K916'     |'C0603'| '(SMC0603AW)'                                                        | '0.047UF'  | '16V'         | '10%'    | 'DISCRETE' | 'CAP CHIP 0.047UF 16V(+-10%,X7R,0603)'                         | 'CHIP0603'     | ''          | ''   | ''        
 '0.047UF'  | '16V'   | '10%'     | '0603'      | 'EMPTY'   | 'TMP_QCH34703K916'(!) = ''              | ''                 | ''       | 'CH34703K916'     |'C0603'| '(SMC0603AW)'                                                        | 'NA'       | '16V'         | '10%'    | 'IO'       | 'CAP CHIP 0.047UF 16V(+-10%,X7R,0603)'                         | 'CHIP0603'     | ''          | ''   | ''        
 '1UF'      | '10V'   | '20%'     | '0402'      | 'X5R'     | 'TMP_QCH5102M9B07'(!) = 'End of Design' | 'Comp-Approve'     | ''       | 'CH5102M9B07'     |'C0402'| '(C0402-0201)'                                                       | '1UF'      | '10V'         | '20%'    | 'DISCRETE' | 'CAP CHIP 1U 10V(+-20%,X5R,0402)H:0.5'                         | 'CHIP0402'     | ''          | ''   | ''        
 '1UF'      | '10V'   | '20%'     | '0402'      | 'EMPTY'   | 'TMP_QCH5102M9B07'(!) = 'End of Design' | 'Comp-Approve'     | ''       | 'CH5102M9B07'     |'C0402'| '(C0402-0201)'                                                       | 'NA'       | '10V'         | '20%'    | 'IO'       | 'CAP CHIP 1U 10V(+-20%,X5R,0402)H:0.5'                         | 'CHIP0402'     | ''          | ''   | ''        
 '22UF'     | '10V'   | '20%'     | '0805'      | 'X5R'     | 'TMP_QCH6222M9A01'(!) = ''              | 'End of Life'      | ''       | 'CH6222M9A01'     |'C0805_H61_EOL'| '(SMC0805AW)'                                                        | '22UF'     | '10V'         | '20%'    | 'DISCRETE' | 'CAP CHIP 22U 10V(+-20%,X5R,0805)'                             | 'CHIP0805'     | ''          | ''   | '20100527'
 '22UF'     | '10V'   | '20%'     | '0805'      | 'EMPTY'   | 'TMP_QCH6222M9A01'(!) = ''              | 'End of Life'      | ''       | 'CH6222M9A01'     |'C0805_H61_EOL'| '(SMC0805AW)'                                                        | 'NA'       | '10V'         | '20%'    | 'IO'       | 'CAP CHIP 22U 10V(+-20%,X5R,0805)'                             | 'CHIP0805'     | ''          | ''   | '20100527'
 '47UF'     | '6.3V'  | '20%'     | '0805'      | 'X5R'     | 'TMP_QCH6471M9A00'(!) = ''              | ''                 | ''       | 'CH6471M9A00'     |'C0805_H61'| '(SMC0805AW)'                                                        | '47UF'     | '6.3V'        | '20%'    | 'DISCRETE' | 'CAP CHIP 47U 6.3V(+-20%,X5R,0805)'                            | 'CHIP0805'     | ''          | ''   | '20100527'
 '47UF'     | '6.3V'  | '20%'     | '0805'      | 'EMPTY'   | 'TMP_QCH6471M9A00'(!) = ''              | ''                 | ''       | 'CH6471M9A00'     |'C0805_H61'| '(SMC0805AW)'                                                        | 'NA'       | '6.3V'        | '20%'    | 'IO'       | 'CAP CHIP 47U 6.3V(+-20%,X5R,0805)'                            | 'CHIP0805'     | ''          | ''   | '20100527'
 '1000PF'   | '50V'   | '10%'     | '0603'      | 'X7R'     | 'TMP_QCH21006K917'(!) = 'End of Design' | 'Comp-Approve'     | ''       | 'CH21006K917'     |'C0603'| '(SMC0603AW)'                                                        | '1000PF'   | '50V'         | '10%'    | 'DISCRETE' | 'CAP CHIP 1000P 50V(+-10%,X7R,0603)'                           | 'CHIP0603'     | ''          | ''   | '20100528'
 '1000PF'   | '50V'   | '10%'     | '0603'      | 'EMPTY'   | 'TMP_QCH21006K917'(!) = 'End of Design' | 'Comp-Approve'     | ''       | 'CH21006K917'     |'C0603'| '(SMC0603AW)'                                                        | 'NA'       | '50V'         | '10%'    | 'IO'       | 'CAP CHIP 1000P 50V(+-10%,X7R,0603)'                           | 'CHIP0603'     | ''          | ''   | '20100528'
 '0.047UF'  | '25V'   | '10%'     | '0603'      | 'X7R'     | 'TMP_QCH3474K1901'(!) = ''              | ''                 | 'SELASS' | 'CH3474K1901'     |'C0603'| '(SMC0603AW)'                                                        | '0.047UF'  | '25V'         | '10%'    | 'DISCRETE' | 'CAP CHIP 0.047UF 25V(10%,X7R,0603)SELASS'                     | 'CHIP0603'     | ''          | ''   | '20100528'
 '0.047UF'  | '25V'   | '10%'     | '0603'      | 'EMPTY'   | 'TMP_QCH3474K1901'(!) = ''              | ''                 | 'SELASS' | 'CH3474K1901'     |'C0603'| '(SMC0603AW)'                                                        | 'NA'       | '25V'         | '10%'    | 'IO'       | 'CAP CHIP 0.047UF 25V(10%,X7R,0603)SELASS'                     | 'CHIP0603'     | ''          | ''   | '20100528'
 '0.047UF'  | '16V'   | '10%'     | '0603'      | 'X7R'     | 'TMP_QCH3473K1919'(!) = 'End of Design' | 'Comp-Approve'     | ''       | 'CH3473K1919'     |'C0603'| '(SMC0603AW)'                                                        | '0.047UF'  | '16V'         | '10%'    | 'DISCRETE' | 'CAP CHIP 0.047U 16V(+-10%,X7R,0603)'                          | 'CHIP0603'     | ''          | ''   | '20100528'
 '0.047UF'  | '16V'   | '10%'     | '0603'      | 'EMPTY'   | 'TMP_QCH3473K1919'(!) = 'End of Design' | 'Comp-Approve'     | ''       | 'CH3473K1919'     |'C0603'| '(SMC0603AW)'                                                        | 'NA'       | '16V'         | '10%'    | 'IO'       | 'CAP CHIP 0.047U 16V(+-10%,X7R,0603)'                          | 'CHIP0603'     | ''          | ''   | '20100528'
 '0.1UF'    | '50V'   | '10%'     | '0603'      | 'X7R'     | 'TMP_QCH4106K1905'(!) = 'End of Design' | 'Comp-Approve'     | 'SELASS' | 'CH4106K1905'     |'C0603'| '(SMC0603AW)'                                                        | '0.1UF'    | '50V'         | '10%'    | 'DISCRETE' | 'CAP CHIP 0.1U 50V(+-10%,X7R,0603)SEL-ASS'                     | 'CHIP0603'     | ''          | ''   | '20100528'
 '0.1UF'    | '50V'   | '10%'     | '0603'      | 'EMPTY'   | 'TMP_QCH4106K1905'(!) = 'End of Design' | 'Comp-Approve'     | 'SELASS' | 'CH4106K1905'     |'C0603'| '(SMC0603AW)'                                                        | 'NA'       | '50V'         | '10%'    | 'IO'       | 'CAP CHIP 0.1U 50V(+-10%,X7R,0603)SEL-ASS'                     | 'CHIP0603'     | ''          | ''   | '20100528'
 '1UF'      | '25V'   | '10%'     | '0603'      | 'X7R'     | 'TMP_QCH5104K1901'(!) = 'End of Design' | 'Comp-Approve'     | 'SELASS' | 'CH5104K1901'     |'C0603'| '(SMC0603AW)'                                                        | '1UF'      | '25V'         | '10%'    | 'DISCRETE' | 'CAP CHIP 1U 25V(+-10%,X7R,0603)SELASS'                        | 'CHIP0603'     | ''          | ''   | '20100528'
 '1UF'      | '25V'   | '10%'     | '0603'      | 'EMPTY'   | 'TMP_QCH5104K1901'(!) = 'End of Design' | 'Comp-Approve'     | 'SELASS' | 'CH5104K1901'     |'C0603'| '(SMC0603AW)'                                                        | 'NA'       | '25V'         | '10%'    | 'IO'       | 'CAP CHIP 1U 25V(+-10%,X7R,0603)SELASS'                        | 'CHIP0603'     | ''          | ''   | '20100528'
 '2.2UF'    | '10V'   | '10%'     | '0603'      | 'X7R'     | 'TMP_QCH5222K1902'(!) = ''              | ''                 | 'SELASS' | 'CH5222K1902'     |'C0603'| '(SMC0603AW)'                                                        | '2.2UF'    | '10V'         | '10%'    | 'DISCRETE' | 'CAP CHIP 2.2UF 10V(+-10%,X7R,0603)SELASS'                     | 'CHIP0603'     | ''          | ''   | '20100528'
 '2.2UF'    | '10V'   | '10%'     | '0603'      | 'EMPTY'   | 'TMP_QCH5222K1902'(!) = ''              | ''                 | 'SELASS' | 'CH5222K1902'     |'C0603'| '(SMC0603AW)'                                                        | 'NA'       | '10V'         | '10%'    | 'IO'       | 'CAP CHIP 2.2UF 10V(+-10%,X7R,0603)SELASS'                     | 'CHIP0603'     | ''          | ''   | '20100528'
 '0.047UF'  | '25V'   | '10%'     | '0603'      | 'X7R'     | 'TMP_QCH3474K1905'(!) = 'End of Design' | 'Comp-Approve'     | ''       | 'CH3474K1905'     |'C0603'| '(SMC0603AW)'                                                        | '0.047UF'  | '25V'         | '10%'    | 'DISCRETE' | 'CAP CHIP 0.047UF 25V(+-10%,X7R,0603)'                         | 'CHIP0603'     | ''          | ''   | '20100528'
 '0.047UF'  | '25V'   | '10%'     | '0603'      | 'EMPTY'   | 'TMP_QCH3474K1905'(!) = 'End of Design' | 'Comp-Approve'     | ''       | 'CH3474K1905'     |'C0603'| '(SMC0603AW)'                                                        | 'NA'       | '25V'         | '10%'    | 'IO'       | 'CAP CHIP 0.047UF 25V(+-10%,X7R,0603)'                         | 'CHIP0603'     | ''          | ''   | '20100528'
 '1000PF'   | '50V'   | '5%'      | '0402'      | 'X7R'     | 'TMP_QCH21006JB10'(!) = ''              | ''                 | ''       | 'CH21006JB10'     |'C0402'| '(C0402-0201,C0402_OCTAGONXA)'                                       | '1000PF'   | '50V'         | '5%'     | 'DISCRETE' | 'CAP CHIP 1000P 50V(+-5%,X7R,0402)'                            | 'CHIP0402'     | ''          | ''   | '20100528'
 '1000PF'   | '50V'   | '5%'      | '0402'      | 'EMPTY'   | 'TMP_QCH21006JB10'(!) = ''              | ''                 | ''       | 'CH21006JB10'     |'C0402'| '(C0402-0201,C0402_OCTAGONXA)'                                       | 'NA'       | '50V'         | '5%'     | 'IO'       | 'CAP CHIP 1000P 50V(+-5%,X7R,0402)'                            | 'CHIP0402'     | ''          | ''   | '20100528'
 '0.01UF'   | '25V'   | '10%'     | '0402'      | 'X7R'     | 'TMP_QCH31004KB17'(!) = 'End of Design' | 'Comp-Release Qty' | ''       | 'CH31004KB17'     |'C0402'| '(C0402-0201,C0402_OCTAGONXA)'                                       | '0.01UF'   | '25V'         | '10%'    | 'DISCRETE' | 'CAP CHIP 0.01U 25V(+-10%,X7R,0402)'                           | 'CHIP0402'     | ''          | ''   | '20100528'
 '0.01UF'   | '25V'   | '10%'     | '0402'      | 'EMPTY'   | 'TMP_QCH31004KB17'(!) = 'End of Design' | 'Comp-Release Qty' | ''       | 'CH31004KB17'     |'C0402'| '(C0402-0201,C0402_OCTAGONXA)'                                       | 'NA'       | '25V'         | '10%'    | 'IO'       | 'CAP CHIP 0.01U 25V(+-10%,X7R,0402)'                           | 'CHIP0402'     | ''          | ''   | '20100528'
 '1UF'      | '10V'   | '10%'     | '0402'      | 'X5R'     | 'TMP_QCH5102K9B06'(!) = ''              | ''                 | ''       | 'CH5102K9B06'     |'C0402'| '(C0402-0201)'                                                       | '1UF'      | '10V'         | '10%'    | 'DISCRETE' | 'CAP CHIP 1UF 10V (+-10%,X5R,0402)'                            | 'CHIP0402'     | ''          | ''   | '20100528'
 '1UF'      | '10V'   | '10%'     | '0402'      | 'EMPTY'   | 'TMP_QCH5102K9B06'(!) = ''              | ''                 | ''       | 'CH5102K9B06'     |'C0402'| '(C0402-0201)'                                                       | 'NA'       | '10V'         | '10%'    | 'IO'       | 'CAP CHIP 1UF 10V (+-10%,X5R,0402)'                            | 'CHIP0402'     | ''          | ''   | '20100528'
 '10UF'     | '10V'   | '10%'     | '0805'      | 'X7R'     | 'TMP_QCH6102K1A01'(!) = ''              | ''                 | 'SELASS' | 'CH6102K1A01'     |'C0805_H61'| '(SMC0805AW)'                                                        | '10UF'     | '10V'         | '10%'    | 'DISCRETE' | 'CAP CHIP10UF 10V(+-10%,X7R,0805)SELASS'                       | 'CHIP0805'     | ''          | ''   | '20100528'
 '10UF'     | '10V'   | '10%'     | '0805'      | 'EMPTY'   | 'TMP_QCH6102K1A01'(!) = ''              | ''                 | 'SELASS' | 'CH6102K1A01'     |'C0805_H61'| '(SMC0805AW)'                                                        | 'NA'       | '10V'         | '10%'    | 'IO'       | 'CAP CHIP10UF 10V(+-10%,X7R,0805)SELASS'                       | 'CHIP0805'     | ''          | ''   | '20100528'
 '22UF'     | '6.3V'  | '20%'     | '0805'      | 'X5R'     | 'TMP_QCH6221M9A16'(!) = ''              | ''                 | 'SELASS' | 'CH6221M9A16'     |'C0805_H61'| '(SMC0805AW)'                                                        | '22UF'     | '6.3V'        | '20%'    | 'DISCRETE' | 'CAP CHIP 22U 6.3V(+-20%,X5R,0805)SELASS'                      | 'CHIP0805'     | ''          | ''   | '20100528'
 '22UF'     | '6.3V'  | '20%'     | '0805'      | 'EMPTY'   | 'TMP_QCH6221M9A16'(!) = ''              | ''                 | 'SELASS' | 'CH6221M9A16'     |'C0805_H61'| '(SMC0805AW)'                                                        | 'NA'       | '6.3V'        | '20%'    | 'IO'       | 'CAP CHIP 22U 6.3V(+-20%,X5R,0805)SELASS'                      | 'CHIP0805'     | ''          | ''   | '20100528'
 '10UF'     | '25V'   | '10%'     | '1206'      | 'X7R'     | 'TMP_QCH6104K1200'(!) = 'End of Design' | 'Comp-Release Qty' | 'SELASS' | 'CH6104K1200'     |'C1206_H76'| '(SMC1206AW)'                                                        | '10UF'     | '25V'         | '10%'    | 'DISCRETE' | 'CAP CHIP 10U 25V(+-10%,X7R,1206)SEL-ASS'                      | 'CHIP1206'     | ''          | ''   | '20100528'
 '10UF'     | '25V'   | '10%'     | '1206'      | 'EMPTY'   | 'TMP_QCH6104K1200'(!) = 'End of Design' | 'Comp-Release Qty' | 'SELASS' | 'CH6104K1200'     |'C1206_H76'| '(SMC1206AW)'                                                        | 'NA'       | '25V'         | '10%'    | 'IO'       | 'CAP CHIP 10U 25V(+-10%,X7R,1206)SEL-ASS'                      | 'CHIP1206'     | ''          | ''   | '20100528'
 '1000PF'   | '50V'   | '5%'      | '0603'      | 'NPO'     | 'TMP_QCH2106J0903'(!) = ''              | ''                 | 'SELASS' | 'CH2106J0903'     |'C0603'| '(SMC0603AW)'                                                        | '1000PF'   | '50V'         | '5%'     | 'DISCRETE' | 'CAP CHIP 1000P 50V(+-5%,NPO,0603)SELASS'                      | 'CHIP0603'     | ''          | ''   | '2010603' 
 '1000PF'   | '50V'   | '5%'      | '0603'      | 'EMPTY'   | 'TMP_QCH2106J0903'(!) = ''              | ''                 | 'SELASS' | 'CH2106J0903'     |'C0603'| '(SMC0603AW)'                                                        | 'NA'       | '50V'         | '5%'     | 'IO'       | 'CAP CHIP 1000P 50V(+-5%,NPO,0603)SELASS'                      | 'CHIP0603'     | ''          | ''   | '2010603' 
 '1800PF'   | '50V'   | '10%'     | '0603'      | 'X7R'     | 'TMP_QCH2186K1900'(!) = ''              | ''                 | 'SELASS' | 'CH2186K1900'     |'C0603'| '(SMC0603AW)'                                                        | '1800PF'   | '50V'         | '10%'    | 'DISCRETE' | 'CAP CHIP 1800P 50V(+-10%,X7R,0603)SELASS'                     | 'CHIP0603'     | ''          | ''   | '2010603' 
 '1800PF'   | '50V'   | '10%'     | '0603'      | 'EMPTY'   | 'TMP_QCH2186K1900'(!) = ''              | ''                 | 'SELASS' | 'CH2186K1900'     |'C0603'| '(SMC0603AW)'                                                        | 'NA'       | '50V'         | '10%'    | 'IO'       | 'CAP CHIP 1800P 50V(+-10%,X7R,0603)SELASS'                     | 'CHIP0603'     | ''          | ''   | '2010603' 
 '270PF'    | '50V'   | '5%'      | '0402'      | 'NPO'     | 'CH1276J0B02'(!)   = 'End of Design' | 'Comp-Approve'     | ''       | 'CH1276J0B02'     |'C0402'| '(C0402-0201)'                                                       | '270PF'    | '50V'         | '5%'     | 'DISCRETE' | 'CAP CHIP 270P 50V(+-5%,NPO,0402)'                             | 'CHIP0402'     | ''          | ''   | '20100609'
 '270PF'    | '50V'   | '5%'      | '0402'      | 'EMPTY'   | 'CH1276J0B02'(!)   = 'End of Design' | 'Comp-Approve'     | ''       | 'CH1276J0B02'     |'C0402'| '(C0402-0201)'                                                       | 'NA'       | '50V'         | '5%'     | 'IO'       | 'CAP CHIP 270P 50V(+-5%,NPO,0402)'                             | 'CHIP0402'     | ''          | ''   | '20100609'
 '1000PF'   | '50V'   | '5%'      | '0402'      | 'X7R'     | 'CH2106J1B03'(!)   = ''              | ''                 | 'SELASS' | 'CH2106J1B03'     |'C0402'| '(C0402-0201)'                                                       | '1000PF'   | '50V'         | '5%'     | 'DISCRETE' | 'CAP CHIP 1000P 50V(+-5%,X7R,0402)SELASS'                      | 'CHIP0402'     | ''          | ''   | '20100617'
 '1000PF'   | '50V'   | '5%'      | '0402'      | 'EMPTY'   | 'CH2106J1B03'(!)   = ''              | ''                 | 'SELASS' | 'CH2106J1B03'     |'C0402'| '(C0402-0201)'                                                       | 'NA'       | '50V'         | '5%'     | 'IO'       | 'CAP CHIP 1000P 50V(+-5%,X7R,0402)SELASS'                      | 'CHIP0402'     | ''          | ''   | '20100617'
 '100PF'    | '50V'   | '5%'      | '0402'      | 'NPO'     | 'CH11006JB00'(!)   = ''              | ''                 | ''       | 'CH11006JB00'     |'C0402'| '(C0402-0201)'                                                       | '100PF'    | '50V'         | '5%'     | 'DISCRETE' | 'CAP CHIP 100P 50V(+-5%,NPO,0402)'                             | 'CHIP0402'     | ''          | ''   | '20100618'
 '100PF'    | '50V'   | '5%'      | '0402'      | 'EMPTY'   | 'CH11006JB00'(!)   = ''              | ''                 | ''       | 'CH11006JB00'     |'C0402'| '(C0402-0201)'                                                       | 'NA'       | '50V'         | '5%'     | 'IO'       | 'CAP CHIP 100P 50V(+-5%,NPO,0402)'                             | 'CHIP0402'     | ''          | ''   | '20100618'
 '220PF'    | '50V'   | '10%'     | '0402'      | 'X7R'     | 'CH1226K1B06'(!)   = ''              | ''                 | 'SELASS' | 'CH1226K1B06'     |'C0402'| '(C0402-0201)'                                                       | '220PF'    | '50V'         | '10%'    | 'DISCRETE' | 'CAP CHIP 220PF 50V(+-10%,X7R,0402)SELASS'                     | 'CHIP0402'     | ''          | ''   | '20100618'
 '220PF'    | '50V'   | '10%'     | '0402'      | 'EMPTY'   | 'CH1226K1B06'(!)   = ''              | ''                 | 'SELASS' | 'CH1226K1B06'     |'C0402'| '(C0402-0201)'                                                       | 'NA'       | '50V'         | '10%'    | 'IO'       | 'CAP CHIP 220PF 50V(+-10%,X7R,0402)SELASS'                     | 'CHIP0402'     | ''          | ''   | '20100618'
 '1500PF'   | '50V'   | '10%'     | '0402'      | 'X7R'     | 'CH2156K1B03'(!)   = ''              | ''                 | 'SELASS' | 'CH2156K1B03'     |'C0402'| '(C0402-0201)'                                                       | '1500PF'   | '50V'         | '10%'    | 'DISCRETE' | 'CAP CHIP1500PF 50V(+-10%,X7R,0402)SELASS '                    | 'CHIP0402'     | ''          | ''   | '20100618'
 '1500PF'   | '50V'   | '10%'     | '0402'      | 'EMPTY'   | 'CH2156K1B03'(!)   = ''              | ''                 | 'SELASS' | 'CH2156K1B03'     |'C0402'| '(C0402-0201)'                                                       | 'NA'       | '50V'         | '10%'    | 'IO'       | 'CAP CHIP1500PF 50V(+-10%,X7R,0402)SELASS'                     | 'CHIP0402'     | ''          | ''   | '20100618'
 '10UF'     | '25V'   | '10%'     | '1206'      | 'X6S'     | 'CH6104KE203'(!)   = ''              | ''                 | 'SELASS' | 'CH6104KE203'     |'C1206_H76'| '(SMC1206AW)'                                                        | '10UF'     | '25V'         | '10%'    | 'DISCRETE' | 'CAP CHIP 10U 25V(+-10%,X6S,1206)SELASS'                       | 'CHIP1206'     | ''          | ''   | '20100618'
 '10UF'     | '25V'   | '10%'     | '1206'      | 'EMPTY'   | 'CH6104KE203'(!)   = ''              | ''                 | 'SELASS' | 'CH6104KE203'     |'C1206_H76'| '(SMC1206AW)'                                                        | 'NA'       | '25V'         | '10%'    | 'IO'       | 'CAP CHIP 10U 25V(+-10%,X6S,1206)SELASS'                       | 'CHIP1206'     | ''          | ''   | '20100618'
 '5600PF'   | '25V'   | '10%'     | '0402'      | 'X7R'     | 'CH25604KB18'(!)   = 'End of Design' | 'Comp-Approve'     | ''       | 'CH25604KB18'     |'C0402'| '(C0402-0201)'                                                       | '5600PF'   | '25V'         | '10%'    | 'DISCRETE' | 'CAP CHIP 5600P 25V(X7R,+-10%,0402)'                           | 'CHIP0402'     | ''          | ''   | '20100621'
 '5600PF'   | '25V'   | '10%'     | '0402'      | 'EMPTY'   | 'CH25604KB18'(!)   = 'End of Design' | 'Comp-Approve'     | ''       | 'CH25604KB18'     |'C0402'| '(C0402-0201)'                                                       | 'NA'       | '25V'         | '10%'    | 'IO'       | 'CAP CHIP 5600P 25V(X7R,+-10%,0402)'                           | 'CHIP0402'     | ''          | ''   | '20100621'
 '330PF'    | '50V'   | '10%'     | '0402'      | 'X7R'     | 'CH1336K1B02'(!)   = ''              | ''                 | ''       | 'CH1336K1B02'     |'C0402'| '(C0402-0201)'                                                       | '330PF'    | '50V'         | '10%'    | 'DISCRETE' | 'CAP CHIP 330P 50V(+-10%,X7R,0402)'                            | 'CHIP0402'     | ''          | ''   | '20100623'
 '330PF'    | '50V'   | '10%'     | '0402'      | 'EMPTY'   | 'CH1336K1B02'(!)   = ''              | ''                 | ''       | 'CH1336K1B02'     |'C0402'| '(C0402-0201)'                                                       | 'NA'       | '50V'         | '10%'    | 'IO'       | 'CAP CHIP 330P 50V(+-10%,X7R,0402)'                            | 'CHIP0402'     | ''          | ''   | '20100623'
 '0.068UF'  | '16V'   | '10%'     | '0402'      | 'X7R'     | 'CH3683K1B09'(!)   = ''              | ''                 | ''       | 'CH3683K1B09'     |'C0402'| '(C0402-0201)'                                                       | '0.068UF'  | '16V'         | '10%'    | 'DISCRETE' | 'CAP CHIP 0.068UF 16V(+-10%,X7R 0402)'                         | 'CHIP0402'     | ''          | ''   | '20100630'
 '0.068UF'  | '16V'   | '10%'     | '0402'      | 'EMPTY'   | 'CH3683K1B09'(!)   = ''              | ''                 | ''       | 'CH3683K1B09'     |'C0402'| '(C0402-0201)'                                                       | 'NA'       | '16V'         | '10%'    | 'IO'       | 'CAP CHIP 0.068UF 16V(+-10%,X7R 0402)'                         | 'CHIP0402'     | ''          | ''   | '20100630'
 '2200PF'   | '50V'   | '10%'     | '0603'      | 'X7R'     | 'CH22206K917'(!)   = 'End of Design' | 'Comp-Approve'     | ''       | 'CH22206K917'     |'C0603'| '(SMC0603AW)'                                                        | '2200PF'   | '50V'         | '10%'    | 'DISCRETE' | 'CAP CHIP 2200P 50V(+-10%,X7R,0603)'                           | 'CHIP0603'     | ''          | ''   | '2010702' 
 '2200PF'   | '50V'   | '10%'     | '0603'      | 'EMPTY'   | 'CH22206K917'(!)   = 'End of Design' | 'Comp-Approve'     | ''       | 'CH22206K917'     |'C0603'| '(SMC0603AW)'                                                        | 'NA'       | '50V'         | '10%'    | 'IO'       | 'CAP CHIP 2200P 50V(+-10%,X7R,0603)'                           | 'CHIP0603'     | ''          | ''   | '2010702' 
 '0.1UF'    | '16V'   | '20%'     | '0402'      | 'Y5V'     | 'CH41003ZB35'(!)   = 'End of Design' | 'Comp-Approve'     | ''       | 'CH41003ZB35'     |'C0402'| '(C0402-0201)'                                                       | '0.1UF'    | '16V'         | '20%'    | 'DISCRETE' | 'CAP CHIP 0.1U 16V(+80%-20%,Y5V,0402)'                         | 'CHIP0402'     | ''          | ''   | '2010709' 
 '0.1UF'    | '16V'   | '20%'     | '0402'      | 'EMPTY'   | 'CH41003ZB35'(!)   = 'End of Design' | 'Comp-Approve'     | ''       | 'CH41003ZB35'     |'C0402'| '(C0402-0201)'                                                       | 'NA'       | '16V'         | '20%'    | 'IO'       | 'CAP CHIP 0.1U 16V(+80%-20%,Y5V,0402)'                         | 'CHIP0402'     | ''          | ''   | '2010709' 
 '0.1UF'    | '50V'   | '10%'     | '0603'      | 'X7R'     | 'CH41006K911'(!)   = 'End of Design' | 'Comp-Approve'     | ''       | 'CH41006K911'     |'C0603'| '(SMC0603AW)'                                                        | '0.1UF'    | '50V'         | '10%'    | 'DISCRETE' | 'CAP CHIP 0.1U 50V(+-10%,X7R,0603)'                            | 'CHIP0603'     | ''          | ''   | '2010709' 
 '0.1UF'    | '50V'   | '10%'     | '0603'      | 'EMPTY'   | 'CH41006K911'(!)   = 'End of Design' | 'Comp-Approve'     | ''       | 'CH41006K911'     |'C0603'| '(SMC0603AW)'                                                        | 'NA'       | '50V'         | '10%'    | 'IO'       | 'CAP CHIP 0.1U 50V(+-10%,X7R,0603)'                            | 'CHIP0603'     | ''          | ''   | '2010709' 
 '0.1UF'    | '16V'   | '10%'     | '0402'      | 'X5R'     | 'CH4103K9B09'(!)   = 'End of Design' | 'Comp-Approve'     | ''       | 'CH4103K9B09'     |'C0402'| '(C0402-0201)'                                                       | '0.1UF'    | '16V'         | '10%'    | 'DISCRETE' | 'CAP CHIP 0.1U 16V(+-10%,X5R,0402) '                           | 'CHIP0402'     | ''          | ''   | '2010709' 
 '0.1UF'    | '16V'   | '10%'     | '0402'      | 'EMPTY'   | 'CH4103K9B09'(!)   = 'End of Design' | 'Comp-Approve'     | ''       | 'CH4103K9B09'     |'C0402'| '(C0402-0201)'                                                       | 'NA'       | '16V'         | '10%'    | 'IO'       | 'CAP CHIP 0.1U 16V(+-10%,X5R,0402) '                           | 'CHIP0402'     | ''          | ''   | '2010709' 
 '0.1UF'    | '25V'   | '20%'     | '0402'      | 'Y5V'     | 'CH4104Z3B07'(!)   = 'End of Design' | 'Comp-Approve'     | ''       | 'CH4104Z3B07'     |'C0402'| '(C0402-0201)'                                                       | '0.1UF'    | '25V'         | '20%'    | 'DISCRETE' | 'CAP CHIP 0.1U 25V(+80%-20%,Y5V,0402)'                         | 'CHIP0402'     | ''          | ''   | '2010709' 
 '0.1UF'    | '25V'   | '20%'     | '0402'      | 'EMPTY'   | 'CH4104Z3B07'(!)   = 'End of Design' | 'Comp-Approve'     | ''       | 'CH4104Z3B07'     |'C0402'| '(C0402-0201)'                                                       | 'NA'       | '25V'         | '20%'    | 'IO'       | 'CAP CHIP 0.1U 25V(+80%-20%,Y5V,0402)'                         | 'CHIP0402'     | ''          | ''   | '2010709' 
 '4.7UF'    | '25V'   | '10%'     | '0805'      | 'X6S'     | 'CH5474KEA06'(!)   = 'End of Design' | 'Comp-Approve'     | ''       | 'CH5474KEA06'     |'C0805_H61'| '(SMC0805AW)'                                                        | '4.7UF'    | '25V'         | '10%'    | 'DISCRETE' | 'CAP CHIP 4.7U 25V(+-10%,X6S,0805) EP'                         | 'CHIP0805'     | ''          | ''   | '2010709' 
 '4.7UF'    | '25V'   | '10%'     | '0805'      | 'EMPTY'   | 'CH5474KEA06'(!)   = 'End of Design' | 'Comp-Approve'     | ''       | 'CH5474KEA06'     |'C0805_H61'| '(SMC0805AW)'                                                        | 'NA'       | '25V'         | '10%'    | 'IO'       | 'CAP CHIP 4.7U 25V(+-10%,X6S,0805) EP'                         | 'CHIP0805'     | ''          | ''   | '2010709' 
 '22UF'     | '16V'   | '20%'     | '1206'      | 'X5R'     | 'CH6223M9200'(!)   = 'End of Design' | 'Comp-Approve'     | ''       | 'CH6223M9200'     |'C1206_H66'| '(SMC1206AW)'                                                        | '22UF'     | '16V'         | '20%'    | 'DISCRETE' | 'CAP CHIP 22UF 16V(+-20%,X5R,1206)'                            | 'CHIP1206'     | ''          | ''   | '2010709' 
 '22UF'     | '16V'   | '20%'     | '1206'      | 'EMPTY'   | 'CH6223M9200'(!)   = 'End of Design' | 'Comp-Approve'     | ''       | 'CH6223M9200'     |'C1206_H66'| '(SMC1206AW)'                                                        | 'NA'       | '16V'         | '20%'    | 'IO'       | 'CAP CHIP 22UF 16V(+-20%,X5R,1206)'                            | 'CHIP1206'     | ''          | ''   | '2010709' 
 '1UF'      | '10V'   | '20%'     | '0603'      | 'Y5V'     | 'CH5102Z3919'(!)   = 'End of Design' | 'Comp-Approve'     | ''       | 'CH5102Z3919'     |'C0603'| '(SMC0603AW)'                                                        | '1UF'      | '10V'         | '20%'    | 'DISCRETE' | 'CAP CHIP 1U 10V(+80%-20%,Y5V,0603)EP'                         | 'CHIP0603'     | ''          | ''   | '20107015'
 '1UF'      | '10V'   | '20%'     | '0603'      | 'EMPTY'   | 'CH5102Z3919'(!)   = 'End of Design' | 'Comp-Approve'     | ''       | 'CH5102Z3919'     |'C0603'| '(SMC0603AW)'                                                        | 'NA'       | '10V'         | '20%'    | 'IO'       | 'CAP CHIP 1U 10V(+80%-20%,Y5V,0603)EP'                         | 'CHIP0603'     | ''          | ''   | '20107015'
 '22PF '    | '50V'   | '5% '     | '0603'      | 'NPO'     | 'CH0226J0911'(!)   = ''              | 'End of Life'      | ''       | 'CH0226J0911'     |'C0603_EOL'| '(SMC0603AW)'                                                        | '22PF'     | '50V'         | '5% '    | 'DISCRETE' | 'CAP CHIP 22P 50V(+-5%,NPO,0603)    '                          | 'CHIP0603'     | ''          | ''   | '20107018'
 '22PF '    | '50V'   | '5% '     | '0603'      | 'EMPTY'   | 'CH0226J0911'(!)   = ''              | 'End of Life'      | ''       | 'CH0226J0911'     |'C0603_EOL'| '(SMC0603AW)'                                                        | 'NA'       | '50V'         | '5% '    | 'IO'       | 'CAP CHIP 22P 50V(+-5%,NPO,0603)    '                          | 'CHIP0603'     | ''          | ''   | '20107018'
 '0.1UF'    | '25V'   | '20%'     | '0603'      | 'Y5V'     | 'CH4104Z3916'(!)   = 'End of Design' | 'Comp-Approve'     | ''       | 'CH4104Z3916'     |'C0603'| '(SMC0603AW)'                                                        | '0.1UF'    | '25V'         | '20%'    | 'DISCRETE' | 'CAP CHIP 0.1U,25V(+80-20%,Y5V,0603)'                          | 'CHIP0603'     | ''          | ''   | '20107018'
 '0.1UF'    | '25V'   | '20%'     | '0603'      | 'EMPTY'   | 'CH4104Z3916'(!)   = 'End of Design' | 'Comp-Approve'     | ''       | 'CH4104Z3916'     |'C0603'| '(SMC0603AW)'                                                        | 'NA'       | '25V'         | '20%'    | 'IO'       | 'CAP CHIP 0.1U,25V(+80-20%,Y5V,0603)'                          | 'CHIP0603'     | ''          | ''   | '20107018'
 '10UF '    | '10V'   | '20%'     | '0603'      | 'X7R'     | 'CH6102M1909'(!)   = 'End of Design' | 'Comp-Approve'     | ''       | 'CH6102M1909'     |'C0603'| '(SMC0603AW)'                                                        | '10UF'     | '10V'         | '20%'    | 'DISCRETE' | 'CAP CHIP 10U,10V(+-20%,X7R,0603)   '                          | 'CHIP0603'     | ''          | ''   | '20107018'
 '10UF '    | '10V'   | '20%'     | '0603'      | 'EMPTY'   | 'CH6102M1909'(!)   = 'End of Design' | 'Comp-Approve'     | ''       | 'CH6102M1909'     |'C0603'| '(SMC0603AW)'                                                        | 'NA'       | '10V'         | '20%'    | 'IO'       | 'CAP CHIP 10U,10V(+-20%,X7R,0603)   '                          | 'CHIP0603'     | ''          | ''   | '20107018'
 '47UF '    | '10V'   | '20%'     | '1206'      | 'X5R'     | 'CH6472M9200'(!)   = 'End of Design' | 'Comp-Approve'     | ''       | 'CH6472M9200'     |'C1206_H76'| '(SMC1206AW)'                                                        | '47UF '    | '10V'         | '20%'    | 'DISCRETE' | 'CAP CHIP 47U 10V(+-20%,X5R,1206)  '                           | 'CHIP1206'     | ''          | ''   | '20107030'
 '47UF '    | '10V'   | '20%'     | '1206'      | 'EMPTY'   | 'CH6472M9200'(!)   = 'End of Design' | 'Comp-Approve'     | ''       | 'CH6472M9200'     |'C1206_H76'| '(SMC1206AW)'                                                        | 'NA'       | '10V'         | '20%'    | 'IO'       | 'CAP CHIP 47U 10V(+-20%,X5R,1206)  '                           | 'CHIP1206'     | ''          | ''   | '20107030'
 '27PF'     | '50V'   | '5%'      | '0402'      | 'NPO'     | 'CH02706JB06'(!)   = ''              | ''                 | ''       | 'CH02706JB06'     |'C0402'| '(C0402-0201)'                                                       | '27PF'     | '50V'         | '5%'     | 'DISCRETE' | 'CAP CHIP 27P 50V(+-5% NPO 0402)'                              | 'CHIP0402'     | ''          | ''   | '20100811'
 '27PF'     | '50V'   | '5%'      | '0402'      | 'EMPTY'   | 'CH02706JB06'(!)   = ''              | ''                 | ''       | 'CH02706JB06'     |'C0402'| '(C0402-0201)'                                                       | 'NA'       | '50V'         | '5%'     | 'IO'       | 'CAP CHIP 27P 50V(+-5% NPO 0402)'                              | 'CHIP0402'     | ''          | ''   | '20100811'
 '1NF'      | '50V'   | '10%'     | '0402'      | 'X7R'     | 'CH21006KB16'(!)   = ''              | ''                 | ''       | 'CH21006KB16'     |'C0402'| '(C0402-0201)'                                                       | '1NF'      | '50V'         | '10%'    | 'DISCRETE' | 'CAP CHIP 1N 50V(+-10%,X7R,0402)EP'                            | 'CHIP0402'     | ''          | ''   | '20100811'
 '1NF'      | '50V'   | '10%'     | '0402'      | 'EMPTY'   | 'CH21006KB16'(!)   = ''              | ''                 | ''       | 'CH21006KB16'     |'C0402'| '(C0402-0201)'                                                       | 'NA'       | '50V'         | '10%'    | 'IO'       | 'CAP CHIP 1N 50V(+-10%,X7R,0402)EP'                            | 'CHIP0402'     | ''          | ''   | '20100811'
 '0.1UF '   | '10V '  | '10%'     | '0402'      | 'X7R'     | 'CH4102K1B04'(!)   = ''              | ''                 | 'SELASS' | 'CH4102K1B04'     |'C0402'| '(C0402-0201)'                                                       | '0.1UF'    | '10V'         | '10%'    | 'DISCRETE' | 'CAP CHIP 0.1U 10V(+-10%,X7R,0402)SELASS  '                    | 'CHIP0402'     | ''          | ''   | '20100811'
 '0.1UF '   | '10V '  | '10%'     | '0402'      | 'EMPTY'   | 'CH4102K1B04'(!)   = ''              | ''                 | 'SELASS' | 'CH4102K1B04'     |'C0402'| '(C0402-0201)'                                                       | 'NA'       | '10V'         | '10%'    | 'IO'       | 'CAP CHIP 0.1U 10V(+-10%,X7R,0402)SELASS  '                    | 'CHIP0402'     | ''          | ''   | '20100811'
 '2.2UF '   | '6.3V'  | '20%'     | '0402'      | 'X5R'     | 'CH5221M9B02'(!)   = 'End of Design' | 'Comp-Release Qty' | ''       | 'CH5221M9B02'     |'C0402'| '(C0402-0201)'                                                       | '2.2UF'    | '6.3V'        | '20%'    | 'DISCRETE' | 'CAP CHIP 2.2U 6.3V(+-20%,X5R,0402)       '                    | 'CHIP0402'     | ''          | ''   | '20100811'
 '2.2UF '   | '6.3V'  | '20%'     | '0402'      | 'EMPTY'   | 'CH5221M9B02'(!)   = 'End of Design' | 'Comp-Release Qty' | ''       | 'CH5221M9B02'     |'C0402'| '(C0402-0201)'                                                       | 'NA'       | '6.3V'        | '20%'    | 'IO'       | 'CAP CHIP 2.2U 6.3V(+-20%,X5R,0402)       '                    | 'CHIP0402'     | ''          | ''   | '20100811'
 '2.2UF '   | '6.3V'  | '10%'     | '0603'      | 'X5R'     | 'CH5221K9911'(!)   = 'End of Design' | 'Comp-Approve'     | ''       | 'CH5221K9911'     |'C0603'| '(SMC0603AW)'                                                        | '2.2UF'    | '6.3V'        | '10%'    | 'DISCRETE' | 'CAP CHIP 2.2U 6.3V(10%,X5R,0603,H0.5)    '                    | 'CHIP0603'     | ''          | ''   | '20100811'
 '2.2UF '   | '6.3V'  | '10%'     | '0603'      | 'EMPTY'   | 'CH5221K9911'(!)   = 'End of Design' | 'Comp-Approve'     | ''       | 'CH5221K9911'     |'C0603'| '(SMC0603AW)'                                                        | 'NA'       | '6.3V'        | '10%'    | 'IO'       | 'CAP CHIP 2.2U 6.3V(10%,X5R,0603,H0.5)    '                    | 'CHIP0603'     | ''          | ''   | '20100811'
 '22UF  '   | '6.3V'  | '20%'     | '0805'      | 'X5R'     | 'CH6221M9A07'(!)   = 'End of Design' | 'Comp-Release Qty' | ''       | 'CH6221M9A07'     |'C0805_H61'| '(SMC0805AW)'                                                        | '22UF'     | '6.3V'        | '20%'    | 'DISCRETE' | 'CAP CHIP 22U 6.3V(+-20%,X5R,0805)        '                    | 'CHIP0805'     | ''          | ''   | '20100811'
 '22UF  '   | '6.3V'  | '20%'     | '0805'      | 'EMPTY'   | 'CH6221M9A07'(!)   = 'End of Design' | 'Comp-Release Qty' | ''       | 'CH6221M9A07'     |'C0805_H61'| '(SMC0805AW)'                                                        | 'NA'       | '6.3V'        | '20%'    | 'IO'       | 'CAP CHIP 22U 6.3V(+-20%,X5R,0805)        '                    | 'CHIP0805'     | ''          | ''   | '20100811'
 '1UF   '   | '25V '  | '10%'     | '0805'      | 'X5R'     | 'CH5104K9A08'(!)   = 'End of Design' | 'Comp-Approve'     | ''       | 'CH5104K9A08'     |'C0805_H43'| '(SMC0805AW)'                                                        | '1UF'      | '25V'         | '10%'    | 'DISCRETE' | 'CAP CHIP 1U 25V(+-10%,X5R,0805)H0.85     '                    | 'CHIP1206'     | ''          | ''   | '20107030'
 '1UF   '   | '25V '  | '10%'     | '0805'      | 'EMPTY'   | 'CH5104K9A08'(!)   = 'End of Design' | 'Comp-Approve'     | ''       | 'CH5104K9A08'     |'C0805_H43'| '(SMC0805AW)'                                                        | 'NA'       | '25V'         | '10%'    | 'IO'       | 'CAP CHIP 1U 25V(+-10%,X5R,0805)H0.85     '                    | 'CHIP1206'     | ''          | ''   | '20107030'
 '0.01UF '  | '25V'   | '10%'     | '0402'      | 'X7R'     | 'CH3104K1B08'(!)   = ''              | ''                 | 'SELASS' | 'CH3104K1B08'     |'C0402'| '(C0402-0201)'                                                       | '0.01UF'   | '25V'         | '10%'    | 'DISCRETE' | 'CAP CHIP 0.01U 25V(+-10%,X7R,0402)SELASS'                     | 'CHIP0402'     | ''          | ''   | '20100827'
 '0.01UF '  | '25V'   | '10%'     | '0402'      | 'EMPTY'   | 'CH3104K1B08'(!)   = ''              | ''                 | 'SELASS' | 'CH3104K1B08'     |'C0402'| '(C0402-0201)'                                                       | 'NA'       | '25V'         | '10%'    | 'IO'       | 'CAP CHIP 0.01U 25V(+-10%,X7R,0402)SELASS'                     | 'CHIP0402'     | ''          | ''   | '20100827'
 '20PF '    | '50V'   | '5% '     | '0603'      | 'NPO'     | 'CH02006J901'(!)   = ''              | ''                 | ''       | 'CH02006J901'     |'C0603'| '(SMC0603AW)'                                                        | '20PF'     | '50V'         | '5% '    | 'DISCRETE' | 'CAPACITOR CHIP 20P 50V(+-5%,NPO,0603)'                        | 'CHIP0603'     | ''          | ''   | '20100831'
 '20PF '    | '50V'   | '5% '     | '0603'      | 'EMPTY'   | 'CH02006J901'(!)   = ''              | ''                 | ''       | 'CH02006J901'     |'C0603'| '(SMC0603AW)'                                                        | 'NA'       | '50V'         | '5% '    | 'IO'       | 'CAPACITOR CHIP 20P 50V(+-5%,NPO,0603)'                        | 'CHIP0603'     | ''          | ''   | '20100831'
 '0.47UF'   | '10V'   | '10%'     | '0603'      | 'X7R'     | 'CH44702K912'(!)   = 'End of Design' | 'Comp-Approve'     | ''       | 'CH44702K912'     |'C0603'| '(SMC0603AW)'                                                        | '0.47UF'   | '10V'         | '10%'    | 'DISCRETE' | 'CAP CHIP 0.47U 10V(+-10%,X7R,0603)'                           | 'CHIP0603'     | ''          | ''   | ''        
 '0.47UF'   | '10V'   | '10%'     | '0603'      | 'EMPTY'   | 'CH44702K912'(!)   = 'End of Design' | 'Comp-Approve'     | ''       | 'CH44702K912'     |'C0603'| '(SMC0603AW)'                                                        | 'NA'       | '10V'         | '10%'    | 'IO'       | 'CAP CHIP 0.47U 10V(+-10%,X7R,0603)'                           | 'CHIP0603'     | ''          | ''   | ''        
 '1UF'      | '16V'   | '10%'     | '0603'      | 'X5R'     | 'CH5103K9901'(!)   = 'End of Design' | 'Comp-Approve'     | ''       | 'CH5103K9901'     |'C0603'| '(SMC0603AW)'                                                        | '1UF'      | '16V'         | '10%'    | 'DISCRETE' | 'CAP CHIP 1U 16V(+-10%,X5R,0603)'                              | 'CHIP0603'     | ''          | ''   | '20100914'
 '1UF'      | '16V'   | '10%'     | '0603'      | 'EMPTY'   | 'CH5103K9901'(!)   = 'End of Design' | 'Comp-Approve'     | ''       | 'CH5103K9901'     |'C0603'| '(SMC0603AW)'                                                        | 'NA'       | '16V'         | '10%'    | 'IO'       | 'CAP CHIP 1U 16V(+-10%,X5R,0603)'                              | 'CHIP0603'     | ''          | ''   | '20100914'
 '0.015UF'  | '50V'   | '10%'     | '0603'      | 'X7R'     | 'CH31506K917'(!)   = 'End of Design' | 'Comp-Approve'     | ''       | 'CH31506K917'     |'C0603'| '(SMC0603AW)'                                                        | '0.015UF'  | '50V'         | '10%'    | 'DISCRETE' | 'CAP CHIP 0.015U 50V(+-10%,X7R,0603)EP'                        | 'CHIP0603'     | ''          | ''   | '20100915'
 '0.015UF'  | '50V'   | '10%'     | '0603'      | 'EMPTY'   | 'CH31506K917'(!)   = 'End of Design' | 'Comp-Approve'     | ''       | 'CH31506K917'     |'C0603'| '(SMC0603AW)'                                                        | 'NA'       | '50V'         | '10%'    | 'IO'       | 'CAP CHIP 0.015U 50V(+-10%,X7R,0603)EP'                        | 'CHIP0603'     | ''          | ''   | '20100915'
 '0.22UF'   | '16V'   | '10%'     | '0402'      | 'X7R'     | 'CH4223K1B00'(!)   = 'End of Design' | 'Comp-Approve'     | ''       | 'CH4223K1B00'     |'C0402'| '(C0402_OCTAGONXA,C0402-0201)'                                       | '0.22UF'   | '16V'         | '10%'    | 'DISCRETE' | 'CAP CHIP 0.22U 16V(10%,X7R,0402)'                             | 'CHIP0402'     | ''          | ''   | '20100916'
 '0.22UF'   | '16V'   | '10%'     | '0402'      | 'EMPTY'   | 'CH4223K1B00'(!)   = 'End of Design' | 'Comp-Approve'     | ''       | 'CH4223K1B00'     |'C0402'| '(C0402_OCTAGONXA,C0402-0201)'                                       | 'NA'       | '16V'         | '10%'    | 'IO'       | 'CAP CHIP 0.22U 16V(10%,X7R,0402)'                             | 'CHIP0402'     | ''          | ''   | '20100916'
 '0.01UF'   | '16V'   | '10%'     | '0201'      | 'X7R'     | 'CH3103K1E00'(!)   = ''              | ''                 | ''       | 'CH3103K1E00'     |'C0201'| '(SMC0201AW)'                                                        | '0.01UF'   | '16V'         | '10%'    | 'DISCRETE' | 'CAP CHIP 0.01U 16V(+-10%,X7R,0201)'                           | 'CHIP0201'     | ''          | ''   | '20100923'
 '0.01UF'   | '16V'   | '10%'     | '0201'      | 'EMPTY'   | 'CH3103K1E00'(!)   = ''              | ''                 | ''       | 'CH3103K1E00'     |'C0201'| '(SMC0201AW)'                                                        | 'NA'       | '16V'         | '10%'    | 'IO'       | 'CAP CHIP 0.01U 16V(+-10%,X7R,0201)'                           | 'CHIP0201'     | ''          | ''   | '20100923'
 '18P'      | '50V'   | '5%'      | '0603'      | 'NPO'     | 'CH0186J0902'(!)   = 'End of Design' | 'Comp-Approve'     | ''       | 'CH0186J0902'     |'C0603'| '(SMC0603AW)'                                                        | '18PF'     | '50V'         | '5%'     | 'DISCRETE' | 'CAP CHIP 18P 50V(+-5%,NPO,0603)   '                           | 'CHIP0603'     | ''          | ''   | '20100923'
 '18P'      | '50V'   | '5%'      | '0603'      | 'EMPTY'   | 'CH0186J0902'(!)   = 'End of Design' | 'Comp-Approve'     | ''       | 'CH0186J0902'     |'C0603'| '(SMC0603AW)'                                                        | 'NA'       | '50V'         | '5%'     | 'IO'       | 'CAP CHIP 18P 50V(+-5%,NPO,0603)   '                           | 'CHIP0603'     | ''          | ''   | '20100923'
 '22PF'     | '50V'   | '5%'      | '0603'      | 'NPO'     | 'CH02206J909'(!)   = 'End of Design' | 'Comp-Approve'     | ''       | 'CH02206J909'     |'C0603'| '(SMC0603AW)'                                                        | '22PF'     | '50V'         | '5%'     | 'DISCRETE' | 'CAP CHIP 22P 50V(+-5%.NPO.0603)'                              | 'CHIP0603'     | ''          | ''   | '20100929'
 '22PF'     | '50V'   | '5%'      | '0603'      | 'EMPTY'   | 'CH02206J909'(!)   = 'End of Design' | 'Comp-Approve'     | ''       | 'CH02206J909'     |'C0603'| '(SMC0603AW)'                                                        | 'NA'       | '50V'         | '5%'     | 'IO'       | 'CAP CHIP 22P 50V(+-5%.NPO.0603)'                              | 'CHIP0603'     | ''          | ''   | '20100929'
 '100PF'    | '50V'   | '5%'      | '0402'      | 'X7R'     | 'CH11006JB18'(!)   = 'End of Design' | 'Comp-Approve'     | ''       | 'CH11006JB18'     |'C0402'| '(C0402-0201)'                                                       | '100PF'    | '50V'         | '5%'     | 'DISCRETE' | 'CAP CHIP 100P 50V(+-5%.X7R.0402)'                             | 'CHIP0402'     | ''          | ''   | '20100929'
 '100PF'    | '50V'   | '5%'      | '0402'      | 'EMPTY'   | 'CH11006JB18'(!)   = 'End of Design' | 'Comp-Approve'     | ''       | 'CH11006JB18'     |'C0402'| '(C0402-0201)'                                                       | 'NA'       | '50V'         | '5%'     | 'IO'       | 'CAP CHIP 100P 50V(+-5%.X7R.0402)'                             | 'CHIP0402'     | ''          | ''   | '20100929'
 '330PF'    | '50V'   | '5%'      | '0603'      | 'NPO'     | 'CH13306J907'(!)   = 'End of Design' | 'Comp-Approve'     | ''       | 'CH13306J907'     |'C0603'| '(SMC0603AW)'                                                        | '330PF'    | '50V'         | '5%'     | 'DISCRETE' | 'CAPACITOR CHIP 330P 50V(+-5%.NPO.0603)'                       | 'CHIP0603'     | ''          | ''   | '20100929'
 '330PF'    | '50V'   | '5%'      | '0603'      | 'EMPTY'   | 'CH13306J907'(!)   = 'End of Design' | 'Comp-Approve'     | ''       | 'CH13306J907'     |'C0603'| '(SMC0603AW)'                                                        | 'NA'       | '50V'         | '5%'     | 'IO'       | 'CAPACITOR CHIP 330P 50V(+-5%.NPO.0603)'                       | 'CHIP0603'     | ''          | ''   | '20100929'
 '3300PF'   | '50V'   | '10%'     | '0402'      | 'X7R'     | 'CH2336K1B01'(!)   = ''              | ''                 | 'SELASS' | 'CH2336K1B01'     |'C0402'| '(C0402-0201)'                                                       | '3300PF'   | '50V'         | '10%'    | 'DISCRETE' | 'CAP CHIP 3300P 50V(+-10%.X7R.0402)SELASS'                     | 'CHIP0402'     | ''          | ''   | '20100929'
 '3300PF'   | '50V'   | '10%'     | '0402'      | 'EMPTY'   | 'CH2336K1B01'(!)   = ''              | ''                 | 'SELASS' | 'CH2336K1B01'     |'C0402'| '(C0402-0201)'                                                       | 'NA'       | '50V'         | '10%'    | 'IO'       | 'CAP CHIP 3300P 50V(+-10%.X7R.0402)SELASS'                     | 'CHIP0402'     | ''          | ''   | '20100929'
 '1UF'      | '10V'   | '20%'     | '0603'      | 'Y5V'     | 'CH51002M930'(!)   = 'End of Design' | 'Comp-Approve'     | ''       | 'CH51002M930'     |'C0603'| '(SMC0603AW)'                                                        | '1UF'      | '10V'         | '20%'    | 'DISCRETE' | 'CAP CHIP 1U 10V(+-20%.Y5V.0603)'                              | 'CHIP0603'     | ''          | ''   | '20100929'
 '1UF'      | '10V'   | '20%'     | '0603'      | 'EMPTY'   | 'CH51002M930'(!)   = 'End of Design' | 'Comp-Approve'     | ''       | 'CH51002M930'     |'C0603'| '(SMC0603AW)'                                                        | 'NA'       | '10V'         | '20%'    | 'IO'       | 'CAP CHIP 1U 10V(+-20%.Y5V.0603)'                              | 'CHIP0603'     | ''          | ''   | '20100929'
 '3.3UF'    | '16V'   | '20%'     | '1206'      | 'Y5V'     | 'CH53303Z233'(!)   = 'End of Design' | 'Comp-Approve'     | ''       | 'CH53303Z233'     |'C1206_H56'| '(SMC1206AW)'                                                        | '3.3UF'    | '16V'         | '20%'    | 'DISCRETE' | 'CAP CHIP 3.3U.16V(+80%-20%.Y5V.1206)'                         | 'CHIP1206'     | ''          | ''   | '20100929'
 '3.3UF'    | '16V'   | '20%'     | '1206'      | 'EMPTY'   | 'CH53303Z233'(!)   = 'End of Design' | 'Comp-Approve'     | ''       | 'CH53303Z233'     |'C1206_H56'| '(SMC1206AW)'                                                        | 'NA'       | '16V'         | '20%'    | 'IO'       | 'CAP CHIP 3.3U.16V(+80%-20%.Y5V.1206)'                         | 'CHIP1206'     | ''          | ''   | '20100929'
 '10UF'     | '6.3V'  | '10%'     | '0805'      | 'X5R'     | 'CH61001KA94'(!)   = 'End of Design' | 'Comp-Approve'     | ''       | 'CH61001KA94'     |'C0805_H61'| '(SMC0805AW)'                                                        | '10UF'     | '6.3V'        | '10%'    | 'DISCRETE' | 'CAP CHIP 10UF.6.3V (+-10%.X5R.0805)'                          | 'CHIP0805'     | ''          | ''   | '20100929'
 '10UF'     | '6.3V'  | '10%'     | '0805'      | 'EMPTY'   | 'CH61001KA94'(!)   = 'End of Design' | 'Comp-Approve'     | ''       | 'CH61001KA94'     |'C0805_H61'| '(SMC0805AW)'                                                        | 'NA'       | '6.3V'        | '10%'    | 'IO'       | 'CAP CHIP 10UF.6.3V (+-10%.X5R.0805)'                          | 'CHIP0805'     | ''          | ''   | '20100929'
 '10PF'     | '50V'   | '5%'      | '0402'      | 'COG'     | 'CH01006JB08'(!)   = ''              | ''                 | ''       | 'CH01006JB08'     |'C0402'| '(C0402-0201)'                                                       | '10PF'     | '50V'         | '5%'     | 'DISCRETE' | 'CAP CHIP 10P 50V(+-5%,C0G,0402)'                              | 'CHIP0402'     | ''          | ''   | '20101013'
 '10PF'     | '50V'   | '5%'      | '0402'      | 'EMPTY'   | 'CH01006JB08'(!)   = ''              | ''                 | ''       | 'CH01006JB08'     |'C0402'| '(C0402-0201)'                                                       | 'NA'       | '50V'         | '5%'     | 'IO'       | 'CAP CHIP 10P 50V(+-5%,C0G,0402)'                              | 'CHIP0402'     | ''          | ''   | '20101013'
 '20PF'     | '50V'   | '5%'      | '0402'      | 'COG'     | 'CH0206J0B05'(!)   = ''              | ''                 | ''       | 'CH0206J0B05'     |'C0402'| '(C0402-0201)'                                                       | '20PF'     | '50V'         | '5%'     | 'DISCRETE' | 'CAP CHIP 20P 50V(+-5%,C0G,0402)'                              | 'CHIP0402'     | ''          | ''   | '20101026'
 '20PF'     | '50V'   | '5%'      | '0402'      | 'EMPTY'   | 'CH0206J0B05'(!)   = ''              | ''                 | ''       | 'CH0206J0B05'     |'C0402'| '(C0402-0201)'                                                       | 'NA'       | '50V'         | '5%'     | 'IO'       | 'CAP CHIP 20P 50V(+-5%,C0G,0402)'                              | 'CHIP0402'     | ''          | ''   | '20101026'
 '0.22UF'   | '6.3V'  | '10%'     | '0402'      | 'X5R'     | 'CH4221K9B00'(!)   = 'End of Design' | 'Comp-Approve'     | ''       | 'CH4221K9B00'     |'C0402'| '(C0402-0201)'                                                       | '0.22UF'   | '6.3V'        | '10%'    | 'DISCRETE' | 'CAP CHIP 0.22U 6.3V(+-10%,X5R,0402)'                          | 'CHIP0402'     | ''          | ''   | '20101026'
 '0.22UF'   | '6.3V'  | '10%'     | '0402'      | 'EMPTY'   | 'CH4221K9B00'(!)   = 'End of Design' | 'Comp-Approve'     | ''       | 'CH4221K9B00'     |'C0402'| '(C0402-0201)'                                                       | 'NA'       | '6.3V'        | '10%'    | 'IO'       | 'CAP CHIP 0.22U 6.3V(+-10%,X5R,0402)'                          | 'CHIP0402'     | ''          | ''   | '20101026'
 '1000PF'   | '2000V' | '10%'     | '1206'      | 'X7R'     | 'CH2100IK212'(!)   = ''              | ''                 | ''       | 'CH2100IK212'     |'C1206_H56'| '(SMC1206AW)'                                                        | '1000PF'   | '2KV'         | '10%'    | 'DISCRETE' | 'CAP CHIP 1000P 2KV(+-10%,X7R,1206)'                           | 'CHIP1206'     | ''          | ''   | '20101028'
 '1000PF'   | '2000V' | '10%'     | '1206'      | 'EMPTY'   | 'CH2100IK212'(!)   = ''              | ''                 | ''       | 'CH2100IK212'     |'C1206_H56'| '(SMC1206AW)'                                                        | 'NA'       | '2KV'         | '10%'    | 'IO'       | 'CAP CHIP 1000P 2KV(+-10%,X7R,1206)'                           | 'CHIP1206'     | ''          | ''   | '20101028'
 '18PF'     | '50V'   | '5%'      | '0402'      | 'C0G'     | 'CH01806JB07'(!)   = ''              | ''                 | ''       | 'CH01806JB07'     |'C0402'| '(C0402-0201)'                                                       | '18PF'     | '50V'         | '5%'     | 'DISCRETE' | 'CAP CHIP 18P 50V(+-5% C0G 0402)'                              | 'CHIP0402'     | ''          | ''   | '20110119'
 '18PF'     | '50V'   | '5%'      | '0402'      | 'EMPTY'   | 'CH01806JB07'(!)   = ''              | ''                 | ''       | 'CH01806JB07'     |'C0402'| '(C0402-0201)'                                                       | 'NA'       | '50V'         | '5%'     | 'IO'       | 'CAP CHIP 18P 50V(+-5% C0G 0402)'                              | 'CHIP0402'     | ''          | ''   | '20110119'
 '15PF'     | '50V'   | '5%'      | '0402'      | 'C0G'     | 'CH01506JB06'(!)   = ''              | ''                 | ''       | 'CH01506JB06'     |'C0402'| '(C0402-0201)'                                                       | '15PF'     | '50V'         | '5%'     | 'DISCRETE' | 'CAP CHIP 15P 50V(+-5% C0G 0402)'                              | 'CHIP0402'     | ''          | ''   | '20110207'
 '15PF'     | '50V'   | '5%'      | '0402'      | 'EMPTY'   | 'CH01506JB06'(!)   = ''              | ''                 | ''       | 'CH01506JB06'     |'C0402'| '(C0402-0201)'                                                       | 'NA'       | '50V'         | '5%'     | 'IO'       | 'CAP CHIP 15P 50V(+-5% C0G 0402)'                              | 'CHIP0402'     | ''          | ''   | '20110207'
 '1000PF'   | '3KV'   | '10%'     | '1808'      | 'X7R'     | 'CH2100GKI12'(!)   = ''              | ''                 | ''       | 'CH2100GKI12'     |'C1808_H86'| '(SMC1808AW)'                                                        | '1000PF'   | '3KV'         | '10%'    | 'DISCRETE' | 'CAP CHIP 1000P 3KV(+-10%.X7R.1808)'                           | 'CHIP1808'     | ''          | ''   | '20110207'
 '1000PF'   | '3KV'   | '10%'     | '1808'      | 'EMPTY'   | 'CH2100GKI12'(!)   = ''              | ''                 | ''       | 'CH2100GKI12'     |'C1808_H86'| '(SMC1808AW)'                                                        | 'NA'       | '3KV'         | '10%'    | 'IO'       | 'CAP CHIP 1000P 3KV(+-10%.X7R.1808)'                           | 'CHIP1808'     | ''          | ''   | '20110207'
 '3.3PF'    | '50V'   | '0.25P'   | '0402'      | 'C0G'     | 'CH-3306TB04'(!)   = ''              | ''                 | ''       | 'CH-3306TB04'     |'C0402'| '(C0402-0201)'                                                       | '3.3PF'    | '50V'         | '0.25P'  | 'DISCRETE' | 'CAP CHIP 3.3P 50V(+-0.25P C0G 0402)'                          | 'CHIP0402'     | ''          | ''   | '20110207'
 '3.3PF'    | '50V'   | '0.25P'   | '0402'      | 'EMPTY'   | 'CH-3306TB04'(!)   = ''              | ''                 | ''       | 'CH-3306TB04'     |'C0402'| '(C0402-0201)'                                                       | 'NA'       | '50V'         | '0.25P'  | 'IO'       | 'CAP CHIP 3.3P 50V(+-0.25P C0G 0402)'                          | 'CHIP0402'     | ''          | ''   | '20110207'
 '3PF'      | '50V'   | '0.25P'   | '0402'      | 'C0G'     | 'CH-3006TB03'(!)   = 'End of Design' | 'Comp-Approve'     | ''       | 'CH-3006TB03'     |'C0402'| '(C0402-0201)'                                                       | '3PF'      | '50V'         | '0.25P'  | 'DISCRETE' | 'CAP CHIP 3P 50V(+-0.25P,COG,0402)'                            | 'CHIP0402'     | ''          | ''   | '20110216'
 '3PF'      | '50V'   | '0.25P'   | '0402'      | 'EMPTY'   | 'CH-3006TB03'(!)   = 'End of Design' | 'Comp-Approve'     | ''       | 'CH-3006TB03'     |'C0402'| '(C0402-0201)'                                                       | 'NA'       | '50V'         | '0.25P'  | 'IO'       | 'CAP CHIP 3P 50V(+-0.25P,COG,0402)'                            | 'CHIP0402'     | ''          | ''   | '20110216'
 '10UF'     | '10V'   | '20%'     | '0603'      | 'X5R'     | 'CH6102M9900'(!)   = 'End of Design' | 'Comp-Approve'     | ''       | 'CH6102M9900'     |'C0603'| '(SMC0603AW)'                                                        | '10UF'     | '10V'         | '20%'    | 'DISCRETE' | 'CAP CHIP 10U 10V(+-20%.X5R.0603)'                             | 'CHIP0603'     | ''          | ''   | '20110223'
 '10UF'     | '10V'   | '20%'     | '0603'      | 'EMPTY'   | 'CH6102M9900'(!)   = 'End of Design' | 'Comp-Approve'     | ''       | 'CH6102M9900'     |'C0603'| '(SMC0603AW)'                                                        | 'NA'       | '10V'         | '20%'    | 'IO'       | 'CAP CHIP 10U 10V(+-20%.X5R.0603)'                             | 'CHIP0603'     | ''          | ''   | '20110223'
 '3.0PF'    | '50V'   | '0.25P'   | '0402'      | 'NPO'     | 'CH-306C0B07'(!)   = ''              | ''                 | ''       | 'CH-306C0B07'     |'C0402'| '(C0402-0201)'                                                       | '3.0PF'    | '50V'         | '0.25P'  | 'DISCRETE' | 'CAP CHIP 3P,50V(+-0.25P,NPO,0402)'                            | 'CHIP0402'     | ''          | ''   | '20110224'
 '3.0PF'    | '50V'   | '0.25P'   | '0402'      | 'EMPTY'   | 'CH-306C0B07'(!)   = ''              | ''                 | ''       | 'CH-306C0B07'     |'C0402'| '(C0402-0201)'                                                       | 'NA'       | '50V'         | '0.25P'  | 'IO'       | 'CAP CHIP 3P,50V(+-0.25P,NPO,0402)'                            | 'CHIP0402'     | ''          | ''   | '20110224'
 '6.8PF'    | '50V'   | '0.1P'    | '0402'      | 'NPO'     | 'CH-6816TB05'(!)   = 'End of Design' | 'Comp-Approve'     | ''       | 'CH-6816TB05'     |'C0402'| '(C0402-0201)'                                                       | '6.8PF'    | '50V'         | '0.1P'   | 'DISCRETE' | 'CAP CHIP 6.8P 50V (+-0.1P NPO 0402)'                          | 'CHIP0402'     | ''          | ''   | '20110224'
 '6.8PF'    | '50V'   | '0.1P'    | '0402'      | 'EMPTY'   | 'CH-6816TB05'(!)   = 'End of Design' | 'Comp-Approve'     | ''       | 'CH-6816TB05'     |'C0402'| '(C0402-0201)'                                                       | 'NA'       | '50V'         | '0.1P'   | 'IO'       | 'CAP CHIP 6.8P 50V (+-0.1P NPO 0402)'                          | 'CHIP0402'     | ''          | ''   | '20110224'
 '1UF'      | '25V'   | '10%'     | '0603'      | 'X7R'     | 'CH5104K1900'(!)   = 'End of Design' | 'Comp-Approve'     | ''       | 'CH5104K1900'     |'C0603'| '(SMC0603AW)'                                                        | '1UF'      | '25V'         | '10%'    | 'DISCRETE' | 'CAP CHIP 1U 25V(+-10%.X7R.0603)'                              | 'CHIP0603'     | ''          | ''   | '20110330'
 '1UF'      | '25V'   | '10%'     | '0603'      | 'EMPTY'   | 'CH5104K1900'(!)   = 'End of Design' | 'Comp-Approve'     | ''       | 'CH5104K1900'     |'C0603'| '(SMC0603AW)'                                                        | 'NA'       | '25V'         | '10%'    | 'IO'       | 'CAP CHIP 1U 25V(+-10%.X7R.0603)'                              | 'CHIP0603'     | ''          | ''   | '20110330'
 '0.022UF'  | '25V'   | '10%'     | '0402'      | 'X7R'     | 'CH3224K1B01'(!)   = ''              | ''                 | ''       | 'CH3224K1B01'     |'C0402'| '(C0402_OCTAGONXA,C0402-0201)'                                       | '0.022UF'  | '25V'         | '10%'    | 'DISCRETE' | 'CAP CHIP 0.022U 25V(+-10%,X7R,0402)'                          | 'CHIP0402'     | ''          | ''   | '20110413'
 '0.022UF'  | '25V'   | '10%'     | '0402'      | 'EMPTY'   | 'CH3224K1B01'(!)   = ''              | ''                 | ''       | 'CH3224K1B01'     |'C0402'| '(C0402_OCTAGONXA,C0402-0201)'                                       | 'NA'       | '25V'         | '10%'    | 'IO'       | 'CAP CHIP 0.022U 25V(+-10%,X7R,0402)'                          | 'CHIP0402'     | ''          | ''   | '20110413'
 '4.7UF'    | '4V'    | '10%'     | '0603'      | 'X6S'     | 'CH547KKE900'(!)   = 'End of Design' | 'Comp-Approve'     | ''       | 'CH547KKE900'     |'C0603'| '(SMC0603AW)'                                                        | '4.7UF'    | '4V'          | '10%'    | 'DISCRETE' | 'CAP CHIP 4.7U 4V(+-10%,X6S,0603)'                             | 'CHIP0603'     | ''          | ''   | '20110414'
 '4.7UF'    | '4V'    | '10%'     | '0603'      | 'EMPTY'   | 'CH547KKE900'(!)   = 'End of Design' | 'Comp-Approve'     | ''       | 'CH547KKE900'     |'C0603'| '(SMC0603AW)'                                                        | 'NA'       | '4V'          | '10%'    | 'IO'       | 'CAP CHIP 4.7U 4V(+-10%,X6S,0603)'                             | 'CHIP0603'     | ''          | ''   | '20110414'
 '10UF'     | '6.3V'  | '10%'     | '0805'      | 'X7R'     | 'CH6101K1A00'(!)   = 'End of Design' | 'Comp-Approve'     | ''       | 'CH6101K1A00'     |'C0805_H61'| '(SMC0805AW)'                                                        | '10UF'     | '6.3V'        | '10%'    | 'DISCRETE' | 'CAP CHIP 10UF 6.3V(+-10%,X7R,0805)H1.25'                      | 'CHIP0805'     | ''          | ''   | '20110415'
 '10UF'     | '6.3V'  | '10%'     | '0805'      | 'EMPTY'   | 'CH6101K1A00'(!)   = 'End of Design' | 'Comp-Approve'     | ''       | 'CH6101K1A00'     |'C0805_H61'| '(SMC0805AW)'                                                        | 'NA'       | '6.3V'        | '10%'    | 'IO'       | 'CAP CHIP 10UF 6.3V(+-10%,X7R,0805)H1.25'                      | 'CHIP0805'     | ''          | ''   | '20110415'
 '10UF'     | '6.3V'  | '20%'     | '0805'      | 'X6S'     | 'CH61001MEE3'(!)   = 'End of Design' | 'Comp-Approve'     | ''       | 'CH61001MEE3'     |'C0805_H61'| '(SMC0805AW)'                                                        | '10UF'     | '6.3V'        | '20%'    | 'DISCRETE' | 'CAP CHIP 10UF 6.3V(+-20%.X6S.0805)'                           | 'CHIP0805'     | ''          | ''   | '20110415'
 '10UF'     | '6.3V'  | '20%'     | '0805'      | 'EMPTY'   | 'CH61001MEE3'(!)   = 'End of Design' | 'Comp-Approve'     | ''       | 'CH61001MEE3'     |'C0805_H61'| '(SMC0805AW)'                                                        | 'NA'       | '6.3V'        | '20%'    | 'IO'       | 'CAP CHIP 10UF 6.3V(+-20%.X6S.0805)'                           | 'CHIP0805'     | ''          | ''   | '20110415'
 '10UF'     | '4V'    | '20%'     | '0805'      | 'X6S'     | 'CH6100KMEE3'(!)   = 'End of Design' | 'Comp-Approve'     | ''       | 'CH6100KMEE3'     |'C0805_H61'| '(SMC0805AW)'                                                        | '10UF'     | '4V'          | '20%'    | 'DISCRETE' | 'CAP CHIP 10U.4V(+-20%.X6S.0805) EP'                           | 'CHIP0805'     | ''          | ''   | '20110415'
 '10UF'     | '4V'    | '20%'     | '0805'      | 'EMPTY'   | 'CH6100KMEE3'(!)   = 'End of Design' | 'Comp-Approve'     | ''       | 'CH6100KMEE3'     |'C0805_H61'| '(SMC0805AW)'                                                        | 'NA'       | '4V'          | '20%'    | 'IO'       | 'CAP CHIP 10U.4V(+-20%.X6S.0805) EP'                           | 'CHIP0805'     | ''          | ''   | '20110415'
 '10UF'     | '4V'    | '20%'     | '0603'      | 'X6S'     | 'CH610KME901'(!)   = ''              | 'End of Life'      | ''       | 'CH610KME901'     |'C0603_EOL'| '(SMC0603AW)'                                                        | '10UF'     | '4V'          | '20%'    | 'DISCRETE' | 'CAP CHIP 10U 4V(+-20%,X6S,0603)'                              | 'CHIP0603'     | ''          | ''   | '20110415'
 '10UF'     | '4V'    | '20%'     | '0603'      | 'EMPTY'   | 'CH610KME901'(!)   = ''              | 'End of Life'      | ''       | 'CH610KME901'     |'C0603_EOL'| '(SMC0603AW)'                                                        | 'NA'       | '4V'          | '20%'    | 'IO'       | 'CAP CHIP 10U 4V(+-20%,X6S,0603)'                              | 'CHIP0603'     | ''          | ''   | '20110415'
 '4.7UF'    | '16V'   | '20%'     | '0805'      | 'X7R'     | 'CH5473M1A01'(!)   = 'End of Design' | 'Comp-Approve'     | ''       | 'CH5473M1A01'     |'C0805_H61'| '(SMC0805AW)'                                                        | '4.7UF'    | '16V'         | '20%'    | 'DISCRETE' | 'CAP CHIP 4.7U 16V(+-20%,X7R,0805)H1.25'                       | 'CHIP0805'     | ''          | ''   | '20110425'
 '4.7UF'    | '16V'   | '20%'     | '0805'      | 'EMPTY'   | 'CH5473M1A01'(!)   = 'End of Design' | 'Comp-Approve'     | ''       | 'CH5473M1A01'     |'C0805_H61'| '(SMC0805AW)'                                                        | 'NA'       | '16V'         | '20%'    | 'IO'       | 'CAP CHIP 4.7U 16V(+-20%,X7R,0805)H1.25'                       | 'CHIP0805'     | ''          | ''   | '20110425'
 '1500PF'   | '50V'   | '10%'     | '0603'      | 'X7R'     | 'CH21506K915'(!)   = 'End of Design' | 'Comp-Approve'     | ''       | 'CH21506K915'     |'C0603'| '(SMC0603AW)'                                                        | '1500PF'   | '50V'         | '10%'    | 'DISCRETE' | 'CAP CHIP 1500P 50V(+-10%.X7R.0603)'                           | 'CHIP0603'     | ''          | ''   | '20110624'
 '1500PF'   | '50V'   | '10%'     | '0603'      | 'EMPTY'   | 'CH21506K915'(!)   = 'End of Design' | 'Comp-Approve'     | ''       | 'CH21506K915'     |'C0603'| '(SMC0603AW)'                                                        | 'NA'       | '50V'         | '10%'    | 'IO'       | 'CAP CHIP 1500P 50V(+-10%.X7R.0603)'                           | 'CHIP0603'     | ''          | ''   | '20110624'
 '12PF'     | '50V'   | '2%'      | '0402'      | 'C0G'     | 'CH0126G0B00'(!)   = ''              | ''                 | ''       | 'CH0126G0B00'     |'C0402'| '(C0402-0201)'                                                       | '12PF'     | '50V'         | '2%'     | 'DISCRETE' | 'CAP CHIP 12P 50V(+-2%,C0G,0402)'                              | 'CHIP0402'     | ''          | ''   | '20110628'
 '12PF'     | '50V'   | '2%'      | '0402'      | 'EMPTY'   | 'CH0126G0B00'(!)   = ''              | ''                 | ''       | 'CH0126G0B00'     |'C0402'| '(C0402-0201)'                                                       | 'NA'       | '50V'         | '2%'     | 'IO'       | 'CAP CHIP 12P 50V(+-2%,C0G,0402)'                              | 'CHIP0402'     | ''          | ''   | '20110628'
 '39PF'     | '50V'   | '5%'      | '0402'      | 'NPO'     | 'CH03906JB06'(!)   = ''              | ''                 | ''       | 'CH03906JB06'     |'C0402'| '(C0402-0201)'                                                       | '39PF'     | '50V'         | '5%'     | 'DISCRETE' | 'CAP CHIP 39P 50V(+-5%.NPO.0402)'                              | 'CHIP0402'     | ''          | ''   | '20110628'
 '39PF'     | '50V'   | '5%'      | '0402'      | 'EMPTY'   | 'CH03906JB06'(!)   = ''              | ''                 | ''       | 'CH03906JB06'     |'C0402'| '(C0402-0201)'                                                       | 'NA'       | '50V'         | '5%'     | 'IO'       | 'CAP CHIP 39P 50V(+-5%.NPO.0402)'                              | 'CHIP0402'     | ''          | ''   | '20110628'
 '4.7UF'    | '10V'   | '10%'     | '0805'      | 'X7R'     | 'CH5472K1A00'(!)   = 'End of Design' | 'Comp-Approve'     | 'SELASS' | 'CH5472K1A00'     |'C0805_H61'| '(SMC0805AW)'                                                        | '4.7UF'    | '10V'         | '10%'    | 'DISCRETE' | 'CAP CHIP 4.7UF 10V(+-10%.X7R.0805)SELASS'                     | 'CHIP0805'     | ''          | ''   | '20100823'
 '4.7UF'    | '10V'   | '10%'     | '0805'      | 'EMPTY'   | 'CH5472K1A00'(!)   = 'End of Design' | 'Comp-Approve'     | 'SELASS' | 'CH5472K1A00'     |'C0805_H61'| '(SMC0805AW)'                                                        | 'NA'       | '10V'         | '10%'    | 'IO'       | 'CAP CHIP 4.7UF 10V(+-10%.X7R.0805)SELASS'                     | 'CHIP0805'     | ''          | ''   | '20100823'
 '3.3UF'    | '10V'   | '10%'     | '0603'      | 'X5R'     | 'CH5332K9900'(!)   = 'End of Design' | 'Comp-Approve'     | ''       | 'CH5332K9900'     |'C0603'| '(SMC0603AW)'                                                        | '3.3UF'    | '10V'         | '10%'    | 'DISCRETE' | 'CAP CHIP 3.3U 10V(+-10%,X5R,0603)'                            | 'CHIP0603'     | ''          | ''   | '20110720'
 '3.3UF'    | '10V'   | '10%'     | '0603'      | 'EMPTY'   | 'CH5332K9900'(!)   = 'End of Design' | 'Comp-Approve'     | ''       | 'CH5332K9900'     |'C0603'| '(SMC0603AW)'                                                        | 'NA'       | '10V'         | '10%'    | 'IO'       | 'CAP CHIP 3.3U 10V(+-10%,X5R,0603)'                            | 'CHIP0603'     | ''          | ''   | '20110720'
 '1800PF'   | '50V'   | '10%'     | '0402'      | 'X7R'     | 'CH21806KB15'(!)   = ''              | ''                 | ''       | 'CH21806KB15'     |'C0402'| '(C0402-0201)'                                                       | '1800PF'   | '50V'         | '10%'    | 'DISCRETE' | 'CAP CHIP 1800P 50V(+-10%.X7R.0402)'                           | 'CHIP0402'     | ''          | ''   | '20110826'
 '1800PF'   | '50V'   | '10%'     | '0402'      | 'EMPTY'   | 'CH21806KB15'(!)   = ''              | ''                 | ''       | 'CH21806KB15'     |'C0402'| '(C0402-0201)'                                                       | 'NA'       | '50V'         | '10%'    | 'IO'       | 'CAP CHIP 1800P 50V(+-10%.X7R.0402)'                           | 'CHIP0402'     | ''          | ''   | '20110826'
 '4700PF'   | '50V'   | '10%'     | '0603'      | 'X7R'     | 'CH2476K1929'(!)   = 'End of Design' | 'Comp-Approve'     | ''       | 'CH2476K1929'     |'C0603'| '(SMC0603AW)'                                                        | '4700PF'   | '50V'         | '10%'    | 'DISCRETE' | 'CAP CHIP 4700P,50V(+-10%,X7R,0603)'                           | 'CHIP0603'     | ''          | ''   | '20110920'
 '4700PF'   | '50V'   | '10%'     | '0603'      | 'EMPTY'   | 'CH2476K1929'(!)   = 'End of Design' | 'Comp-Approve'     | ''       | 'CH2476K1929'     |'C0603'| '(SMC0603AW)'                                                        | 'NA'       | '50V'         | '10%'    | 'IO'       | 'CAP CHIP 4700P,50V(+-10%,X7R,0603)'                           | 'CHIP0603'     | ''          | ''   | '20110920'
 '0.1UF'    | '10V'   | '10%'     | '0201'      | 'X5R'     | 'CH4102K9E00'(!)   = ''              | ''                 | ''       | 'CH4102K9E00'     |'C0201'| '(SMC0201AW)'                                                        | '0.1UF'    | '10V'         | '10%'    | 'DISCRETE' | 'CAP CHIP 0.1U 10V(+-10%.X5R.0201)'                            | 'CHIP0201'     | ''          | ''   | '20111207'
 '0.1UF'    | '10V'   | '10%'     | '0201'      | 'EMPTY'   | 'CH4102K9E00'(!)   = ''              | ''                 | ''       | 'CH4102K9E00'     |'C0201'| '(SMC0201AW)'                                                        | 'NA'       | '10V'         | '10%'    | 'IO'       | 'CAP CHIP 0.1U 10V(+-10%.X5R.0201)'                            | 'CHIP0201'     | ''          | ''   | '20111207'
 '27PF'     | '50V'   | '5%'      | '0603'      | 'NPO'     | 'CH0276J0905'(!)   = 'End of Design' | 'Comp-Approve'     | 'SELASS' | 'CH0276J0905'     |'C0603'| '(SMC0603AW)'                                                        | '27PF'     | '50V'         | '5%'     | 'DISCRETE' | 'CAP CHIP 27P 50V(+-5%.NPO.0603)SELASS'                        | 'CHIP0603'     | ''          | ''   | '20111208'
 '27PF'     | '50V'   | '5%'      | '0603'      | 'EMPTY'   | 'CH0276J0905'(!)   = 'End of Design' | 'Comp-Approve'     | 'SELASS' | 'CH0276J0905'     |'C0603'| '(SMC0603AW)'                                                        | 'NA'       | '50V'         | '5%'     | 'IO'       | 'CAP CHIP 27P 50V(+-5%.NPO.0603)SELASS'                        | 'CHIP0603'     | ''          | ''   | '20111208'
 '0.015UF'  | '16V'   | '10%'     | '0402'      | 'X7R'     | 'CH3153K1B12'(!)   = ''              | ''                 | ''       | 'CH3153K1B12'     |'C0402'| '(C0402-0201)'                                                       | '0.015UF'  | '16V'         | '10%'    | 'DISCRETE' | 'CAP CHIP 0.015U 16V(+-10%.X7R.0402)'                          | 'CHIP0402'     | ''          | ''   | '20111209'
 '0.015UF'  | '16V'   | '10%'     | '0402'      | 'EMPTY'   | 'CH3153K1B12'(!)   = ''              | ''                 | ''       | 'CH3153K1B12'     |'C0402'| '(C0402-0201)'                                                       | 'NA'       | '16V'         | '10%'    | 'IO'       | 'CAP CHIP 0.015U 16V(+-10%.X7R.0402)'                          | 'CHIP0402'     | ''          | ''   | '20111209'
 '0.047UF'  | '10V'   | '10%'     | '0402'      | 'X7R'     | 'CH34702KB10'(!)   = ''              | ''                 | ''       | 'CH34702KB10'     |'C0402'| '(C0402-0201)'                                                       | '0.047UF'  | '10V'         | '10%'    | 'DISCRETE' | 'CAP CHIP 0.047U 10V(+-10% X7R 0402)'                          | 'CHIP0402'     | ''          | ''   | '20111209'
 '0.047UF'  | '10V'   | '10%'     | '0402'      | 'EMPTY'   | 'CH34702KB10'(!)   = ''              | ''                 | ''       | 'CH34702KB10'     |'C0402'| '(C0402-0201)'                                                       | 'NA'       | '10V'         | '10%'    | 'IO'       | 'CAP CHIP 0.047U 10V(+-10% X7R 0402)'                          | 'CHIP0402'     | ''          | ''   | '20111209'
 '10PF'     | '50V'   | '0.5P'    | 'C0402'     | 'COH'     | 'CH01006JBD1'(!)   = 'End of Design' | 'Comp-Approve'     | ''       | 'CH01006JBD1'     |'C0402'| '(C0402-0201)'                                                       | '10PF'     | '50V'         | '0.5P'   | 'DISCRETE' | 'CAP CHIP 10P 50V(+-0.5P.COH.0402)'                            | 'CHIP0402'     | ''          | ''   | '20111213'
 '10PF'     | '50V'   | '0.5P'    | 'C0402'     | 'EMPTY'   | 'CH01006JBD1'(!)   = 'End of Design' | 'Comp-Approve'     | ''       | 'CH01006JBD1'     |'C0402'| '(C0402-0201)'                                                       | 'NA'       | '50V'         | '0.5P'   | 'IO'       | 'CAP CHIP 10P 50V(+-0.5P.COH.0402)'                            | 'CHIP0402'     | ''          | ''   | '20111213'
 '0.01UF'   | '50V'   | '5%'      | 'C0603'     | 'X7R'     | 'CH3106J1905'(!)   = 'End of Design' | 'Comp-Approve'     | ''       | 'CH3106J1905'     |'C0603'| '(SMC0603AW)'                                                        | '0.01UF'   | '50V'         | '5%'     | 'DISCRETE' | 'CAP CHIP 0.01U 50V(+-5%.X7R.0603)'                            | 'CHIP0603'     | ''          | ''   | '20111213'
 '0.01UF'   | '50V'   | '5%'      | 'C0603'     | 'EMPTY'   | 'CH3106J1905'(!)   = 'End of Design' | 'Comp-Approve'     | ''       | 'CH3106J1905'     |'C0603'| '(SMC0603AW)'                                                        | 'NA'       | '50V'         | '5%'     | 'IO'       | 'CAP CHIP 0.01U 50V(+-5%.X7R.0603)'                            | 'CHIP0603'     | ''          | ''   | '20111213'
 '0.1UF'    | '16V'   | '10%'     | 'C0603'     | 'X7R'     | 'CH41003K914'(!)   = 'End of Design' | 'Comp-Approve'     | ''       | 'CH41003K914'     |'C0603'| '(SMC0603AW)'                                                        | '0.1UF'    | '16V'         | '10%'    | 'DISCRETE' | 'CAP CHIP 0.1U 16V(+-10%. X7R.0603)'                           | 'CHIP0603'     | ''          | ''   | '20111213'
 '0.1UF'    | '16V'   | '10%'     | 'C0603'     | 'EMPTY'   | 'CH41003K914'(!)   = 'End of Design' | 'Comp-Approve'     | ''       | 'CH41003K914'     |'C0603'| '(SMC0603AW)'                                                        | 'NA'       | '16V'         | '10%'    | 'IO'       | 'CAP CHIP 0.1U 16V(+-10%. X7R.0603)'                           | 'CHIP0603'     | ''          | ''   | '20111213'
 '4.7UF'    | '6.3V'  | '10%'     | 'C0603'     | 'X5R'     | 'CH5471K9E07'(!)   = 'End of Design' | 'Comp-Release Qty' | ''       | 'CH5471K9E07'     |'C0603'| '(SMC0603AW)'                                                        | '4.7UF'    | '6.3V'        | '10%'    | 'DISCRETE' | 'CAP CHIP 4.7U 6.3V(+-10%.X5R.0603)'                           | 'CHIP0603'     | ''          | ''   | '20111213'
 '4.7UF'    | '6.3V'  | '10%'     | 'C0603'     | 'EMPTY'   | 'CH5471K9E07'(!)   = 'End of Design' | 'Comp-Release Qty' | ''       | 'CH5471K9E07'     |'C0603'| '(SMC0603AW)'                                                        | 'NA'       | '6.3V'        | '10%'    | 'IO'       | 'CAP CHIP 4.7U 6.3V(+-10%.X5R.0603)'                           | 'CHIP0603'     | ''          | ''   | '20111213'
 '8200PF'   | '25V'   | '10%'     | 'C0402'     | 'X7R'     | 'CH2824K1B05'(!)   = ''              | ''                 | ''       | 'CH2824K1B05'     |'C0402'| '(C0402-0201)'                                                       | '8200PF'   | '25V'         | '10%'    | 'DISCRETE' | 'CAP CHIP 8200P 25V (+-10%.X7R.0402)'                          | 'CHIP0402'     | ''          | ''   | '20111229'
 '8200PF'   | '25V'   | '10%'     | 'C0402'     | 'EMPTY'   | 'CH2824K1B05'(!)   = ''              | ''                 | ''       | 'CH2824K1B05'     |'C0402'| '(C0402-0201)'                                                       | 'NA'       | '25V'         | '10%'    | 'IO'       | 'CAP CHIP 8200P 25V (+-10%.X7R.0402)'                          | 'CHIP0402'     | ''          | ''   | '20111229'
 '100PF'    | '50V'   | '5%'      | 'C0402_SEL' | 'C0G'     | 'CH1106J0B09'(!)   = ''              | ''                 | 'SELASS' | 'CH1106J0B09'     |'C0402'| '(C0402-0201)'                                                       | '100PF'    | '50V'         | '5%'     | 'DISCRETE' | 'CAP CHIP 100P 50V(+-5%.C0G.0402)SEL ASN'                      | 'CHIP0402'     | ''          | ''   | '20111229'
 '100PF'    | '50V'   | '5%'      | 'C0402_SEL' | 'EMPTY'   | 'CH1106J0B09'(!)   = ''              | ''                 | 'SELASS' | 'CH1106J0B09'     |'C0402'| '(C0402-0201)'                                                       | 'NA'       | '50V'         | '5%'     | 'IO'       | 'CAP CHIP 100P 50V(+-5%.C0G.0402)SEL ASN'                      | 'CHIP0402'     | ''          | ''   | '20111229'
 '22UF'     | '6.3V'  | '10%'     | 'C0805_SEL' | 'X5R'     | 'CH6221M9A16'(!)   = ''              | ''                 | 'SELASS' | 'CH6221M9A16'     |'C0805_H61'| '(SMC0805AW)'                                                        | '22UF'     | '6.3V'        | '10%'    | 'DISCRETE' | 'CAP CHIP 22U 6.3V(+-20%.X5R.0805)SELASS'                      | 'CHIP0805'     | ''          | ''   | '20111229'
 '22UF'     | '6.3V'  | '10%'     | 'C0805_SEL' | 'EMPTY'   | 'CH6221M9A16'(!)   = ''              | ''                 | 'SELASS' | 'CH6221M9A16'     |'C0805_H61'| '(SMC0805AW)'                                                        | 'NA'       | '6.3V'        | '10%'    | 'IO'       | 'CAP CHIP 22U 6.3V(+-20%.X5R.0805)SELASS'                      | 'CHIP0805'     | ''          | ''   | '20111229'
 '0.033UF'  | '16V'   | '10%'     | 'C0402'     | 'X7R'     | 'CH3333K1B02'(!)   = 'End of Design' | 'Comp-Release Qty' | ''       | 'CH3333K1B02'     |'C0402'| '(C0402-0201)'                                                       | '0.033UF'  | '16V'         | '10%'    | 'DISCRETE' | 'CAP CHIP 0.033U 16V(+-10%.X7R.0402)'                          | 'CHIP0402'     | ''          | ''   | '20111230'
 '0.033UF'  | '16V'   | '10%'     | 'C0402'     | 'EMPTY'   | 'CH3333K1B02'(!)   = 'End of Design' | 'Comp-Release Qty' | ''       | 'CH3333K1B02'     |'C0402'| '(C0402-0201)'                                                       | 'NA'       | '16V'         | '10%'    | 'IO'       | 'CAP CHIP 0.033U 16V(+-10%.X7R.0402)'                          | 'CHIP0402'     | ''          | ''   | '20111230'
 '470PF'    | '50V'   | '5%'      | 'C0402'     | 'NPO'     | 'CH1476J0B08'(!)   = ''              | ''                 | ''       | 'CH1476J0B08'     |'C0402'| '(C0402-0201)'                                                       | '470PF'    | '50V'         | '5%'     | 'DISCRETE' | 'CAP CHIP 470P,50V(+-5%,NPO,0402)'                             | 'CHIP0402'     | ''          | ''   | '20120113'
 '470PF'    | '50V'   | '5%'      | 'C0402'     | 'EMPTY'   | 'CH1476J0B08'(!)   = ''              | ''                 | ''       | 'CH1476J0B08'     |'C0402'| '(C0402-0201)'                                                       | 'NA'       | '50V'         | '5%'     | 'IO'       | 'CAP CHIP 470P,50V(+-5%,NPO,0402)'                             | 'CHIP0402'     | ''          | ''   | '20120113'
 '6800PF'   | '50V'   | '10%'     | 'C0402'     | 'X7R'     | 'CH2686K1B01'(!)   = ''              | ''                 | ''       | 'CH2686K1B01'     |'C0402'| '(C0402-0201)'                                                       | '6800PF'   | '50V'         | '10%'    | 'DISCRETE' | 'CAP CHIP 6800P 50V(+-10%,X7R,0402)'                           | 'CHIP0402'     | ''          | ''   | '20120113'
 '6800PF'   | '50V'   | '10%'     | 'C0402'     | 'EMPTY'   | 'CH2686K1B01'(!)   = ''              | ''                 | ''       | 'CH2686K1B01'     |'C0402'| '(C0402-0201)'                                                       | 'NA'       | '50V'         | '10%'    | 'IO'       | 'CAP CHIP 6800P 50V(+-10%,X7R,0402)'                           | 'CHIP0402'     | ''          | ''   | '20120113'
 '0.047UF'  | '16V'   | '10%'     | 'C0402'     | 'X7R'     | 'CH3473K1B00'(!)   = ''              | ''                 | ''       | 'CH3473K1B00'     |'C0402'| '(C0402-0201)'                                                       | '0.047UF'  | '16V'         | '10%'    | 'DISCRETE' | 'CAP CHIP 0.047U 16V(+-10%,X7R,0402)'                          | 'CHIP0402'     | ''          | ''   | '20120113'
 '0.047UF'  | '16V'   | '10%'     | 'C0402'     | 'EMPTY'   | 'CH3473K1B00'(!)   = ''              | ''                 | ''       | 'CH3473K1B00'     |'C0402'| '(C0402-0201)'                                                       | 'NA'       | '16V'         | '10%'    | 'IO'       | 'CAP CHIP 0.047U 16V(+-10%,X7R,0402)'                          | 'CHIP0402'     | ''          | ''   | '20120113'
 '0.068UF'  | '25V'   | '10%'     | 'C0603'     | 'X7R'     | 'CH3684K1904'(!)   = 'End of Design' | 'Comp-Approve'     | ''       | 'CH3684K1904'     |'C0603'| '(SMC0603AW)'                                                        | '0.068UF'  | '25V'         | '10%'    | 'DISCRETE' | 'CAP CHIP 0.068UF 25V(10%,X7R,0603)'                           | 'CHIP0603'     | ''          | ''   | '20120113'
 '0.068UF'  | '25V'   | '10%'     | 'C0603'     | 'EMPTY'   | 'CH3684K1904'(!)   = 'End of Design' | 'Comp-Approve'     | ''       | 'CH3684K1904'     |'C0603'| '(SMC0603AW)'                                                        | 'NA'       | '25V'         | '10%'    | 'IO'       | 'CAP CHIP 0.068UF 25V(10%,X7R,0603)'                           | 'CHIP0603'     | ''          | ''   | '20120113'
 '0.1UF'    | '100V'  | '10%'     | 'C0805'     | 'X7R'     | 'CH4108K1A00'(!)   = 'End of Design' | 'Comp-Approve'     | ''       | 'CH4108K1A00'     |'C0805_H61'| '(SMC0805AW)'                                                        | '0.1UF'    | '100V'        | '10%'    | 'DISCRETE' | 'CAP CHIP 0.1UF 100V(+-10%,X7R,0805)H1.25'                     | 'CHIP0805'     | ''          | ''   | '20120114'
 '0.1UF'    | '100V'  | '10%'     | 'C0805'     | 'EMPTY'   | 'CH4108K1A00'(!)   = 'End of Design' | 'Comp-Approve'     | ''       | 'CH4108K1A00'     |'C0805_H61'| '(SMC0805AW)'                                                        | 'NA'       | '100V'        | '10%'    | 'IO'       | 'CAP CHIP 0.1UF 100V(+-10%,X7R,0805)H1.25'                     | 'CHIP0805'     | ''          | ''   | '20120114'
 '4.7UF'    | '16V'   | '10%'     | 'C0805'     | 'X7R'     | 'CH5473K1A00'(!)   = 'End of Design' | 'Comp-Approve'     | ''       | 'CH5473K1A00'     |'C0805_H61'| '(SMC0805AW)'                                                        | '4.7UF'    | '16V'         | '10%'    | 'DISCRETE' | 'CAP CHIP 4.7UF 16V(+-10%,X7R,0805,H1.25)'                     | 'CHIP0805'     | ''          | ''   | '20120114'
 '4.7UF'    | '16V'   | '10%'     | 'C0805'     | 'EMPTY'   | 'CH5473K1A00'(!)   = 'End of Design' | 'Comp-Approve'     | ''       | 'CH5473K1A00'     |'C0805_H61'| '(SMC0805AW)'                                                        | 'NA'       | '16V'         | '10%'    | 'IO'       | 'CAP CHIP 4.7UF 16V(+-10%,X7R,0805,H1.25)'                     | 'CHIP0805'     | ''          | ''   | '20120114'
 '0.22UF'   | '25V'   | '10%'     | 'C0603'     | 'X5R'     | 'CH4224K9904'(!)   = ''              | ''                 | ''       | 'CH4224K9904'     |'C0603'| '(SMC0603AW)'                                                        | '0.22UF'   | '25V'         | '10%'    | 'DISCRETE' | 'CAP CHIP 0.22U 25V(10%.X5R.0603)'                             | 'CHIP0603'     | ''          | ''   | '20120114'
 '0.22UF'   | '25V'   | '10%'     | 'C0603'     | 'EMPTY'   | 'CH4224K9904'(!)   = ''              | ''                 | ''       | 'CH4224K9904'     |'C0603'| '(SMC0603AW)'                                                        | 'NA'       | '25V'         | '10%'    | 'IO'       | 'CAP CHIP 0.22U 25V(10%.X5R.0603)'                             | 'CHIP0603'     | ''          | ''   | '20120114'
 '2200PF'   | '2KV'   | '10%'     | 'C1812'     | 'X7R'     | 'CH222IK1400'(!)   = ''              | ''                 | ''       | 'CH222IK1400'     |'C1812_H63'| '(SMC1812AW)'                                                        | '2200PF'   | '2KV'         | '10%'    | 'DISCRETE' | 'CAP CHIP 2200PF 2KV(+-10%.X7R.1812)H1.3'                      | 'CHIP1812'     | ''          | ''   | '20120116'
 '2200PF'   | '2KV'   | '10%'     | 'C1812'     | 'EMPTY'   | 'CH222IK1400'(!)   = ''              | ''                 | ''       | 'CH222IK1400'     |'C1812_H63'| '(SMC1812AW)'                                                        | 'NA'       | '2KV'         | '10%'    | 'IO'       | 'CAP CHIP 2200PF 2KV(+-10%.X7R.1812)H1.3'                      | 'CHIP1812'     | ''          | ''   | '20120116'
 '1UF'      | '100V'  | '10%'     | 'C1206'     | 'X7R'     | 'CH5108K1202'(!)   = 'End of Design' | 'Comp-Approve'     | ''       | 'CH5108K1202'     |'C1206_H66'| '(SMC1206AW)'                                                        | '1UF'      | '100V'        | '10%'    | 'DISCRETE' | 'CAP CHIP 1U 100V(10%.1206.X7R)'                               | 'CHIP1206'     | ''          | ''   | '20120116'
 '1UF'      | '100V'  | '10%'     | 'C1206'     | 'EMPTY'   | 'CH5108K1202'(!)   = 'End of Design' | 'Comp-Approve'     | ''       | 'CH5108K1202'     |'C1206_H66'| '(SMC1206AW)'                                                        | 'NA'       | '100V'        | '10%'    | 'IO'       | 'CAP CHIP 1U 100V(10%.1206.X7R)'                               | 'CHIP1206'     | ''          | ''   | '20120116'
 '0.15UF'   | '10V'   | '10%'     | 'C0603'     | 'X7R'     | 'CH41502K909'(!)   = ''              | ''                 | ''       | 'CH41502K909'     |'C0603'| '(SMC0603AW)'                                                        | '0.15UF'   | '10V'         | '10%'    | 'DISCRETE' | 'CAP CHIP 0.15U 10V(+-10%.X7R.0603)'                           | 'CHIP0603'     | ''          | ''   | '20120119'
 '0.15UF'   | '10V'   | '10%'     | 'C0603'     | 'EMPTY'   | 'CH41502K909'(!)   = ''              | ''                 | ''       | 'CH41502K909'     |'C0603'| '(SMC0603AW)'                                                        | 'NA'       | '10V'         | '10%'    | 'IO'       | 'CAP CHIP 0.15U 10V(+-10%.X7R.0603)'                           | 'CHIP0603'     | ''          | ''   | '20120119'
 '33PF'     | '16V'   | '5%'      | 'C0402'     | 'NP0'     | 'CH0333J0B00'(!)   = 'End of Design' | 'Comp-Approve'     | ''       | 'CH0333J0B00'     |'C0402'| '(C0402-0201)'                                                       | '33PF'     | '16V'         | '5%'     | 'DISCRETE' | 'CAP CHIP 33P 16V(+-5%,NP0,0402)'                              | 'CHIP0402'     | ''          | ''   | '20120120'
 '33PF'     | '16V'   | '5%'      | 'C0402'     | 'EMPTY'   | 'CH0333J0B00'(!)   = 'End of Design' | 'Comp-Approve'     | ''       | 'CH0333J0B00'     |'C0402'| '(C0402-0201)'                                                       | 'NA'       | '16V'         | '5%'     | 'IO'       | 'CAP CHIP 33P 16V(+-5%,NP0,0402)'                              | 'CHIP0402'     | ''          | ''   | '20120120'
 '1500PF'   | '100V'  | '10%'     | 'C0402'     | 'X7R'     | 'CH2158K1B00'(!)   = 'End of Design' | 'Comp-Approve'     | ''       | 'CH2158K1B00'     |'C0402'| '(C0402-0201)'                                                       | '1500PF'   | '100V'        | '10%'    | 'DISCRETE' | 'CAP CHIP 1500P 100V(+-10%.X7R.0402)'                          | 'CHIP0402'     | ''          | ''   | '20120120'
 '1500PF'   | '100V'  | '10%'     | 'C0402'     | 'EMPTY'   | 'CH2158K1B00'(!)   = 'End of Design' | 'Comp-Approve'     | ''       | 'CH2158K1B00'     |'C0402'| '(C0402-0201)'                                                       | 'NA'       | '100V'        | '10%'    | 'IO'       | 'CAP CHIP 1500P 100V(+-10%.X7R.0402)'                          | 'CHIP0402'     | ''          | ''   | '20120120'
 '390PF'    | '50V'   | '5%'      | 'C0402'     | 'C0G'     | 'CH1396J0B02'(!)   = ''              | ''                 | ''       | 'CH1396J0B02'     |'C0402'| '(C0402-0201)'                                                       | '390PF'    | '50V'         | '5%'     | 'DISCRETE' | 'CAP CHIP 390P 50V (+-5%,C0G,0402)'                            | 'CHIP0402'     | ''          | ''   | '20120120'
 '390PF'    | '50V'   | '5%'      | 'C0402'     | 'EMPTY'   | 'CH1396J0B02'(!)   = ''              | ''                 | ''       | 'CH1396J0B02'     |'C0402'| '(C0402-0201)'                                                       | 'NA'       | '50V'         | '5%'     | 'IO'       | 'CAP CHIP 390P 50V (+-5%,C0G,0402)'                            | 'CHIP0402'     | ''          | ''   | '20120120'
 '22UF'     | '4V'    | '20%'     | 'C0603'     | 'X5R'     | 'CH622KM9900'(!)   = 'End of Design' | 'Comp-Approve'     | ''       | 'CH622KM9900'     |'C0603'| '(SMC0603AW)'                                                        | '22UF'     | '4V'          | '20%'    | 'DISCRETE' | 'CAP CHIP 22UF 4V(+-20%,X5R,0603)H0.8'                         | 'CHIP0603'     | ''          | ''   | '20120202'
 '22UF'     | '4V'    | '20%'     | 'C0603'     | 'EMPTY'   | 'CH622KM9900'(!)   = 'End of Design' | 'Comp-Approve'     | ''       | 'CH622KM9900'     |'C0603'| '(SMC0603AW)'                                                        | 'NA'       | '4V'          | '20%'    | 'IO'       | 'CAP CHIP 22UF 4V(+-20%,X5R,0603)H0.8'                         | 'CHIP0603'     | ''          | ''   | '20120202'
 '82PF'     | '50V'   | '1%'      | 'C0402'     | 'C0G'     | 'CH0826F0B00'(!)   = ''              | ''                 | 'SELASS' | 'CH0826F0B00'     |'C0402'| '(C0402-0201)'                                                       | '82PF'     | '50V'         | '1%'     | 'DISCRETE' | 'CAP CHIP 82PF 50V(+-1%.C0G.0402)SELASS'                       | 'CHIP0402'     | ''          | ''   | '20120207'
 '82PF'     | '50V'   | '1%'      | 'C0402'     | 'EMPTY'   | 'CH0826F0B00'(!)   = ''              | ''                 | 'SELASS' | 'CH0826F0B00'     |'C0402'| '(C0402-0201)'                                                       | 'NA'       | '50V'         | '1%'     | 'IO'       | 'CAP CHIP 82PF 50V(+-1%.C0G.0402)SELASS'                       | 'CHIP0402'     | ''          | ''   | '20120207'
 '0.01UF'   | '50V'   | '10%'     | 'C0402'     | 'X7R'     | 'CH31006KB18'(!)   = ''              | ''                 | ''       | 'CH31006KB18'     |'C0402'| '(C0402_OCTAGONXA,C0402-0201)'                                       | '0.01UF'   | '50V'         | '10%'    | 'DISCRETE' | 'CAP CHIP 0.01U 50V(+-10%,X7R,0402)'                           | 'CHIP0402'     | ''          | ''   | '20120326'
 '0.01UF'   | '50V'   | '10%'     | 'C0402'     | 'EMPTY'   | 'CH31006KB18'(!)   = ''              | ''                 | ''       | 'CH31006KB18'     |'C0402'| '(C0402_OCTAGONXA,C0402-0201)'                                       | 'NA'       | '50V'         | '10%'    | 'IO'       | 'CAP CHIP 0.01U 50V(+-10%,X7R,0402)'                           | 'CHIP0402'     | ''          | ''   | '20120326'
 '120PF'    | '50V'   | '5%'      | 'C0402'     | 'NPO'     | 'CH11206JB07'(!)   = ''              | ''                 | ''       | 'CH11206JB07'     |'C0402'| '(C0402-0201)'                                                       | '120PF'    | '50V'         | '10%'    | 'DISCRETE' | 'CAP CHIP 120P 50V(+-5%,NPO,0402)'                             | 'CHIP0402'     | ''          | ''   | '20120326'
 '120PF'    | '50V'   | '5%'      | 'C0402'     | 'EMPTY'   | 'CH11206JB07'(!)   = ''              | ''                 | ''       | 'CH11206JB07'     |'C0402'| '(C0402-0201)'                                                       | 'NA'       | '50V'         | '10%'    | 'IO'       | 'CAP CHIP 120P 50V(+-5%,NPO,0402)'                             | 'CHIP0402'     | ''          | ''   | '20120326'
 '1000PF'   | '2KV'   | '10%'     | 'THLF'      | 'CERAMIC' | 'CG2100FKD00'(!)   = ''              | ''                 | ''       | 'CG2100FKD00'     |'EC315_P197_V'| '(EC315_P197_V)'                                                     | '1000PF'   | '2KV'         | '10%'    | 'DISCRETE' | 'CAP CERAMIC 1000P 2KV(+-10%,P5,DIP)'                          | 'DIP'          | ''          | ''   | '20120405'
 '1000PF'   | '2KV'   | '10%'     | 'THLF'      | 'EMPTY'   | 'CG2100FKD00'(!)   = ''              | ''                 | ''       | 'CG2100FKD00'     |'EC315_P197_V'| '(EC315_P197_V)'                                                     | 'NA'       | '2KV'         | '10%'    | 'IO'       | 'CAP CERAMIC 1000P 2KV(+-10%,P5,DIP)'                          | 'DIP'          | ''          | ''   | '20120405'
 '1000PF'   | '50V'   | '10%'     | 'C0603'     | 'NPO'     | 'CH21006K909'(!)   = 'End of Design' | 'Comp-Approve'     | ''       | 'CH21006K909'     |'C0603'| '(SMC0603AW)'                                                        | '1000PF'   | '50V'         | '10%'    | 'DISCRETE' | 'CAP CHIP 1000P 50V(+-10%,NPO,0603)'                           | 'CHIP0603'     | ''          | ''   | '20120406'
 '1000PF'   | '50V'   | '10%'     | 'C0603'     | 'EMPTY'   | 'CH21006K909'(!)   = 'End of Design' | 'Comp-Approve'     | ''       | 'CH21006K909'     |'C0603'| '(SMC0603AW)'                                                        | 'NA'       | '50V'         | '10%'    | 'IO'       | 'CAP CHIP 1000P 50V(+-10%,NPO,0603)'                           | 'CHIP0603'     | ''          | ''   | '20120406'
 '0.022UF'  | '50V'   | '10%'     | 'C0603'     | 'X7R'     | 'CH3226K1901'(!)   = 'End of Design' | 'Comp-Approve'     | ''       | 'CH3226K1901'     |'C0603'| '(SMC0603AW)'                                                        | '0.022UF'  | '50V'         | '10%'    | 'DISCRETE' | 'CAP CHIP 0.022U 50V(+-10%.X7R.0603)L-F'                       | 'CHIP0603'     | ''          | ''   | '20120416'
 '0.022UF'  | '50V'   | '10%'     | 'C0603'     | 'EMPTY'   | 'CH3226K1901'(!)   = 'End of Design' | 'Comp-Approve'     | ''       | 'CH3226K1901'     |'C0603'| '(SMC0603AW)'                                                        | 'NA'       | '50V'         | '10%'    | 'IO'       | 'CAP CHIP 0.022U 50V(+-10%.X7R.0603)L-F'                       | 'CHIP0603'     | ''          | ''   | '20120416'
 '10UF'     | '25V'   | '10%'     | 'C1206'     | 'X6S'     | 'CH6104KE201'(!)   = 'End of Design' | 'Comp-Approve'     | ''       | 'CH6104KE201'     |'C1206_H76'| '(SMC1206AW)'                                                        | '10UF'     | '25V'         | '10%'    | 'DISCRETE' | 'CAP CHIP 10U 25V(+-10%.X6S.1206)'                             | 'CHIP1206'     | ''          | ''   | '20120419'
 '10UF'     | '25V'   | '10%'     | 'C1206'     | 'EMPTY'   | 'CH6104KE201'(!)   = 'End of Design' | 'Comp-Approve'     | ''       | 'CH6104KE201'     |'C1206_H76'| '(SMC1206AW)'                                                        | 'NA'       | '25V'         | '10%'    | 'IO'       | 'CAP CHIP 10U 25V(+-10%.X6S.1206)'                             | 'CHIP1206'     | ''          | ''   | '20120419'
 '22UF'     | '2.5V'  | '20%'     | 'C0805'     | 'X6S'     | 'CH622LMEA00'(!)   = 'End of Design' | 'Comp-Approve'     | ''       | 'CH622LMEA00'     |'C0805_H36'| '(SMC0805AW)'                                                        | '22UF'     | '2.5V'        | '20%'    | 'DISCRETE' | 'CAP CHIP 22UF 2.5V(20%,X6S,0805,H0.85)'                       | 'CHIP0805'     | ''          | ''   | '20120420'
 '22UF'     | '2.5V'  | '20%'     | 'C0805'     | 'EMPTY'   | 'CH622LMEA00'(!)   = 'End of Design' | 'Comp-Approve'     | ''       | 'CH622LMEA00'     |'C0805_H36'| '(SMC0805AW)'                                                        | 'NA'       | '2.5V'        | '20%'    | 'IO'       | 'CAP CHIP 22UF 2.5V(20%,X6S,0805,H0.85)'                       | 'CHIP0805'     | ''          | ''   | '20120420'
 '22UF'     | '6.3V'  | '20%'     | 'C0805'     | 'X5R'     | 'CH6221M9A00'(!)   = 'End of Design' | 'Comp-Approve'     | ''       | 'CH6221M9A00'     |'C0805_H61'| '(SMC0805AW)'                                                        | '22UF'     | '6.3V'        | '20%'    | 'DISCRETE' | 'CAP CHIP 22U 6.3V(+-20%,X5R,0805)H1.25'                       | 'CHIP0805'     | ''          | ''   | '20120420'
 '22UF'     | '6.3V'  | '20%'     | 'C0805'     | 'EMPTY'   | 'CH6221M9A00'(!)   = 'End of Design' | 'Comp-Approve'     | ''       | 'CH6221M9A00'     |'C0805_H61'| '(SMC0805AW)'                                                        | 'NA'       | '6.3V'        | '20%'    | 'IO'       | 'CAP CHIP 22U 6.3V(+-20%,X5R,0805)H1.25'                       | 'CHIP0805'     | ''          | ''   | '20120420'
 '0.039UF'  | '16V'   | '10%'     | 'C0603'     | 'X7R'     | 'CH33903K911'(!)   = ''              | ''                 | ''       | 'CH33903K911'     |'C0603'| '(SMC0603AW)'                                                        | '0.039UF'  | '16V'         | '10%'    | 'DISCRETE' | 'CAP CHIP 0.039U 16V(+-10%.X7R.0603)'                          | 'CHIP0603'     | ''          | ''   | '20120423'
 '0.039UF'  | '16V'   | '10%'     | 'C0603'     | 'EMPTY'   | 'CH33903K911'(!)   = ''              | ''                 | ''       | 'CH33903K911'     |'C0603'| '(SMC0603AW)'                                                        | 'NA'       | '16V'         | '10%'    | 'IO'       | 'CAP CHIP 0.039U 16V(+-10%.X7R.0603)'                          | 'CHIP0603'     | ''          | ''   | '20120423'
 '0.056UF'  | '16V'   | '10%'     | 'C0402'     | 'X7R'     | 'CH3563K1B00'(!)   = ''              | ''                 | ''       | 'CH3563K1B00'     |'C0402'| '(C0402-0201)'                                                       | '0.056UF'  | '16V'         | '10%'    | 'DISCRETE' | 'CAP CHIP 0.056U 16V(+-10%,X7R,0402)'                          | 'CHIP0402'     | ''          | ''   | '20120424'
 '0.056UF'  | '16V'   | '10%'     | 'C0402'     | 'EMPTY'   | 'CH3563K1B00'(!)   = ''              | ''                 | ''       | 'CH3563K1B00'     |'C0402'| '(C0402-0201)'                                                       | 'NA'       | '16V'         | '10%'    | 'IO'       | 'CAP CHIP 0.056U 16V(+-10%,X7R,0402)'                          | 'CHIP0402'     | ''          | ''   | '20120424'
 '100UF'    | '4V'    | '20%'     | 'C0805'     | 'X5R'     | 'CH710KM9A00'(!)   = 'End of Design' | 'Comp-Approve'     | ''       | 'CH710KM9A00'     |'C0805_H61'| '(SMC0805AW)'                                                        | '100UF'    | '4V'          | '20%'    | 'DISCRETE' | 'CAP CHIP 100U 4V(+-20%,X5R,0805)H1.25'                        | 'CHIP0805'     | ''          | ''   | '20120509'
 '100UF'    | '4V'    | '20%'     | 'C0805'     | 'EMPTY'   | 'CH710KM9A00'(!)   = 'End of Design' | 'Comp-Approve'     | ''       | 'CH710KM9A00'     |'C0805_H61'| '(SMC0805AW)'                                                        | 'NA'       | '4V'          | '20%'    | 'IO'       | 'CAP CHIP 100U 4V(+-20%,X5R,0805)H1.25'                        | 'CHIP0805'     | ''          | ''   | '20120509'
 '10UF'     | '6.3V'  | '20%'     | 'C0402'     | 'X5R'     | 'CH6101M9B02'(!)   = ''              | ''                 | ''       | 'CH6101M9B02'     |'C0402'| '(C0402-0201)'                                                       | '10UF'     | '6.3V'        | '20%'    | 'DISCRETE' | 'CAP CHIP 10U 6.3V(+-20%,X5R,0402)'                            | 'CHIP0402'     | ''          | ''   | '20120521'
 '10UF'     | '6.3V'  | '20%'     | 'C0402'     | 'EMPTY'   | 'CH6101M9B02'(!)   = ''              | ''                 | ''       | 'CH6101M9B02'     |'C0402'| '(C0402-0201)'                                                       | 'NA'       | '6.3V'        | '20%'    | 'IO'       | 'CAP CHIP 10U 6.3V(+-20%,X5R,0402)'                            | 'CHIP0402'     | ''          | ''   | '20120521'
 '0.1UF'    | '6.3V'  | '10%'     | 'C0201'     | 'X5R'     | 'CH4101K9E01'(!)   = ''              | ''                 | ''       | 'CH4101K9E01'     |'C0201'| '(SMC0201AW)'                                                        | '0.1UF'    | '6.3V'        | '10%'    | 'DISCRETE' | 'CAP CHIP 0.1UF 6.3V(+-10%,X5R,0201)'                          | 'CHIP0201'     | ''          | ''   | '20120528'
 '0.1UF'    | '6.3V'  | '10%'     | 'C0201'     | 'EMPTY'   | 'CH4101K9E01'(!)   = ''              | ''                 | ''       | 'CH4101K9E01'     |'C0201'| '(SMC0201AW)'                                                        | 'NA'       | '6.3V'        | '10%'    | 'IO'       | 'CAP CHIP 0.1UF 6.3V(+-10%,X5R,0201)'                          | 'CHIP0201'     | ''          | ''   | '20120528'
 '1000PF'   | '16V'   | '10%'     | 'C0201'     | 'X7R'     | 'CH2103K1E14'(!)   = ''              | ''                 | ''       | 'CH2103K1E14'     |'C0201'| '(SMC0201AW)'                                                        | '1000PF'   | '16V'         | '10%'    | 'DISCRETE' | 'CAP CHIP 1000P 16V(10%,X7R,0201)'                             | 'CHIP0201'     | ''          | ''   | '20120528'
 '1000PF'   | '16V'   | '10%'     | 'C0201'     | 'EMPTY'   | 'CH2103K1E14'(!)   = ''              | ''                 | ''       | 'CH2103K1E14'     |'C0201'| '(SMC0201AW)'                                                        | 'NA'       | '16V'         | '10%'    | 'IO'       | 'CAP CHIP 1000P 16V(10%,X7R,0201)'                             | 'CHIP0201'     | ''          | ''   | '20120528'
 '0.22UF'   | '6.3V'  | '20%'     | 'C0201'     | 'X5R'     | 'CH4221M9E00'(!)   = 'End of Design' | 'Comp-Release Qty' | ''       | 'CH4221M9E00'     |'C0201'| '(SMC0201AW)'                                                        | '0.22UF'   | '6.3V'        | '20%'    | 'DISCRETE' | 'CAP CHIP 0.22UF 6.3V(20%,X5R,0201)'                           | 'CHIP0201'     | ''          | ''   | '20120528'
 '0.22UF'   | '6.3V'  | '20%'     | 'C0201'     | 'EMPTY'   | 'CH4221M9E00'(!)   = 'End of Design' | 'Comp-Release Qty' | ''       | 'CH4221M9E00'     |'C0201'| '(SMC0201AW)'                                                        | 'NA'       | '6.3V'        | '20%'    | 'IO'       | 'CAP CHIP 0.22UF 6.3V(20%,X5R,0201)'                           | 'CHIP0201'     | ''          | ''   | '20120528'
 '4.7UF'    | '6.3V'  | '20%'     | 'C0402'     | 'X5R'     | 'CH5471M9B00'(!)   = 'End of Design' | 'Comp-Release Qty' | ''       | 'CH5471M9B00'     |'C0402'| '(C0402-0201)'                                                       | '4.7UF'    | '6.3V'        | '20%'    | 'DISCRETE' | 'CAP CHIP 4.7U 6.3V(+-20%.X5R.0402)'                           | 'CHIP0402'     | ''          | ''   | '20120528'
 '4.7UF'    | '6.3V'  | '20%'     | 'C0402'     | 'EMPTY'   | 'CH5471M9B00'(!)   = 'End of Design' | 'Comp-Release Qty' | ''       | 'CH5471M9B00'     |'C0402'| '(C0402-0201)'                                                       | 'NA'       | '6.3V'        | '20%'    | 'IO'       | 'CAP CHIP 4.7U 6.3V(+-20%.X5R.0402)'                           | 'CHIP0402'     | ''          | ''   | '20120528'
 '22UF'     | '6.3V'  | '20%'     | 'C0603'     | 'X5R'     | 'CH6221M9900'(!)   = ''              | ''                 | ''       | 'CH6221M9900'     |'C0603'| '(SMC0603AW)'                                                        | '22UF'     | '6.3V'        | '20%'    | 'DISCRETE' | 'CAP CHIP 22U 6.3V(+-20%,X5R,0603)HF'                          | 'CHIP0603'     | ''          | ''   | '20120528'
 '22UF'     | '6.3V'  | '20%'     | 'C0603'     | 'EMPTY'   | 'CH6221M9900'(!)   = ''              | ''                 | ''       | 'CH6221M9900'     |'C0603'| '(SMC0603AW)'                                                        | 'NA'       | '6.3V'        | '20%'    | 'IO'       | 'CAP CHIP 22U 6.3V(+-20%,X5R,0603)HF'                          | 'CHIP0603'     | ''          | ''   | '20120528'
 '1UF'      | '6.3V'  | '20%'     | 'C0201'     | 'X5R'     | 'CH5101M9E02'(!)   = ''              | ''                 | ''       | 'CH5101M9E02'     |'C0201'| '(SMC0201AW)'                                                        | '1UF'      | '6.3V'        | '20%'    | 'DISCRETE' | 'CAP CHIP 1UF 6.3V(+-20%,X5R,0201)'                            | 'CHIP0201'     | ''          | ''   | '20120528'
 '1UF'      | '6.3V'  | '20%'     | 'C0201'     | 'EMPTY'   | 'CH5101M9E02'(!)   = ''              | ''                 | ''       | 'CH5101M9E02'     |'C0201'| '(SMC0201AW)'                                                        | 'NA'       | '6.3V'        | '20%'    | 'IO'       | 'CAP CHIP 1UF 6.3V(+-20%,X5R,0201)'                            | 'CHIP0201'     | ''          | ''   | '20120528'
 '5.6PF'    | '25V'   | '0.25PF'  | 'C0201'     | 'C0G'     | 'CH-564C0E00'(!)   = ''              | ''                 | ''       | 'CH-564C0E00'     |'C0201'| '(SMC0201AW)'                                                        | '5.6PF'    | '25V'         | '0.25PF' | 'DISCRETE' | 'CAP 5.6PF 25V(0.25PF,C0G,0201,HQ,ESR250)'                     | 'CHIP0201'     | ''          | ''   | '20120601'
 '5.6PF'    | '25V'   | '0.25PF'  | 'C0201'     | 'EMPTY'   | 'CH-564C0E00'(!)   = ''              | ''                 | ''       | 'CH-564C0E00'     |'C0201'| '(SMC0201AW)'                                                        | 'NA'       | '25V'         | '0.25PF' | 'IO'       | 'CAP 5.6PF 25V(0.25PF,C0G,0201,HQ,ESR250)'                     | 'CHIP0201'     | ''          | ''   | '20120601'
 '22UF'     | '6.3V'  | '20%'     | 'C0805'     | 'X5R'     | 'CH6221M9A01'(!)   = 'End of Design' | 'End of Life'      | ''       | 'CH6221M9A01'     |'C0805_H61_EOL'| '(SMC0805AW)'                                                        | '22UF'     | '6.3V'        | '20%'    | 'DISCRETE' | 'CAP CHIP 22U 6.3V(+-20%.X5R.0805)H1.25'                       | 'CHIP0805'     | ''          | ''   | '20120604'
 '22UF'     | '6.3V'  | '20%'     | 'C0805'     | 'EMPTY'   | 'CH6221M9A01'(!)   = 'End of Design' | 'End of Life'      | ''       | 'CH6221M9A01'     |'C0805_H61_EOL'| '(SMC0805AW)'                                                        | 'NA'       | '6.3V'        | '20%'    | 'IO'       | 'CAP CHIP 22U 6.3V(+-20%.X5R.0805)H1.25'                       | 'CHIP0805'     | ''          | ''   | '20120604'
 '4.7UF'    | '10V'   | '20%'     | 'C0603'     | 'X5R'     | 'CH5472M9901'(!)   = 'End of Design' | 'Comp-Approve'     | ''       | 'CH5472M9901'     |'C0603'| '(SMC0603AW)'                                                        | '4.7UF'    | '10V'         | '20%'    | 'DISCRETE' | 'CAP CHIP 4.7U,10V(+-20%,X5R,0603)'                            | 'CHIP0603'     | ''          | ''   | '20120604'
 '4.7UF'    | '10V'   | '20%'     | 'C0603'     | 'EMPTY'   | 'CH5472M9901'(!)   = 'End of Design' | 'Comp-Approve'     | ''       | 'CH5472M9901'     |'C0603'| '(SMC0603AW)'                                                        | 'NA'       | '10V'         | '20%'    | 'IO'       | 'CAP CHIP 4.7U,10V(+-20%,X5R,0603)'                            | 'CHIP0603'     | ''          | ''   | '20120604'
 '0.033UF'  | '50V'   | '10%'     | 'C0603'     | 'X7R'     | 'CH33306K915'(!)   = 'End of Design' | 'Comp-Approve'     | ''       | 'CH33306K915'     |'C0603'| '(SMC0603AW)'                                                        | '0.033UF'  | '50V'         | '10%'    | 'DISCRETE' | 'CAP CHIP 0.033U 50V(+-10%,X7R,0603)'                          | 'CHIP0603'     | ''          | ''   | '20120727'
 '0.033UF'  | '50V'   | '10%'     | 'C0603'     | 'EMPTY'   | 'CH33306K915'(!)   = 'End of Design' | 'Comp-Approve'     | ''       | 'CH33306K915'     |'C0603'| '(SMC0603AW)'                                                        | 'NA'       | '50V'         | '10%'    | 'IO'       | 'CAP CHIP 0.033U 50V(+-10%,X7R,0603)'                          | 'CHIP0603'     | ''          | ''   | '20120727'
 '4.7UF'    | '25V'   | '20%'     | 'C1206'     | 'X7R'     | 'CH5474M1200'(!)   = 'End of Design' | 'Comp-Approve'     | ''       | 'CH5474M1200'     |'C1206_H66'| '(SMC1206AW)'                                                        | '4.7UF'    | '25V'         | '20%'    | 'DISCRETE' | 'CAP CHIP 4.7U 25V(+-20%,X7R,1206)H1.6'                        | 'CHIP1206'     | ''          | ''   | '20120814'
 '4.7UF'    | '25V'   | '20%'     | 'C1206'     | 'EMPTY'   | 'CH5474M1200'(!)   = 'End of Design' | 'Comp-Approve'     | ''       | 'CH5474M1200'     |'C1206_H66'| '(SMC1206AW)'                                                        | 'NA'       | '25V'         | '20%'    | 'IO'       | 'CAP CHIP 4.7U 25V(+-20%,X7R,1206)H1.6'                        | 'CHIP1206'     | ''          | ''   | '20120814'
 '0.01UF'   | '250V'  | '10%'     | 'C0805'     | 'X7R'     | 'CH3100CKA14'(!)   = ''              | ''                 | ''       | 'CH3100CKA14'     |'C0805_H61'| '(SMC0805AW)'                                                        | '0.01UF'   | '250V'        | '10%'    | 'DISCRETE' | 'CAP CHIP 0.01U 250V(+-10%.X7R.0805)'                          | 'CHIP0805'     | ''          | ''   | '20120905'
 '0.01UF'   | '250V'  | '10%'     | 'C0805'     | 'EMPTY'   | 'CH3100CKA14'(!)   = ''              | ''                 | ''       | 'CH3100CKA14'     |'C0805_H61'| '(SMC0805AW)'                                                        | 'NA'       | '250V'        | '10%'    | 'IO'       | 'CAP CHIP 0.01U 250V(+-10%.X7R.0805)'                          | 'CHIP0805'     | ''          | ''   | '20120905'
 '0.33UF'   | '6.3V'  | '10%'     | 'C0402'     | 'X5R'     | 'CH4331K9B06'(!)   = 'End of Design' | 'Comp-Approve'     | ''       | 'CH4331K9B06'     |'C0402'| '(C0402-0201)'                                                       | '0.33UF'   | '6.3V'        | '10%'    | 'DISCRETE' | 'CAP CHIP 0.33U 6.3V(10%.X5R.0402)'                            | 'CHIP0402'     | ''          | ''   | '20120906'
 '0.33UF'   | '6.3V'  | '10%'     | 'C0402'     | 'EMPTY'   | 'CH4331K9B06'(!)   = 'End of Design' | 'Comp-Approve'     | ''       | 'CH4331K9B06'     |'C0402'| '(C0402-0201)'                                                       | 'NA'       | '6.3V'        | '10%'    | 'IO'       | 'CAP CHIP 0.33U 6.3V(10%.X5R.0402)'                            | 'CHIP0402'     | ''          | ''   | '20120906'
 '39NF'     | '16V'   | '10%'     | 'C0402'     | 'X7R'     | 'CH3393K1B00'(!)   = ''              | ''                 | ''       | 'CH3393K1B00'     |'C0402'| '(C0402-0201)'                                                       | '39NF'     | '16V'         | '10%'    | 'DISCRETE' | 'CAP CHIP 39NF 16V(+-10%,X7R,0402)'                            | 'CHIP0402'     | ''          | ''   | '20120917'
 '39NF'     | '16V'   | '10%'     | 'C0402'     | 'EMPTY'   | 'CH3393K1B00'(!)   = ''              | ''                 | ''       | 'CH3393K1B00'     |'C0402'| '(C0402-0201)'                                                       | 'NA'       | '16V'         | '10%'    | 'IO'       | 'CAP CHIP 39NF 16V(+-10%,X7R,0402)'                            | 'CHIP0402'     | ''          | ''   | '20120917'
 '1UF'      | '10V'   | '10%'     | 'C0402'     | 'X6S'     | 'CH5102KEB00'(!)   = ''              | ''                 | ''       | 'CH5102KEB00'     |'C0402'| '(C0402-0201)'                                                       | '1UF'      | '10V'         | '10%'    | 'DISCRETE' | 'CAP CHIP 1UF 10V(+-10%,X6S,0402)'                             | 'CHIP0402'     | ''          | ''   | '20120919'
 '1UF'      | '10V'   | '10%'     | 'C0402'     | 'EMPTY'   | 'CH5102KEB00'(!)   = ''              | ''                 | ''       | 'CH5102KEB00'     |'C0402'| '(C0402-0201)'                                                       | 'NA'       | '10V'         | '10%'    | 'IO'       | 'CAP CHIP 1UF 10V(+-10%,X6S,0402)'                             | 'CHIP0402'     | ''          | ''   | '20120919'
 '0.47UF'   | '10V'   | '10%'     | 'C0402'     | 'X6S'     | 'CH44702KEB0'(!)   = 'End of Design' | 'Comp-Approve'     | ''       | 'CH44702KEB0'     |'C0402'| '(C0402-0201)'                                                       | '0.47UF'   | '10V'         | '10%'    | 'DISCRETE' | 'CAP CHIP 0.47UF 10V(+-10%,X6S,0402)'                          | 'CHIP0402'     | ''          | ''   | '20121002'
 '0.47UF'   | '10V'   | '10%'     | 'C0402'     | 'EMPTY'   | 'CH44702KEB0'(!)   = 'End of Design' | 'Comp-Approve'     | ''       | 'CH44702KEB0'     |'C0402'| '(C0402-0201)'                                                       | 'NA'       | '10V'         | '10%'    | 'IO'       | 'CAP CHIP 0.47UF 10V(+-10%,X6S,0402)'                          | 'CHIP0402'     | ''          | ''   | '20121002'
 '0.33UF'   | '6.3V'  | '10%'     | 'C0402'     | 'X6S'     | 'CH4331KEB01'(!)   = 'End of Design' | 'Comp-Approve'     | ''       | 'CH4331KEB01'     |'C0402'| '(C0402-0201)'                                                       | '0.33UF'   | '6.3V'        | '10%'    | 'DISCRETE' | 'CAP CHIP 0.33UF 6.3V(10%,X6S,0402)'                           | 'CHIP0402'     | ''          | ''   | '20121009'
 '0.33UF'   | '6.3V'  | '10%'     | 'C0402'     | 'EMPTY'   | 'CH4331KEB01'(!)   = 'End of Design' | 'Comp-Approve'     | ''       | 'CH4331KEB01'     |'C0402'| '(C0402-0201)'                                                       | 'NA'       | '6.3V'        | '10%'    | 'IO'       | 'CAP CHIP 0.33UF 6.3V(10%,X6S,0402)'                           | 'CHIP0402'     | ''          | ''   | '20121009'
 '0.47UF'   | '6.3V'  | '10%'     | 'C0402'     | 'X6S'     | 'CH4471KEB01'(!)   = 'End of Design' | 'Comp-Approve'     | ''       | 'CH4471KEB01'     |'C0402'| '(C0402-0201)'                                                       | '0.47UF'   | '6.3V'        | '10%'    | 'DISCRETE' | 'CAP CHIP 0.47UF 6.3V(10%,X6S,0402)'                           | 'CHIP0402'     | ''          | ''   | '20121009'
 '0.47UF'   | '6.3V'  | '10%'     | 'C0402'     | 'EMPTY'   | 'CH4471KEB01'(!)   = 'End of Design' | 'Comp-Approve'     | ''       | 'CH4471KEB01'     |'C0402'| '(C0402-0201)'                                                       | 'NA'       | '6.3V'        | '10%'    | 'IO'       | 'CAP CHIP 0.47UF 6.3V(10%,X6S,0402)'                           | 'CHIP0402'     | ''          | ''   | '20121009'
 '22UF'     | '25V'   | '10%'     | 'C1206'     | 'X5R'     | 'CH6224K9200'(!)   = 'End of Design' | 'Comp-Approve'     | ''       | 'CH6224K9200'     |'C1206_H76'| '(SMC1206AW)'                                                        | '22UF'     | '25V'         | '10%'    | 'DISCRETE' | 'CAP CHIP 22U 25V(+-10%,X5R,1206)'                             | 'CHIP1206'     | ''          | ''   | '20121201'
 '22UF'     | '25V'   | '10%'     | 'C1206'     | 'EMPTY'   | 'CH6224K9200'(!)   = 'End of Design' | 'Comp-Approve'     | ''       | 'CH6224K9200'     |'C1206_H76'| '(SMC1206AW)'                                                        | 'NA'       | '25V'         | '10%'    | 'IO'       | 'CAP CHIP 22U 25V(+-10%,X5R,1206)'                             | 'CHIP1206'     | ''          | ''   | '20121201'
 '4.7PF'    | '50V'   | '0.1P'    | 'C0402'     | 'NPO'     | 'CH-4716TB06'(!)   = ''              | ''                 | ''       | 'CH-4716TB06'     |'C0402'| '(C0402-0201)'                                                       | '4.7PF'    | '50V'         | '0.10%'  | 'DISCRETE' | 'CAP CHIP 4.7P 50V(+-0.1P.NPO.0402)'                           | 'CHIP0402'     | ''          | ''   | '20121216'
 '4.7PF'    | '50V'   | '0.1P'    | 'C0402'     | 'EMPTY'   | 'CH-4716TB06'(!)   = ''              | ''                 | ''       | 'CH-4716TB06'     |'C0402'| '(C0402-0201)'                                                       | 'NA'       | '50V'         | '0.10%'  | 'IO'       | 'CAP CHIP 4.7P 50V(+-0.1P.NPO.0402)'                           | 'CHIP0402'     | ''          | ''   | '20121216'
 '0.47UF'   | '100V'  | '10%'     | 'C0805'     | 'X7R'     | 'CH4478K1A00'(!)   = ''              | ''                 | ''       | 'CH4478K1A00'     |'C0805_H61'| '(SMC0805AW)'                                                        | '0.47UF'   | '100V'        | '10%'    | 'DISCRETE' | 'CAP CHIP 0.47U 100V(+-10%.X7R.0805)'                          | 'CHIP0805'     | ''          | ''   | '20121219'
 '0.47UF'   | '100V'  | '10%'     | 'C0805'     | 'EMPTY'   | 'CH4478K1A00'(!)   = ''              | ''                 | ''       | 'CH4478K1A00'     |'C0805_H61'| '(SMC0805AW)'                                                        | 'NA'       | '100V'        | '10%'    | 'IO'       | 'CAP CHIP 0.47U 100V(+-10%.X7R.0805)'                          | 'CHIP0805'     | ''          | ''   | '20121219'
 '2.2UF'    | '100V'  | '10%'     | 'C1206'     | 'X7R'     | 'CH5228K1202'(!)   = 'End of Design' | 'Comp-Approve'     | ''       | 'CH5228K1202'     |'C1206_H76'| '(SMC1206AW)'                                                        | '2.2UF'    | '100V'        | '10%'    | 'DISCRETE' | 'CAP CHIP 2.2UF 100V(+-10%,X7R,1206)'                          | 'CHIP1206'     | ''          | ''   | '20121219'
 '2.2UF'    | '100V'  | '10%'     | 'C1206'     | 'EMPTY'   | 'CH5228K1202'(!)   = 'End of Design' | 'Comp-Approve'     | ''       | 'CH5228K1202'     |'C1206_H76'| '(SMC1206AW)'                                                        | 'NA'       | '100V'        | '10%'    | 'IO'       | 'CAP CHIP 2.2UF 100V(+-10%,X7R,1206)'                          | 'CHIP1206'     | ''          | ''   | '20121219'
 '0.01UF'   | '1KV'   | '10%'     | 'C1206'     | 'X7R'     | 'CH310FK1200'(!)   = ''              | ''                 | ''       | 'CH310FK1200'     |'C1206_H56'| '(SMC1206AW)'                                                        | '0.01UF'   | '1KV'         | '10%'    | 'DISCRETE' | 'CAP CHIP 0.01U 1KV(+-10%,X7R,1206)H1.25'                      | 'CHIP1206'     | ''          | ''   | '20130103'
 '0.01UF'   | '1KV'   | '10%'     | 'C1206'     | 'EMPTY'   | 'CH310FK1200'(!)   = ''              | ''                 | ''       | 'CH310FK1200'     |'C1206_H56'| '(SMC1206AW)'                                                        | 'NA'       | '1KV'         | '10%'    | 'IO'       | 'CAP CHIP 0.01U 1KV(+-10%,X7R,1206)H1.25'                      | 'CHIP1206'     | ''          | ''   | '20130103'
 '0.01UF'   | '100V'  | '10%'     | 'C0603'     | 'X7R'     | 'CH3108K1900'(!)   = ''              | ''                 | ''       | 'CH3108K1900'     |'C0603'| '(SMC0603AW)'                                                        | '0.01UF'   | '100V'        | '10%'    | 'DISCRETE' | 'CAP CHIP 0.01U 100V(+-10%.X7R.0603)'                          | 'CHIP0603'     | ''          | ''   | '20130110'
 '0.01UF'   | '100V'  | '10%'     | 'C0603'     | 'EMPTY'   | 'CH3108K1900'(!)   = ''              | ''                 | ''       | 'CH3108K1900'     |'C0603'| '(SMC0603AW)'                                                        | 'NA'       | '100V'        | '10%'    | 'IO'       | 'CAP CHIP 0.01U 100V(+-10%.X7R.0603)'                          | 'CHIP0603'     | ''          | ''   | '20130110'
 '560PF'    | '50V'   | '10%'     | 'C0402'     | 'X7R'     | 'CH1566K1B09'(!)   = ''              | ''                 | ''       | 'CH1566K1B09'     |'C0402'| '(C0402_OCTAGONXA,C0402-0201)'                                       | '560PF'    | '50V'         | '10%'    | 'DISCRETE' | 'CAP CHIP 560P 50V(+-10%,X7R,0402)'                            | 'CHIP0402'     | ''          | ''   | '20130114'
 '560PF'    | '50V'   | '10%'     | 'C0402'     | 'EMPTY'   | 'CH1566K1B09'(!)   = ''              | ''                 | ''       | 'CH1566K1B09'     |'C0402'| '(C0402_OCTAGONXA,C0402-0201)'                                       | 'NA'       | '50V'         | '10%'    | 'IO'       | 'CAP CHIP 560P 50V(+-10%,X7R,0402)'                            | 'CHIP0402'     | ''          | ''   | '20130114'
 '820PF'    | '50V'   | '10%'     | 'C0402'     | 'X7R'     | 'CH18206KB11'(!)   = ''              | ''                 | ''       | 'CH18206KB11'     |'C0402'| '(C0402-0201)'                                                       | '820PF'    | '50V'         | '10%'    | 'DISCRETE' | 'CAP CHIP 820P 50V(+-10%,X7R,0402)'                            | 'CHIP0402'     | ''          | ''   | '20130114'
 '820PF'    | '50V'   | '10%'     | 'C0402'     | 'EMPTY'   | 'CH18206KB11'(!)   = ''              | ''                 | ''       | 'CH18206KB11'     |'C0402'| '(C0402-0201)'                                                       | 'NA'       | '50V'         | '10%'    | 'IO'       | 'CAP CHIP 820P 50V(+-10%,X7R,0402)'                            | 'CHIP0402'     | ''          | ''   | '20130114'
 '2.2UF'    | '16V'   | '20%'     | 'C0805'     | 'Y5V'     | 'CH52203ZA30'(!)   = ''              | ''                 | ''       | 'CH52203ZA30'     |'C0805_H64'| '(SMC0805AW)'                                                        | '2.2UF'    | '16V'         | '20%'    | 'DISCRETE' | 'CAP CHIP 2.2U.16V(+80-20%.Y5V.0805)'                          | 'CHIP0805'     | ''          | ''   | '20130214'
 '2.2UF'    | '16V'   | '20%'     | 'C0805'     | 'EMPTY'   | 'CH52203ZA30'(!)   = ''              | ''                 | ''       | 'CH52203ZA30'     |'C0805_H64'| '(SMC0805AW)'                                                        | 'NA'       | '16V'         | '20%'    | 'IO'       | 'CAP CHIP 2.2U.16V(+80-20%.Y5V.0805)'                          | 'CHIP0805'     | ''          | ''   | '20130214'
 '22UF'     | '4V'    | '20%'     | 'C0603'     | 'X6S'     | 'CH622KME901'(!)   = ''              | ''                 | ''       | 'CH622KME901'     |'C0603'| '(SMC0603AW)'                                                        | '22UF'     | '4V'          | '20%'    | 'DISCRETE' | 'CAP CHIP 22UF 4V(+-20%,X6S,0603)'                             | 'CHIP0603'     | ''          | ''   | '20130321'
 '22UF'     | '4V'    | '20%'     | 'C0603'     | 'EMPTY'   | 'CH622KME901'(!)   = ''              | ''                 | ''       | 'CH622KME901'     |'C0603'| '(SMC0603AW)'                                                        | 'NA'       | '4V'          | '20%'    | 'IO'       | 'CAP CHIP 22UF 4V(+-20%,X6S,0603)'                             | 'CHIP0603'     | ''          | ''   | '20130321'
 '0.68UF'   | '16V'   | '80%'     | 'C0603'     | 'Y5V'     | 'CH4683Z3900'(!)   = 'End of Design' | 'Comp-Approve'     | ''       | 'CH4683Z3900'     |'C0603'| '(SMC0603AW)'                                                        | '0.68UF'   | '16V'         | '80%'    | 'DISCRETE' | 'CAP CHIP 0.68U 16V(+80%-20%,Y5V,0603)'                        | 'CHIP0603'     | ''          | ''   | '20130321'
 '0.68UF'   | '16V'   | '80%'     | 'C0603'     | 'EMPTY'   | 'CH4683Z3900'(!)   = 'End of Design' | 'Comp-Approve'     | ''       | 'CH4683Z3900'     |'C0603'| '(SMC0603AW)'                                                        | 'NA'       | '16V'         | '80%'    | 'IO'       | 'CAP CHIP 0.68U 16V(+80%-20%,Y5V,0603)'                        | 'CHIP0603'     | ''          | ''   | '20130321'
 '22UF'     | '4V'    | '20%'     | 'C0402'     | 'X5R'     | 'CH622KM9B02'(!)   = 'End of Design' | 'Comp-Approve'     | ''       | 'CH622KM9B02'     |'C0402'| '(C0402-0201)'                                                       | '22UF'     | '4V'          | '20%'    | 'DISCRETE' | 'CAP CHIP 22UF 4V (+-20%, X5R,0402)'                           | 'CHIP0402'     | ''          | ''   | '20130408'
 '22UF'     | '4V'    | '20%'     | 'C0402'     | 'EMPTY'   | 'CH622KM9B02'(!)   = 'End of Design' | 'Comp-Approve'     | ''       | 'CH622KM9B02'     |'C0402'| '(C0402-0201)'                                                       | 'NA'       | '4V'          | '20%'    | 'IO'       | 'CAP CHIP 22UF 4V (+-20%, X5R,0402)'                           | 'CHIP0402'     | ''          | ''   | '20130408'
 '180PF'    | '50V'   | '5%'      | 'C0402'     | 'NPO'     | 'CH11806JB09'(!)   = ''              | ''                 | ''       | 'CH11806JB09'     |'C0402'| '(C0402-0201)'                                                       | '180PF'    | '50V'         | '5%'     | 'DISCRETE' | 'CAP CHIP 180P 50V(+-5%.NPO.0402)'                             | 'CHIP0402'     | ''          | ''   | '20130628'
 '180PF'    | '50V'   | '5%'      | 'C0402'     | 'EMPTY'   | 'CH11806JB09'(!)   = ''              | ''                 | ''       | 'CH11806JB09'     |'C0402'| '(C0402-0201)'                                                       | 'NA'       | '50V'         | '5%'     | 'IO'       | 'CAP CHIP 180P 50V(+-5%.NPO.0402)'                             | 'CHIP0402'     | ''          | ''   | '20130628'
 '12PF'     | '50V'   | '5%'      | 'C0402'     | 'C0G'     | 'CH01206JB05'(!)   = ''              | ''                 | ''       | 'CH01206JB05'     |'C0402'| '(C0402-0201)'                                                       | '12PF'     | '50V'         | '5%'     | 'DISCRETE' | 'CAP CHIP 12P 50V(+-5%.C0G.0402)'                              | 'CHIP0402'     | ''          | ''   | '20130703'
 '12PF'     | '50V'   | '5%'      | 'C0402'     | 'EMPTY'   | 'CH01206JB05'(!)   = ''              | ''                 | ''       | 'CH01206JB05'     |'C0402'| '(C0402-0201)'                                                       | 'NA'       | '50V'         | '5%'     | 'IO'       | 'CAP CHIP 12P 50V(+-5%.C0G.0402)'                              | 'CHIP0402'     | ''          | ''   | '20130703'
 '4700PF'   | '6.3V'  | '10%'     | 'C0201'     | 'X7R'     | 'CH2471K1E01'(!)   = ''              | ''                 | ''       | 'CH2471K1E01'     |'C0201'| '(SMC0201AW)'                                                        | '4700PF'   | '6.3V'        | '10%'    | 'DISCRETE' | 'CAP CHIP 4700P 6.3V (+-10%,X7R,0201)'                         | 'CHIP0201'     | ''          | ''   | '20131017'
 '4700PF'   | '6.3V'  | '10%'     | 'C0201'     | 'EMPTY'   | 'CH2471K1E01'(!)   = ''              | ''                 | ''       | 'CH2471K1E01'     |'C0201'| '(SMC0201AW)'                                                        | 'NA'       | '6.3V'        | '10%'    | 'IO'       | 'CAP CHIP 4700P 6.3V (+-10%,X7R,0201)'                         | 'CHIP0201'     | ''          | ''   | '20131017'
 '0.1UF'    | '4V'    | '20%'     | 'C0201'     | 'X6S'     | 'CH410KMEE00'(!)   = 'End of Design' | 'Comp-Approve'     | ''       | 'CH410KMEE00'     |'C0201'| '(SMC0201AW)'                                                        | '0.1UF'    | '4V'          | '20%'    | 'DISCRETE' | 'CAP CHIP 0.1U 4V(+-20%,X6S,0201)'                             | 'CHIP0201'     | ''          | ''   | '20131017'
 '0.1UF'    | '4V'    | '20%'     | 'C0201'     | 'EMPTY'   | 'CH410KMEE00'(!)   = 'End of Design' | 'Comp-Approve'     | ''       | 'CH410KMEE00'     |'C0201'| '(SMC0201AW)'                                                        | 'NA'       | '4V'          | '20%'    | 'IO'       | 'CAP CHIP 0.1U 4V(+-20%,X6S,0201)'                             | 'CHIP0201'     | ''          | ''   | '20131017'
 '2.2UF'    | '10V'   | '10%'     | 'C0603'     | 'X5R'     | 'CH5222K9907'(!)   = 'End of Design' | 'Comp-Approve'     | ''       | 'CH5222K9907'     |'C0603'| '(SMC0603AW)'                                                        | '2.2UF'    | '10V'         | '10%'    | 'DISCRETE' | 'CAP CHIP 2.2U 10V(+-10%.X5R.0603)'                            | 'CHIP0603'     | ''          | ''   | '20140325'
 '2.2UF'    | '10V'   | '10%'     | 'C0603'     | 'EMPTY'   | 'CH5222K9907'(!)   = 'End of Design' | 'Comp-Approve'     | ''       | 'CH5222K9907'     |'C0603'| '(SMC0603AW)'                                                        | 'NA'       | '10V'         | '10%'    | 'IO'       | 'CAP CHIP 2.2U 10V(+-10%.X5R.0603)'                            | 'CHIP0603'     | ''          | ''   | '20140325'
 '0.047UF'  | '25V'   | '10%'     | 'C0402'     | 'X7R'     | 'CH3474K1B04'(!)   = ''              | ''                 | ''       | 'CH3474K1B04'     |'C0402'| '(C0402_OCTAGONXA,C0402-0201)'                                       | '0.047UF'  | '25V'         | '10%'    | 'DISCRETE' | 'CAP CHIP 0.047U 25V(+-10% X7R 0402)'                          | 'CHIP0402'     | ''          | ''   | '20140325'
 '0.047UF'  | '25V'   | '10%'     | 'C0402'     | 'EMPTY'   | 'CH3474K1B04'(!)   = ''              | ''                 | ''       | 'CH3474K1B04'     |'C0402'| '(C0402_OCTAGONXA,C0402-0201)'                                       | 'NA'       | '25V'         | '10%'    | 'IO'       | 'CAP CHIP 0.047U 25V(+-10% X7R 0402)'                          | 'CHIP0402'     | ''          | ''   | '20140325'
 '3900PF'   | '50V'   | '10%'     | 'C0402'     | 'X7R'     | 'CH23906KB14'(!)   = ''              | ''                 | ''       | 'CH23906KB14'     |'C0402'| '(C0402-0201)'                                                       | '3900PF'   | '50V'         | '10%'    | 'DISCRETE' | 'CAP CHIP 3900P 50V(+-10%,X7R,0402)'                           | 'CHIP0402'     | ''          | ''   | '20140325'
 '3900PF'   | '50V'   | '10%'     | 'C0402'     | 'EMPTY'   | 'CH23906KB14'(!)   = ''              | ''                 | ''       | 'CH23906KB14'     |'C0402'| '(C0402-0201)'                                                       | 'NA'       | '50V'         | '10%'    | 'IO'       | 'CAP CHIP 3900P 50V(+-10%,X7R,0402)'                           | 'CHIP0402'     | ''          | ''   | '20140325'
 '8.2PF'    | '50V'   | '0.1P'    | 'C0402'     | 'NP0'     | 'CH-8216TB09'(!)   = ''              | ''                 | ''       | 'CH-8216TB09'     |'C0402'| '(C0402-0201)'                                                       | '8.2PF'    | '50V'         | '0.1P'   | 'DISCRETE' | 'CAP CHIP 8.2P 50V (+-0.1P NP0 0402)'                          | 'CHIP0402'     | ''          | ''   | '20140326'
 '8.2PF'    | '50V'   | '0.1P'    | 'C0402'     | 'EMPTY'   | 'CH-8216TB09'(!)   = ''              | ''                 | ''       | 'CH-8216TB09'     |'C0402'| '(C0402-0201)'                                                       | 'NA'       | '50V'         | '0.1P'   | 'IO'       | 'CAP CHIP 8.2P 50V (+-0.1P NP0 0402)'                          | 'CHIP0402'     | ''          | ''   | '20140326'
 '220PF'    | '100V'  | '10%'     | 'C0402'     | 'X7R'     | 'CH1228K1B00'(!)   = 'End of Design' | 'Comp-Approve'     | ''       | 'CH1228K1B00'     |'C0402'| '(C0402-0201)'                                                       | '220PF'    | '100V'        | '10%'    | 'DISCRETE' | 'CAP CHIP 220PF 100V(10%,X7R,0402)'                            | 'CHIP0402'     | ''          | ''   | '20140326'
 '220PF'    | '100V'  | '10%'     | 'C0402'     | 'EMPTY'   | 'CH1228K1B00'(!)   = 'End of Design' | 'Comp-Approve'     | ''       | 'CH1228K1B00'     |'C0402'| '(C0402-0201)'                                                       | 'NA'       | '100V'        | '10%'    | 'IO'       | 'CAP CHIP 220PF 100V(10%,X7R,0402)'                            | 'CHIP0402'     | ''          | ''   | '20140326'
 '10UF'     | '25V'   | '10%'     | 'C0805'     | 'X6S'     | 'CH6104KEA00'(!)   = ''              | ''                 | ''       | 'CH6104KEA00'     |'C0805_H61'| '(SMC0805AW)'                                                        | '10UF'     | '25V'         | '10%'    | 'DISCRETE' | 'CAP CHIP 10U 25V(+-10%,X6S,0805,H1.25)'                       | 'CHIP0805'     | ''          | ''   | '20140327'
 '10UF'     | '25V'   | '10%'     | 'C0805'     | 'EMPTY'   | 'CH6104KEA00'(!)   = ''              | ''                 | ''       | 'CH6104KEA00'     |'C0805_H61'| '(SMC0805AW)'                                                        | 'NA'       | '25V'         | '10%'    | 'IO'       | 'CAP CHIP 10U 25V(+-10%,X6S,0805,H1.25)'                       | 'CHIP0805'     | ''          | ''   | '20140327'
 '1UF'      | '25V'   | '10%'     | 'C0402'     | 'X6S'     | 'CH5104KEB02'(!)   = ''              | ''                 | ''       | 'CH5104KEB02'     |'C0402'| '(C0402_OCTAGONXA,C0402-0201)'                                       | '1UF'      | '25V'         | '10%'    | 'DISCRETE' | 'CAP CHIP 1UF 25V(+-10%,X6S,0402)'                             | 'CHIP0402'     | ''          | ''   | '20140327'
 '1UF'      | '25V'   | '10%'     | 'C0402'     | 'EMPTY'   | 'CH5104KEB02'(!)   = ''              | ''                 | ''       | 'CH5104KEB02'     |'C0402'| '(C0402_OCTAGONXA,C0402-0201)'                                       | 'NA'       | '25V'         | '10%'    | 'IO'       | 'CAP CHIP 1UF 25V(+-10%,X6S,0402)'                             | 'CHIP0402'     | ''          | ''   | '20140327'
 '2.2UF'    | '16V'   | '10%'     | 'C0603'     | 'X6S'     | 'CH5223KE901'(!)   = ''              | ''                 | ''       | 'CH5223KE901'     |'C0603'| '(SMC0603AW)'                                                        | '2.2UF'    | '16V'         | '10%'    | 'DISCRETE' | 'CAP CHIP 2.2U 16V(+-10%,X6S,0603)'                            | 'CHIP0603'     | ''          | ''   | '20140327'
 '2.2UF'    | '16V'   | '10%'     | 'C0603'     | 'EMPTY'   | 'CH5223KE901'(!)   = ''              | ''                 | ''       | 'CH5223KE901'     |'C0603'| '(SMC0603AW)'                                                        | 'NA'       | '16V'         | '10%'    | 'IO'       | 'CAP CHIP 2.2U 16V(+-10%,X6S,0603)'                            | 'CHIP0603'     | ''          | ''   | '20140327'
 '22UF'     | '6.3V'  | '20%'     | 'C0603'     | 'X6S'     | 'CH6221ME900'(!)   = ''              | ''                 | ''       | 'CH6221ME900'     |'C0603'| '(SMC0603AW)'                                                        | '22UF'     | '6.3V'        | '20%'    | 'DISCRETE' | 'CAP CHIP 22U 6.3V(+-20%,X6S,0603)'                            | 'CHIP0603'     | ''          | ''   | '20140327'
 '22UF'     | '6.3V'  | '20%'     | 'C0603'     | 'EMPTY'   | 'CH6221ME900'(!)   = ''              | ''                 | ''       | 'CH6221ME900'     |'C0603'| '(SMC0603AW)'                                                        | 'NA'       | '6.3V'        | '20%'    | 'IO'       | 'CAP CHIP 22U 6.3V(+-20%,X6S,0603)'                            | 'CHIP0603'     | ''          | ''   | '20140327'
 '2.2UF'    | '10V'   | '10%'     | 'C0603'     | 'X7R'     | 'CH5222K1906'(!)   = ''              | ''                 | ''       | 'CH5222K1906'     |'C0603'| '(SMC0603AW)'                                                        | '2.2UF'    | '10V'         | '10%'    | 'DISCRETE' | 'CAP CHIP 2.2UF 10V(+-10%.X7R.0603)'                           | 'CHIP0603'     | ''          | ''   | '20140327'
 '2.2UF'    | '10V'   | '10%'     | 'C0603'     | 'EMPTY'   | 'CH5222K1906'(!)   = ''              | ''                 | ''       | 'CH5222K1906'     |'C0603'| '(SMC0603AW)'                                                        | 'NA'       | '10V'         | '10%'    | 'IO'       | 'CAP CHIP 2.2UF 10V(+-10%.X7R.0603)'                           | 'CHIP0603'     | ''          | ''   | '20140327'
 '0.47UF'   | '25V'   | '10%'     | 'C0603'     | 'X7R'     | 'CH4474K1907'(!)   = 'End of Design' | 'Comp-Approve'     | ''       | 'CH4474K1907'     |'C0603'| '(SMC0603AW)'                                                        | '0.47UF'   | '25V'         | '10%'    | 'DISCRETE' | 'CAP CHIP 0.47UF 25V(+-10%,X7R,0603)'                          | 'CHIP0603'     | ''          | ''   | '20140328'
 '0.47UF'   | '25V'   | '10%'     | 'C0603'     | 'EMPTY'   | 'CH4474K1907'(!)   = 'End of Design' | 'Comp-Approve'     | ''       | 'CH4474K1907'     |'C0603'| '(SMC0603AW)'                                                        | 'NA'       | '25V'         | '10%'    | 'IO'       | 'CAP CHIP 0.47UF 25V(+-10%,X7R,0603)'                          | 'CHIP0603'     | ''          | ''   | '20140328'
 '1000PF'   | '50V'   | '5%'      | 'C0603'     | 'NPO'     | 'CH21006J902'(!)   = 'End of Design' | 'Comp-Approve'     | ''       | 'CH21006J902'     |'C0603'| '(SMC0603AW)'                                                        | '1000PF'   | '50V'         | '5%'     | 'DISCRETE' | 'CAP CHIP 1000P 50V(+-5%.NPO.0603)EP'                          | 'CHIP0603'     | ''          | ''   | '20140328'
 '1000PF'   | '50V'   | '5%'      | 'C0603'     | 'EMPTY'   | 'CH21006J902'(!)   = 'End of Design' | 'Comp-Approve'     | ''       | 'CH21006J902'     |'C0603'| '(SMC0603AW)'                                                        | 'NA'       | '50V'         | '5%'     | 'IO'       | 'CAP CHIP 1000P 50V(+-5%.NPO.0603)EP'                          | 'CHIP0603'     | ''          | ''   | '20140328'
 '0.047UF'  | '50V'   | '10%'     | 'C0603'     | 'X7R'     | 'CH34706K912'(!)   = 'End of Design' | 'Comp-Approve'     | ''       | 'CH34706K912'     |'C0603'| '(SMC0603AW)'                                                        | '0.047UF'  | '50V'         | '10%'    | 'DISCRETE' | 'CAP. CHIP 0.047UF 50V(+-10%,X7R,0603)'                        | 'CHIP0603'     | ''          | ''   | '20140328'
 '0.047UF'  | '50V'   | '10%'     | 'C0603'     | 'EMPTY'   | 'CH34706K912'(!)   = 'End of Design' | 'Comp-Approve'     | ''       | 'CH34706K912'     |'C0603'| '(SMC0603AW)'                                                        | 'NA'       | '50V'         | '10%'    | 'IO'       | 'CAP. CHIP 0.047UF 50V(+-10%,X7R,0603)'                        | 'CHIP0603'     | ''          | ''   | '20140328'
 '10UF'     | '25V'   | '20%'     | 'C0603'     | 'X5R'     | 'CH6104M9901'(!)   = ''              | ''                 | ''       | 'CH6104M9901'     |'C0603'| '(SMC0603AW)'                                                        | '10UF'     | '25V'         | '20%'    | 'DISCRETE' | 'CAP CHIP 10UF 25V(+-20%,X5R,0603)'                            | 'CHIP0603'     | ''          | ''   | '20140331'
 '10UF'     | '25V'   | '20%'     | 'C0603'     | 'EMPTY'   | 'CH6104M9901'(!)   = ''              | ''                 | ''       | 'CH6104M9901'     |'C0603'| '(SMC0603AW)'                                                        | 'NA'       | '25V'         | '20%'    | 'IO'       | 'CAP CHIP 10UF 25V(+-20%,X5R,0603)'                            | 'CHIP0603'     | ''          | ''   | '20140331'
 '10UF'     | '16V'   | '10%'     | 'C0805'     | 'X7R'     | 'CH6103K1A00'(!)   = ''              | ''                 | ''       | 'CH6103K1A00'     |'C0805_H61'| '(SMC0805AW)'                                                        | '10UF'     | '16V'         | '10%'    | 'DISCRETE' | 'CAP CHIP 10UF 16V(+-10%,X7R,0805)'                            | 'CHIP0805'     | ''          | ''   | '20140331'
 '10UF'     | '16V'   | '10%'     | 'C0805'     | 'EMPTY'   | 'CH6103K1A00'(!)   = ''              | ''                 | ''       | 'CH6103K1A00'     |'C0805_H61'| '(SMC0805AW)'                                                        | 'NA'       | '16V'         | '10%'    | 'IO'       | 'CAP CHIP 10UF 16V(+-10%,X7R,0805)'                            | 'CHIP0805'     | ''          | ''   | '20140331'
 '0.01UF'   | '1KV'   | '10%'     | 'C1206'     | 'X7R'     | 'CH310FK1201'(!)   = 'End of Design' | 'Comp-Approve'     | ''       | 'CH310FK1201'     |'C1206_H76'| '(SMC1206AW)'                                                        | '0.01UF'   | '1KV'         | '10%'    | 'DISCRETE' | 'CAP CHIP 0.01U 1KV(+-10%,X7R,1206)H1.6'                       | 'CHIP1206'     | ''          | ''   | '20140331'
 '0.01UF'   | '1KV'   | '10%'     | 'C1206'     | 'EMPTY'   | 'CH310FK1201'(!)   = 'End of Design' | 'Comp-Approve'     | ''       | 'CH310FK1201'     |'C1206_H76'| '(SMC1206AW)'                                                        | 'NA'       | '1KV'         | '10%'    | 'IO'       | 'CAP CHIP 0.01U 1KV(+-10%,X7R,1206)H1.6'                       | 'CHIP1206'     | ''          | ''   | '20140331'
 '0.1UF'    | '100V'  | '10%'     | 'C1206'     | 'X7R'     | 'CH4108K1202'(!)   = 'End of Design' | 'Comp-Approve'     | ''       | 'CH4108K1202'     |'C1206_H42'| '(SMC1206AW)'                                                        | '0.1UF'    | '100V'        | '10%'    | 'DISCRETE' | 'CAP CHIP 0.1U 100V(+-10%.X7R.1206)H1.25'                      | 'CHIP1206'     | ''          | ''   | '20140331'
 '0.1UF'    | '100V'  | '10%'     | 'C1206'     | 'EMPTY'   | 'CH4108K1202'(!)   = 'End of Design' | 'Comp-Approve'     | ''       | 'CH4108K1202'     |'C1206_H42'| '(SMC1206AW)'                                                        | 'NA'       | '100V'        | '10%'    | 'IO'       | 'CAP CHIP 0.1U 100V(+-10%.X7R.1206)H1.25'                      | 'CHIP1206'     | ''          | ''   | '20140331'
 '0.1UF'    | '250V'  | '10%'     | 'C1206'     | 'X7R'     | 'CH410CK1200'(!)   = 'End of Design' | 'Comp-Approve'     | ''       | 'CH410CK1200'     |'C1206_H66'| '(SMC1206AW)'                                                        | '0.1UF'    | '250V'        | '10%'    | 'DISCRETE' | 'CAP CHIP 0.1U 250V(10%,X7R,1206)H1.6'                         | 'CHIP1206'     | ''          | ''   | '20140331'
 '0.1UF'    | '250V'  | '10%'     | 'C1206'     | 'EMPTY'   | 'CH410CK1200'(!)   = 'End of Design' | 'Comp-Approve'     | ''       | 'CH410CK1200'     |'C1206_H66'| '(SMC1206AW)'                                                        | 'NA'       | '250V'        | '10%'    | 'IO'       | 'CAP CHIP 0.1U 250V(10%,X7R,1206)H1.6'                         | 'CHIP1206'     | ''          | ''   | '20140331'
 '0.015UF'  | '50V'   | '10%'     | 'C0402'     | 'X7R'     | 'CH3156K1B00'(!)   = 'End of Design' | 'Comp-Approve'     | ''       | 'CH3156K1B00'     |'C0402'| '(C0402-0201)'                                                       | '0.015UF'  | '50V'         | '10%'    | 'DISCRETE' | 'CAP CHIP 0.015U 50V(+-10%,X7R,0402)'                          | 'CHIP0402'     | ''          | ''   | '20140331'
 '0.015UF'  | '50V'   | '10%'     | 'C0402'     | 'EMPTY'   | 'CH3156K1B00'(!)   = 'End of Design' | 'Comp-Approve'     | ''       | 'CH3156K1B00'     |'C0402'| '(C0402-0201)'                                                       | 'NA'       | '50V'         | '10%'    | 'IO'       | 'CAP CHIP 0.015U 50V(+-10%,X7R,0402)'                          | 'CHIP0402'     | ''          | ''   | '20140331'
 '22UF'     | '16V'   | '10%'     | 'C1206'     | 'X6S'     | 'CH6223KE200'(!)   = 'End of Design' | 'Comp-Approve'     | ''       | 'CH6223KE200'     |'C1206_H66'| '(SMC1206AW)'                                                        | '22UF'     | '16V'         | '10%'    | 'DISCRETE' | 'CAP CHIP 22UF 16V(+-10%,X6S,1206)'                            | 'CHIP1206'     | ''          | ''   | '20140401'
 '22UF'     | '16V'   | '10%'     | 'C1206'     | 'EMPTY'   | 'CH6223KE200'(!)   = 'End of Design' | 'Comp-Approve'     | ''       | 'CH6223KE200'     |'C1206_H66'| '(SMC1206AW)'                                                        | 'NA'       | '16V'         | '10%'    | 'IO'       | 'CAP CHIP 22UF 16V(+-10%,X6S,1206)'                            | 'CHIP1206'     | ''          | ''   | '20140401'
 '10UF'     | '6.3V'  | '20%'     | 'C0603'     | 'X6S'     | 'CH6101ME900'(!)   = 'End of Design' | 'Comp-Approve'     | ''       | 'CH6101ME900'     |'C0603'| '(SMC0603AW)'                                                        | '10UF'     | '6.3V'        | '20%'    | 'DISCRETE' | 'CAP CHIP 10U 6.3V(+-20%,X6S,0603)'                            | 'CHIP0603'     | ''          | ''   | '20140415'
 '10UF'     | '6.3V'  | '20%'     | 'C0603'     | 'EMPTY'   | 'CH6101ME900'(!)   = 'End of Design' | 'Comp-Approve'     | ''       | 'CH6101ME900'     |'C0603'| '(SMC0603AW)'                                                        | 'NA'       | '6.3V'        | '20%'    | 'IO'       | 'CAP CHIP 10U 6.3V(+-20%,X6S,0603)'                            | 'CHIP0603'     | ''          | ''   | '20140415'
 '1000PF'   | '2KV'   | '20%'     | 'C1808'     | 'X7R'     | 'CH210IM1I00'(!)   = 'End of Design' | 'Comp-Release Qty' | ''       | 'CH210IM1I00'     |'C1808_H80'| '(SMC1808AW)'                                                        | '1000PF'   | '2KV'         | '20%'    | 'DISCRETE' | 'CAP CHIP 1000P 2KV(20%,X7R,1808,H2.03)'                       | 'CHIP1808'     | ''          | ''   | '20140418'
 '1000PF'   | '2KV'   | '20%'     | 'C1808'     | 'EMPTY'   | 'CH210IM1I00'(!)   = 'End of Design' | 'Comp-Release Qty' | ''       | 'CH210IM1I00'     |'C1808_H80'| '(SMC1808AW)'                                                        | 'NA'       | '2KV'         | '20%'    | 'IO'       | 'CAP CHIP 1000P 2KV(20%,X7R,1808,H2.03)'                       | 'CHIP1808'     | ''          | ''   | '20140418'
 '33NF'     | '25V'   | '10%'     | 'C0402'     | 'X7R'     | 'CH3334K1B00'(!)   = ''              | ''                 | ''       | 'CH3334K1B00'     |'C0402'| '(C0402_OCTAGONXA,C0402-0201)'                                       | '33NF'     | '25V'         | '10%'    | 'DISCRETE' | 'CAP CHIP 33NF 25V(+-10%,X7R,0402)'                            | 'CHIP0402'     | ''          | ''   | '20140507'
 '33NF'     | '25V'   | '10%'     | 'C0402'     | 'EMPTY'   | 'CH3334K1B00'(!)   = ''              | ''                 | ''       | 'CH3334K1B00'     |'C0402'| '(C0402_OCTAGONXA,C0402-0201)'                                       | 'NA'       | '25V'         | '10%'    | 'IO'       | 'CAP CHIP 33NF 25V(+-10%,X7R,0402)'                            | 'CHIP0402'     | ''          | ''   | '20140507'
 '0.1UF'    | '6.3V'  | '10%'     | 'C0201'     | 'X6S'     | 'CH4101KEE01'(!)   = ''              | ''                 | ''       | 'CH4101KEE01'     |'C0201'| '(SMC0201AW)'                                                        | '0.1UF'    | '6.3V'        | '10%'    | 'DISCRETE' | 'CAP CHIP 0.1UF 6.3V(10%,X6S,0201,H0.3)'                       | 'CHIP0201'     | ''          | ''   | '20140508'
 '0.1UF'    | '6.3V'  | '10%'     | 'C0201'     | 'EMPTY'   | 'CH4101KEE01'(!)   = ''              | ''                 | ''       | 'CH4101KEE01'     |'C0201'| '(SMC0201AW)'                                                        | 'NA'       | '6.3V'        | '10%'    | 'IO'       | 'CAP CHIP 0.1UF 6.3V(10%,X6S,0201,H0.3)'                       | 'CHIP0201'     | ''          | ''   | '20140508'
 '0.1UF'    | '16V'   | '10%'     | 'C0201'     | 'X6S'     | 'CH4103KEE01'(!)   = ''              | ''                 | ''       | 'CH4103KEE01'     |'C0201'| '(SMC0201AW)'                                                        | '0.1UF'    | '16V'         | '10%'    | 'DISCRETE' | 'CAP CHIP 0.1UF 16V(+-10%,X6S,0201)'                           | 'CHIP0201'     | ''          | ''   | '20140508'
 '0.1UF'    | '16V'   | '10%'     | 'C0201'     | 'EMPTY'   | 'CH4103KEE01'(!)   = ''              | ''                 | ''       | 'CH4103KEE01'     |'C0201'| '(SMC0201AW)'                                                        | 'NA'       | '16V'         | '10%'    | 'IO'       | 'CAP CHIP 0.1UF 16V(+-10%,X6S,0201)'                           | 'CHIP0201'     | ''          | ''   | '20140508'
 '3300PF'   | '16V'   | '10%'     | 'C0201'     | 'X7R'     | 'CH2333K1E00'(!)   = ''              | ''                 | ''       | 'CH2333K1E00'     |'C0201'| '(C0201_HOME-PLATE_H22)'                                             | '3300PF'   | '16V'         | '10%'    | 'DISCRETE' | 'CAP CHIP 3300P 16V(+-10%,X7R,0201)'                           | 'CHIP0201'     | ''          | ''   | '20140707'
 '3300PF'   | '16V'   | '10%'     | 'C0201'     | 'EMPTY'   | 'CH2333K1E00'(!)   = ''              | ''                 | ''       | 'CH2333K1E00'     |'C0201'| '(C0201_HOME-PLATE_H22)'                                             | 'NA'       | '16V'         | '10%'    | 'IO'       | 'CAP CHIP 3300P 16V(+-10%,X7R,0201)'                           | 'CHIP0201'     | ''          | ''   | '20140707'
 '6800PF'   | '10V'   | '10%'     | 'C0201'     | 'X7R'     | 'CH2682K1E02'(!)   = ''              | ''                 | ''       | 'CH2682K1E02'     |'C0201'| '(SMC0201AW)'                                                        | '6800PF'   | '10V'         | '10%'    | 'DISCRETE' | 'CAP CHIP 6800PF 10V(10%,X7R,0201)'                            | 'CHIP0201'     | ''          | ''   | '20140707'
 '6800PF'   | '10V'   | '10%'     | 'C0201'     | 'EMPTY'   | 'CH2682K1E02'(!)   = ''              | ''                 | ''       | 'CH2682K1E02'     |'C0201'| '(SMC0201AW)'                                                        | 'NA'       | '10V'         | '10%'    | 'IO'       | 'CAP CHIP 6800PF 10V(10%,X7R,0201)'                            | 'CHIP0201'     | ''          | ''   | '20140707'
 '100PF'    | '25V'   | '5%'      | 'C0201'     | 'COG'     | 'CH1104J0E07'(!)   = ''              | ''                 | ''       | 'CH1104J0E07'     |'C0201'| '(SMC0201AW)'                                                        | '100PF'    | '25V'         | '5%'     | 'DISCRETE' | 'CAP CHIP 100P 25V(+-5%,COG,0201)'                             | 'CHIP0201'     | ''          | ''   | '20140707'
 '100PF'    | '25V'   | '5%'      | 'C0201'     | 'EMPTY'   | 'CH1104J0E07'(!)   = ''              | ''                 | ''       | 'CH1104J0E07'     |'C0201'| '(SMC0201AW)'                                                        | 'NA'       | '25V'         | '5%'     | 'IO'       | 'CAP CHIP 100P 25V(+-5%,COG,0201)'                             | 'CHIP0201'     | ''          | ''   | '20140707'
 '330PF'    | '25V'   | '5%'      | 'C0201'     | 'X7R'     | 'CH1334J1E00'(!)   = ''              | ''                 | ''       | 'CH1334J1E00'     |'C0201'| '(SMC0201AW)'                                                        | '330PF'    | '25V'         | '5%'     | 'DISCRETE' | 'CAP CHIP 330P 25V(+-5%,X7R,0201)'                             | 'CHIP0201'     | ''          | ''   | '20140707'
 '330PF'    | '25V'   | '5%'      | 'C0201'     | 'EMPTY'   | 'CH1334J1E00'(!)   = ''              | ''                 | ''       | 'CH1334J1E00'     |'C0201'| '(SMC0201AW)'                                                        | 'NA'       | '25V'         | '5%'     | 'IO'       | 'CAP CHIP 330P 25V(+-5%,X7R,0201)'                             | 'CHIP0201'     | ''          | ''   | '20140707'
 '22UF'     | '10V'   | '10%'     | 'C1206'     | 'X7R'     | 'CH6222K1200'(!)   = 'End of Design' | 'Comp-Approve'     | ''       | 'CH6222K1200'     |'C1206_H76'| '(SMC1206AW)'                                                        | '22UF'     | '10V'         | '10%'    | 'DISCRETE' | 'CAP CHIP 22U 10V(+-10%. X7R.1206)H1.6'                        | 'CHIP1206'     | ''          | ''   | '20140711'
 '22UF'     | '10V'   | '10%'     | 'C1206'     | 'EMPTY'   | 'CH6222K1200'(!)   = 'End of Design' | 'Comp-Approve'     | ''       | 'CH6222K1200'     |'C1206_H76'| '(SMC1206AW)'                                                        | 'NA'       | '10V'         | '10%'    | 'IO'       | 'CAP CHIP 22U 10V(+-10%. X7R.1206)H1.6'                        | 'CHIP1206'     | ''          | ''   | '20140711'
 '22UF'     | '6.3V'  | '20%'     | 'C0805'     | 'X6S'     | 'CH6221MEA02'(!)   = ''              | ''                 | 'SELASS' | 'CH6221MEA02'     |'C0805_H61'| '(SMC0805AW)'                                                        | '22UF'     | '6.3V'        | '20%'    | 'DISCRETE' | 'CAP CHIP 22U 6.3V(+-20%,X6S,0805)SELASS'                      | 'CHIP0805'     | ''          | ''   | '20140714'
 '22UF'     | '6.3V'  | '20%'     | 'C0805'     | 'EMPTY'   | 'CH6221MEA02'(!)   = ''              | ''                 | 'SELASS' | 'CH6221MEA02'     |'C0805_H61'| '(SMC0805AW)'                                                        | 'NA'       | '6.3V'        | '20%'    | 'IO'       | 'CAP CHIP 22U 6.3V(+-20%,X6S,0805)SELASS'                      | 'CHIP0805'     | ''          | ''   | '20140714'
 '1000PF'   | '2000V' | '10%'     | 'THLF'      | 'MEF'     | 'CD2100FKD00'(!)   = ''              | ''                 | ''       | 'CD2100FKD00'     |'EC591_R158X709_394'| '(EC591_R158X709_394)'                                               | '1000PF'   | '2000V'       | '10%'    | 'DISCRETE' | 'CAP MYLAR DIP 1000P 2000V(+-10%,P15)'                         | 'DIP'          | ''          | ''   | '20140725'
 '1000PF'   | '2000V' | '10%'     | 'THLF'      | 'EMPTY'   | 'CD2100FKD00'(!)   = ''              | ''                 | ''       | 'CD2100FKD00'     |'EC591_R158X709_394'| '(EC591_R158X709_394)'                                               | 'NA'       | '2000V'       | '10%'    | 'IO'       | 'CAP MYLAR DIP 1000P 2000V(+-10%,P15)'                         | 'DIP'          | ''          | ''   | '20140725'
 '1PF'      | '50V'   | '0.05P'   | 'C0402'     | 'COG'     | 'CH-106T0B00'(!)   = ''              | ''                 | ''       | 'CH-106T0B00'     |'C0402'| '(C0402-0201)'                                                       | '1PF'      | '50V'         | '0.05P'  | 'DISCRETE' | 'CAP CHIP 1P 50V(+-0.05P,COG,0402)'                            | 'CHIP0402'     | ''          | ''   | '20140812'
 '1PF'      | '50V'   | '0.05P'   | 'C0402'     | 'EMPTY'   | 'CH-106T0B00'(!)   = ''              | ''                 | ''       | 'CH-106T0B00'     |'C0402'| '(C0402-0201)'                                                       | 'NA'       | '50V'         | '0.05P'  | 'IO'       | 'CAP CHIP 1P 50V(+-0.05P,COG,0402)'                            | 'CHIP0402'     | ''          | ''   | '20140812'
 '18NF'     | '100V'  | '10%'     | 'C0603'     | 'X7R'     | 'CH3188K1900'(!)   = ''              | ''                 | ''       | 'CH3188K1900'     |'C0603'| '(SMC0603AW)'                                                        | '18NF'     | '100V'        | '10%'    | 'DISCRETE' | 'CAP CHIP 18NF 100V(+-10%,X7R,0603)'                           | 'CHIP0603'     | ''          | ''   | '20140813'
 '18NF'     | '100V'  | '10%'     | 'C0603'     | 'EMPTY'   | 'CH3188K1900'(!)   = ''              | ''                 | ''       | 'CH3188K1900'     |'C0603'| '(SMC0603AW)'                                                        | 'NA'       | '100V'        | '10%'    | 'IO'       | 'CAP CHIP 18NF 100V(+-10%,X7R,0603)'                           | 'CHIP0603'     | ''          | ''   | '20140813'
 '0.39UF'   | '10V'   | '10%'     | 'C0402'     | 'X5R'     | 'CH4392K9B00'(!)   = 'End of Design' | 'Comp-Release Qty' | ''       | 'CH4392K9B00'     |'C0402'| '(C0402-0201)'                                                       | '0.39UF'   | '10V'         | '10%'    | 'DISCRETE' | 'CAP CHIP 0.39UF 10V(+-10%,X5R,0402)'                          | 'CHIP0402'     | ''          | ''   | '20140813'
 '0.39UF'   | '10V'   | '10%'     | 'C0402'     | 'EMPTY'   | 'CH4392K9B00'(!)   = 'End of Design' | 'Comp-Release Qty' | ''       | 'CH4392K9B00'     |'C0402'| '(C0402-0201)'                                                       | 'NA'       | '10V'         | '10%'    | 'IO'       | 'CAP CHIP 0.39UF 10V(+-10%,X5R,0402)'                          | 'CHIP0402'     | ''          | ''   | '20140813'
 '0.47UF'   | '50V'   | '10%'     | 'C0603'     | 'X5R'     | 'CH4476K9901'(!)   = 'End of Design' | 'Comp-Approve'     | ''       | 'CH4476K9901'     |'C0603'| '(SMC0603AW)'                                                        | '0.47UF'   | '50V'         | '10%'    | 'DISCRETE' | 'CAP CHIP 0.47UF 50V(10%,X5R,0603)'                            | 'CHIP0603'     | ''          | ''   | '20140817'
 '0.47UF'   | '50V'   | '10%'     | 'C0603'     | 'EMPTY'   | 'CH4476K9901'(!)   = 'End of Design' | 'Comp-Approve'     | ''       | 'CH4476K9901'     |'C0603'| '(SMC0603AW)'                                                        | 'NA'       | '50V'         | '10%'    | 'IO'       | 'CAP CHIP 0.47UF 50V(10%,X5R,0603)'                            | 'CHIP0603'     | ''          | ''   | '20140817'
 '0.01UF'   | '25V'   | '5%'      | 'C0402'     | 'X7R'     | 'CH3104J1B00'(!)   = ''              | ''                 | ''       | 'CH3104J1B00'     |'C0402'| '(C0402-0201)'                                                       | '0.01UF'   | '25V'         | '5%'     | 'DISCRETE' | 'CAP CHIP 0.01U 25V (+-5%,X7R,0402)'                           | 'CHIP0402'     | ''          | ''   | '20140819'
 '0.01UF'   | '25V'   | '5%'      | 'C0402'     | 'EMPTY'   | 'CH3104J1B00'(!)   = ''              | ''                 | ''       | 'CH3104J1B00'     |'C0402'| '(C0402-0201)'                                                       | 'NA'       | '25V'         | '5%'     | 'IO'       | 'CAP CHIP 0.01U 25V (+-5%,X7R,0402)'                           | 'CHIP0402'     | ''          | ''   | '20140819'
 '22UF'     | '25V'   | '20%'     | 'C0805'     | 'X5R'     | 'CH6224M9A00'(!)   = ''              | ''                 | ''       | 'CH6224M9A00'     |'C0805_H61'| '(SMC0805AW)'                                                        | '22UF'     | '25V'         | '20%'    | 'DISCRETE' | 'CAP CHIP 22U 25V(+-20%,X5R,0805)'                             | 'CHIP0805'     | ''          | ''   | '20140819'
 '22UF'     | '25V'   | '20%'     | 'C0805'     | 'EMPTY'   | 'CH6224M9A00'(!)   = ''              | ''                 | ''       | 'CH6224M9A00'     |'C0805_H61'| '(SMC0805AW)'                                                        | 'NA'       | '25V'         | '20%'    | 'IO'       | 'CAP CHIP 22U 25V(+-20%,X5R,0805)'                             | 'CHIP0805'     | ''          | ''   | '20140819'
 '100UF'    | '10V'   | '20%'     | 'C1206'     | 'X5R'     | 'CH7102M9201'(!)   = 'End of Design' | 'Comp-Approve'     | ''       | 'CH7102M9201'     |'C1206_H76'| '(SMC1206AW)'                                                        | '100UF'    | '10V'         | '20%'    | 'DISCRETE' | 'CAP CHIP 100U 10V(+-20%,X5R,3216)'                            | 'CHIP1206'     | ''          | ''   | '20140819'
 '100UF'    | '10V'   | '20%'     | 'C1206'     | 'EMPTY'   | 'CH7102M9201'(!)   = 'End of Design' | 'Comp-Approve'     | ''       | 'CH7102M9201'     |'C1206_H76'| '(SMC1206AW)'                                                        | 'NA'       | '10V'         | '20%'    | 'IO'       | 'CAP CHIP 100U 10V(+-20%,X5R,3216)'                            | 'CHIP1206'     | ''          | ''   | '20140819'
 '10UF'     | '35V'   | '10%'     | 'C1206'     | 'X7R'     | 'CH6105K1200'(!)   = 'End of Design' | 'Comp-Approve'     | ''       | 'CH6105K1200'     |'C1206_H76'| '(SMC1206AW)'                                                        | '10UF'     | '35V'         | '10%'    | 'DISCRETE' | 'CAP CHIP 10U 35V(+-10%.X7R.1206)H1.6'                         | 'CHIP1206'     | ''          | ''   | '20140826'
 '10UF'     | '35V'   | '10%'     | 'C1206'     | 'EMPTY'   | 'CH6105K1200'(!)   = 'End of Design' | 'Comp-Approve'     | ''       | 'CH6105K1200'     |'C1206_H76'| '(SMC1206AW)'                                                        | 'NA'       | '35V'         | '10%'    | 'IO'       | 'CAP CHIP 10U 35V(+-10%.X7R.1206)H1.6'                         | 'CHIP1206'     | ''          | ''   | '20140826'
 '1UF'      | '16V'   | '10%'     | 'C0402'     | 'X6S'     | 'CH5103KEB01'(!)   = ''              | ''                 | ''       | 'CH5103KEB01'     |'C0402'| '(C0402_OCTAGONXA,C0402-0201)'                                       | '1UF'      | '16V'         | '10%'    | 'DISCRETE' | 'CAP CHIP 1UF 16V(10%,X6S,0402)'                               | 'CHIP0402'     | ''          | ''   | '20140828'
 '1UF'      | '16V'   | '10%'     | 'C0402'     | 'EMPTY'   | 'CH5103KEB01'(!)   = ''              | ''                 | ''       | 'CH5103KEB01'     |'C0402'| '(C0402_OCTAGONXA,C0402-0201)'                                       | 'NA'       | '16V'         | '10%'    | 'IO'       | 'CAP CHIP 1UF 16V(10%,X6S,0402)'                               | 'CHIP0402'     | ''          | ''   | '20140828'
 '10UF'     | '6.3V'  | '10%'     | 'C0805'     | 'X6S'     | 'CH6101KEA00'(!)   = 'End of Design' | 'Comp-Approve'     | ''       | 'CH6101KEA00'     |'C0805_H61'| '(SMC0805AW)'                                                        | '10UF'     | '6.3V'        | '10%'    | 'DISCRETE' | 'CAP CHIP 10UF,6.3V (+-10%,X6S,0805)'                          | 'CHIP0805'     | ''          | ''   | '20140829'
 '10UF'     | '6.3V'  | '10%'     | 'C0805'     | 'EMPTY'   | 'CH6101KEA00'(!)   = 'End of Design' | 'Comp-Approve'     | ''       | 'CH6101KEA00'     |'C0805_H61'| '(SMC0805AW)'                                                        | 'NA'       | '6.3V'        | '10%'    | 'IO'       | 'CAP CHIP 10UF,6.3V (+-10%,X6S,0805)'                          | 'CHIP0805'     | ''          | ''   | '20140829'
 '1UF'      | '6.3V'  | '10%'     | 'C0402'     | 'X6S'     | 'CH5101KEB00'(!)   = 'End of Design' | 'Comp-Approve'     | ''       | 'CH5101KEB00'     |'C0402'| '(C0402-0201)'                                                       | '1UF'      | '6.3V'        | '10%'    | 'DISCRETE' | 'CAP CHIP 1U 6.3V(+-10%,X6S,0402)'                             | 'CHIP0402'     | ''          | ''   | '20140829'
 '1UF'      | '6.3V'  | '10%'     | 'C0402'     | 'EMPTY'   | 'CH5101KEB00'(!)   = 'End of Design' | 'Comp-Approve'     | ''       | 'CH5101KEB00'     |'C0402'| '(C0402-0201)'                                                       | 'NA'       | '6.3V'        | '10%'    | 'IO'       | 'CAP CHIP 1U 6.3V(+-10%,X6S,0402)'                             | 'CHIP0402'     | ''          | ''   | '20140829'
 '100UF'    | '6.3V'  | '20%'     | 'C1206'     | 'X6T'     | 'CH7101MH200'(!)   = 'End of Design' | 'Comp-Approve'     | ''       | 'CH7101MH200'     |'C1206_H66'| '(SMC1206AW)'                                                        | '100UF'    | '6.3V'        | '20%'    | 'DISCRETE' | 'CAP CHIP 100U 6.3V(+-20%,X6T,1206)H1.6'                       | 'CHIP1206'     | ''          | ''   | '20140829'
 '100UF'    | '6.3V'  | '20%'     | 'C1206'     | 'EMPTY'   | 'CH7101MH200'(!)   = 'End of Design' | 'Comp-Approve'     | ''       | 'CH7101MH200'     |'C1206_H66'| '(SMC1206AW)'                                                        | 'NA'       | '6.3V'        | '20%'    | 'IO'       | 'CAP CHIP 100U 6.3V(+-20%,X6T,1206)H1.6'                       | 'CHIP1206'     | ''          | ''   | '20140829'
 '4.7UF'    | '25V'   | '10%'     | 'C0805'     | 'X7R'     | 'TH5474K1A00'(!)   = ''              | ''                 | 'EMSSEL' | 'TH5474K1A00'     |'C0805_H61'| '(SMC0805AW)'                                                        | '4.7UF'    | '25V'         | '10%'    | 'DISCRETE' | 'CAP CHIP 4.7U 25V(+-10%,X7R,0805)EMS SEL'                     | 'CHIP0805'     | ''          | ''   | '20140912'
 '4.7UF'    | '25V'   | '10%'     | 'C0805'     | 'EMPTY'   | 'TH5474K1A00'(!)   = ''              | ''                 | 'EMSSEL' | 'TH5474K1A00'     |'C0805_H61'| '(SMC0805AW)'                                                        | 'NA'       | '25V'         | '10%'    | 'IO'       | 'CAP CHIP 4.7U 25V(+-10%,X7R,0805)EMS SEL'                     | 'CHIP0805'     | ''          | ''   | '20140912'
 '1000PF'   | '200V'  | '10%'     | 'C1206'     | 'X7R'     | 'CH210CK1200'(!)   = ''              | ''                 | ''       | 'CH210CK1200'     |'C1206_H42'| '(SMC1206AW)'                                                        | '1000PF'   | '200V'        | '10%'    | 'DISCRETE' | 'CAP CHIP 1000PF 200V(+-10%,X7R,1206)H0.8'                     | 'CHIP1206'     | ''          | ''   | '20140930'
 '1000PF'   | '200V'  | '10%'     | 'C1206'     | 'EMPTY'   | 'CH210CK1200'(!)   = ''              | ''                 | ''       | 'CH210CK1200'     |'C1206_H42'| '(SMC1206AW)'                                                        | 'NA'       | '200V'        | '10%'    | 'IO'       | 'CAP CHIP 1000PF 200V(+-10%,X7R,1206)H0.8'                     | 'CHIP1206'     | ''          | ''   | '20140930'
 '0.47UF'   | '10V'   | '10%'     | 'C0402'     | 'X7R'     | 'CH4472K1B00'(!)   = 'End of Design' | 'Comp-Approve'     | ''       | 'CH4472K1B00'     |'C0402'| '(C0402_OCTAGONXA,C0402-0201)'                                       | '0.47UF'   | '10V'         | '10%'    | 'DISCRETE' | 'CAP CHIP 0.47UF 10V(+-10%,X7R,0402)'                          | 'CHIP0402'     | ''          | ''   | '20141003'
 '0.47UF'   | '10V'   | '10%'     | 'C0402'     | 'EMPTY'   | 'CH4472K1B00'(!)   = 'End of Design' | 'Comp-Approve'     | ''       | 'CH4472K1B00'     |'C0402'| '(C0402_OCTAGONXA,C0402-0201)'                                       | 'NA'       | '10V'         | '10%'    | 'IO'       | 'CAP CHIP 0.47UF 10V(+-10%,X7R,0402)'                          | 'CHIP0402'     | ''          | ''   | '20141003'
 '0.39UF'   | '10V'   | '10%'     | 'C0603'     | 'X7R'     | 'CH4392K1900'(!)   = 'End of Design' | 'P/N Release'      | ''       | 'CH4392K1900'     |'C0603'| '(SMC0603AW)'                                                        | '0.39UF'   | '10V'         | '10%'    | 'DISCRETE' | 'CAP CHIP 0.39U 10V(+-10%,X7R,0603)'                           | 'CHIP0603'     | ''          | ''   | '20141016'
 '0.39UF'   | '10V'   | '10%'     | 'C0603'     | 'EMPTY'   | 'CH4392K1900'(!)   = 'End of Design' | 'P/N Release'      | ''       | 'CH4392K1900'     |'C0603'| '(SMC0603AW)'                                                        | 'NA'       | '10V'         | '10%'    | 'IO'       | 'CAP CHIP 0.39U 10V(+-10%,X7R,0603)'                           | 'CHIP0603'     | ''          | ''   | '20141016'
 '22UF'     | '35V'   | '20%'     | 'C0805'     | 'X5R'     | 'CH6225M9A00'(!)   = 'End of Design' | 'Comp-Approve'     | ''       | 'CH6225M9A00'     |'C0805_H61'| '(SMC0805AW)'                                                        | '22UF'     | '35V'         | '20%'    | 'DISCRETE' | 'CAP CHIP 22UF 35V(+-20%,X5R,0805)'                            | 'CHIP0805'     | ''          | ''   | '20141016'
 '22UF'     | '35V'   | '20%'     | 'C0805'     | 'EMPTY'   | 'CH6225M9A00'(!)   = 'End of Design' | 'Comp-Approve'     | ''       | 'CH6225M9A00'     |'C0805_H61'| '(SMC0805AW)'                                                        | 'NA'       | '35V'         | '20%'    | 'IO'       | 'CAP CHIP 22UF 35V(+-20%,X5R,0805)'                            | 'CHIP0805'     | ''          | ''   | '20141016'
 '220UF'    | '4V'    | '20%'     | 'C1206'     | 'X5R'     | 'CH722KM9200'(!)   = 'End of Design' | 'Comp-Approve'     | ''       | 'CH722KM9200'     |'C1206_H76'| '(SMC1206AW)'                                                        | '220UF'    | '4V'          | '20%'    | 'DISCRETE' | 'CAP CHIP 220UF 4V(+-20%,X5R,1206)'                            | 'CHIP1206'     | ''          | ''   | '20141103'
 '220UF'    | '4V'    | '20%'     | 'C1206'     | 'EMPTY'   | 'CH722KM9200'(!)   = 'End of Design' | 'Comp-Approve'     | ''       | 'CH722KM9200'     |'C1206_H76'| '(SMC1206AW)'                                                        | 'NA'       | '4V'          | '20%'    | 'IO'       | 'CAP CHIP 220UF 4V(+-20%,X5R,1206)'                            | 'CHIP1206'     | ''          | ''   | '20141103'
 '22UF'     | '10V'   | '10%'     | 'C0805'     | 'X6S'     | 'CH6222KEA00'(!)   = 'End of Design' | 'Comp-Release Qty' | ''       | 'CH6222KEA00'     |'C0805_H61'| '(SMC0805AW)'                                                        | '22UF'     | '10V'         | '10%'    | 'DISCRETE' | 'CAP CHIP 22U 10V(+-10%,X6S,0805)'                             | 'CHIP0805'     | ''          | ''   | '20141127'
 '22UF'     | '10V'   | '10%'     | 'C0805'     | 'EMPTY'   | 'CH6222KEA00'(!)   = 'End of Design' | 'Comp-Release Qty' | ''       | 'CH6222KEA00'     |'C0805_H61'| '(SMC0805AW)'                                                        | 'NA'       | '10V'         | '10%'    | 'IO'       | 'CAP CHIP 22U 10V(+-10%,X6S,0805)'                             | 'CHIP0805'     | ''          | ''   | '20141127'
 '22UF'     | '10V'   | '20%'     | 'C0805'     | 'X7S'     | 'CH6222M1A00'(!)   = 'End of Design' | 'Comp-Release Qty' | ''       | 'CH6222M1A00'     |'C0805_H61'| '(SMC0805AW)'                                                        | '22UF'     | '10V'         | '20%'    | 'DISCRETE' | 'CAP CHIP 22U 10V(+-20%,X7S,0805)'                             | 'CHIP0805'     | ''          | ''   | '20141127'
 '22UF'     | '10V'   | '20%'     | 'C0805'     | 'EMPTY'   | 'CH6222M1A00'(!)   = 'End of Design' | 'Comp-Release Qty' | ''       | 'CH6222M1A00'     |'C0805_H61'| '(SMC0805AW)'                                                        | 'NA'       | '10V'         | '20%'    | 'IO'       | 'CAP CHIP 22U 10V(+-20%,X7S,0805)'                             | 'CHIP0805'     | ''          | ''   | '20141127'
 '4.7UF'    | '25V'   | '10%'     | 'C0603'     | 'X6S'     | 'CH-474KE900'(!)   = ''              | 'End of Life'      | ''       | 'CH-474KE900'     |'C0603_EOL'| '(SMC0603AW)'                                                        | '4.7UF'    | '25V'         | '10%'    | 'DISCRETE' | 'CAP CHIP 4.7UF 25V(+-10%,X6S,0603)'                           | 'CHIP0603'     | ''          | ''   | '20141212'
 '4.7UF'    | '25V'   | '10%'     | 'C0603'     | 'EMPTY'   | 'CH-474KE900'(!)   = ''              | 'End of Life'      | ''       | 'CH-474KE900'     |'C0603_EOL'| '(SMC0603AW)'                                                        | 'NA'       | '25V'         | '10%'    | 'IO'       | 'CAP CHIP 4.7UF 25V(+-10%,X6S,0603)'                           | 'CHIP0603'     | ''          | ''   | '20141212'
 '2PF'      | '50V'   | '0.05PF'  | 'C0402'     | 'C0G'     | 'CH-206T0B00'(!)   = ''              | ''                 | ''       | 'CH-206T0B00'     |'C0402'| '(C0402-0201)'                                                       | '2PF'      | '50V'         | '0.05PF' | 'DISCRETE' | 'CAP CHIP 2P 50V(+-0.05PF,C0G,0402)'                           | 'CHIP0402'     | ''          | ''   | '20141225'
 '2PF'      | '50V'   | '0.05PF'  | 'C0402'     | 'EMPTY'   | 'CH-206T0B00'(!)   = ''              | ''                 | ''       | 'CH-206T0B00'     |'C0402'| '(C0402-0201)'                                                       | 'NA'       | '50V'         | '0.05PF' | 'IO'       | 'CAP CHIP 2P 50V(+-0.05PF,C0G,0402)'                           | 'CHIP0402'     | ''          | ''   | '20141225'
 '330PF'    | '50V'   | '10%'     | 'C0402'     | 'X7R'     | 'CH13306KB11'(!)   = ''              | 'End of Life'      | ''       | 'CH13306KB11'     |'C0402_EOL'| '(C0402-0201)'                                                       | '330PF'    | '50V'         | '10%'    | 'DISCRETE' | 'CAP CHIP 330P 50V(+-10%.X7R.0402)'                            | 'CHIP0402'     | ''          | ''   | '20140116'
 '330PF'    | '50V'   | '10%'     | 'C0402'     | 'EMPTY'   | 'CH13306KB11'(!)   = ''              | 'End of Life'      | ''       | 'CH13306KB11'     |'C0402_EOL'| '(C0402-0201)'                                                       | 'NA'       | '50V'         | '10%'    | 'IO'       | 'CAP CHIP 330P 50V(+-10%.X7R.0402)'                            | 'CHIP0402'     | ''          | ''   | '20140116'
 '10UF'     | '16V'   | '20%'     | 'C0603'     | 'X6S'     | 'CH6103ME902'(!)   = ''              | ''                 | ''       | 'CH6103ME902'     |'C0603'| '(SMC0603AW)'                                                        | '10UF'     | '16V'         | '20%'    | 'DISCRETE' | 'CAP CHIP 10U 16V(+-20%,X6S,0603)'                             | 'CHIP0603'     | ''          | ''   | '20140116'
 '10UF'     | '16V'   | '20%'     | 'C0603'     | 'EMPTY'   | 'CH6103ME902'(!)   = ''              | ''                 | ''       | 'CH6103ME902'     |'C0603'| '(SMC0603AW)'                                                        | 'NA'       | '16V'         | '20%'    | 'IO'       | 'CAP CHIP 10U 16V(+-20%,X6S,0603)'                             | 'CHIP0603'     | ''          | ''   | '20140116'
 '0.068UF'  | '50V'   | '10%'     | 'C0603'     | 'X7R'     | 'CH3686K1901'(!)   = 'End of Design' | 'Comp-Approve'     | ''       | 'CH3686K1901'     |'C0603'| '(SMC0603AW)'                                                        | '0.068UF'  | '50V'         | '10%'    | 'DISCRETE' | 'CAP CHIP 0.068UF 50V(10%,X7R,0603)'                           | 'CHIP0603'     | ''          | ''   | '20140119'
 '0.068UF'  | '50V'   | '10%'     | 'C0603'     | 'EMPTY'   | 'CH3686K1901'(!)   = 'End of Design' | 'Comp-Approve'     | ''       | 'CH3686K1901'     |'C0603'| '(SMC0603AW)'                                                        | 'NA'       | '50V'         | '10%'    | 'IO'       | 'CAP CHIP 0.068UF 50V(10%,X7R,0603)'                           | 'CHIP0603'     | ''          | ''   | '20140119'
 '1UF'      | '6.3V'  | '10%'     | '0402'      | 'X5R'     | 'CH5101K9B01'(!)   = 'End of Design' | 'Comp-Release Qty' | ''       | 'CH5101K9B01'     |'C0402'| '(C0402_OCTAGONXA,C0402-0201)'                                       | '1UF'      | '6.3V'        | '10%'    | 'DISCRETE' | 'CAP CHIP 1U 6.3V(+-10%,X5R,0402)'                             | 'CHIP0402'     | ''          | ''   | '20150209'
 '1UF'      | '6.3V'  | '10%'     | '0402'      | 'EMPTY'   | 'CH5101K9B01'(!)   = 'End of Design' | 'Comp-Release Qty' | ''       | 'CH5101K9B01'     |'C0402'| '(C0402_OCTAGONXA,C0402-0201)'                                       | 'NA'       | '6.3V'        | '10%'    | 'IO'       | 'CAP CHIP 1U 6.3V(+-10%,X5R,0402)'                             | 'CHIP0402'     | ''          | ''   | '20150209'
 '10UF'     | '6.3V'  | '20%'     | '0603'      | 'X7R'     | 'CH6101M1904'(!)   = 'End of Design' | 'Comp-Approve'     | ''       | 'CH6101M1904'     |'C0603'| '(SMC0603AW)'                                                        | '10UF'     | '6.3V'        | '20%'    | 'DISCRETE' | 'CAP CHIP 10U.6.3V(+-20%.X7R.0603)'                            | 'CHIP0603'     | ''          | ''   | '20100917'
 '10UF'     | '6.3V'  | '20%'     | '0603'      | 'EMPTY'   | 'CH6101M1904'(!)   = 'End of Design' | 'Comp-Approve'     | ''       | 'CH6101M1904'     |'C0603'| '(SMC0603AW)'                                                        | 'NA'       | '6.3V'        | '20%'    | 'IO'       | 'CAP CHIP 10U.6.3V(+-20%.X7R.0603)'                            | 'CHIP0603'     | ''          | ''   | '20100917'
 '4.7UF'    | '10V'   | '10%'     | '0402'      | 'X5R'     | 'CH5472K9B00'(!)   = ''              | ''                 | ''       | 'CH5472K9B00'     |'C0402'| '(C0402-0201)'                                                       | '4.7UF'    | '10V'         | '10%'    | 'DISCRETE' | 'CAP CHIP 4.7U 10V(+-10%,X5R,0402)'                            | 'CHIP0402'     | ''          | ''   | '20150226'
 '4.7UF'    | '10V'   | '10%'     | '0402'      | 'EMPTY'   | 'CH5472K9B00'(!)   = ''              | ''                 | ''       | 'CH5472K9B00'     |'C0402'| '(C0402-0201)'                                                       | 'NA'       | '10V'         | '10%'    | 'IO'       | 'CAP CHIP 4.7U 10V(+-10%,X5R,0402)'                            | 'CHIP0402'     | ''          | ''   | '20150226'
 '22UF'     | '16V'   | '10%'     | '1206'      | 'X5R'     | 'CH6223K9201'(!)   = 'End of Design' | 'Comp-Approve'     | ''       | 'CH6223K9201'     |'C1206_H76'| '(SMC1206AW)'                                                        | '22UF'     | '16V'         | '10%'    | 'DISCRETE' | 'CAP CHIP 22U 16V(+-10%,X5R,1206)H1.6'                         | 'CHIP1206'     | ''          | ''   | '20150304'
 '22UF'     | '16V'   | '10%'     | '1206'      | 'EMPTY'   | 'CH6223K9201'(!)   = 'End of Design' | 'Comp-Approve'     | ''       | 'CH6223K9201'     |'C1206_H76'| '(SMC1206AW)'                                                        | 'NA'       | '16V'         | '10%'    | 'IO'       | 'CAP CHIP 22U 16V(+-10%,X5R,1206)H1.6'                         | 'CHIP1206'     | ''          | ''   | '20150304'
 '22UF'     | '10V'   | '20%'     | 'C0805'     | 'X6S'     | 'CH6222MEA00'(!)   = ''              | ''                 | ''       | 'CH6222MEA00'     |'C0805_H61'| '(SMC0805AW)'                                                        | '22UF'     | '10V'         | '20%'    | 'DISCRETE' | 'CAP CHIP 22U 10V(+-20%,X6S,0805)'                             | 'CHIP0805'     | ''          | ''   | '20150401'
 '22UF'     | '10V'   | '20%'     | 'C0805'     | 'EMPTY'   | 'CH6222MEA00'(!)   = ''              | ''                 | ''       | 'CH6222MEA00'     |'C0805_H61'| '(SMC0805AW)'                                                        | 'NA'       | '10V'         | '20%'    | 'IO'       | 'CAP CHIP 22U 10V(+-20%,X6S,0805)'                             | 'CHIP0805'     | ''          | ''   | '20150401'
 '1UF'      | '6.3V'  | '10%'     | '0402'      | 'X7R'     | 'CH5101K1B01'(!)   = ''              | ''                 | ''       | 'CH5101K1B01'     |'C0402'| '(C0402_OCTAGONXA,C0402-0201)'                                       | '1UF'      | '6.3V'        | '10%'    | 'DISCRETE' | 'CAP CHIP 1U,6.3V(+-10%,X7R,0402)'                             | 'CHIP0402'     | ''          | ''   | '20150410'
 '1UF'      | '6.3V'  | '10%'     | '0402'      | 'EMPTY'   | 'CH5101K1B01'(!)   = ''              | ''                 | ''       | 'CH5101K1B01'     |'C0402'| '(C0402_OCTAGONXA,C0402-0201)'                                       | 'NA'       | '6.3V'        | '10%'    | 'IO'       | 'CAP CHIP 1U,6.3V(+-10%,X7R,0402)'                             | 'CHIP0402'     | ''          | ''   | '20150410'
 '0.1UF'    | '16V'   | '10%'     | '0402'      | 'X7R'     | 'TMP_QCH4103K1B09'(!) = 'End of Design' | 'Comp-Approve'     | 'SELASS' | 'CH4103K1B09'     |'C0402'| '(C0402_OCTAGONXA,C0402-0201)'                                       | '0.1UF'    | '16V'         | '10%'    | 'DISCRETE' | 'CAP CHIP 0.1U 16V(10%,X7R,0402)SEL-ASS'                       | 'CHIP0402'     | ''          | ''   | '20150413'
 '0.1UF'    | '16V'   | '10%'     | '0402'      | 'EMPTY'   | 'TMP_QCH4103K1B09'(!) = 'End of Design' | 'Comp-Approve'     | 'SELASS' | 'CH4103K1B09'     |'C0402'| '(C0402_OCTAGONXA,C0402-0201)'                                       | 'NA'       | '16V'         | '10%'    | 'IO'       | 'CAP CHIP 0.1U 16V(10%,X7R,0402)SEL-ASS'                       | 'CHIP0402'     | ''          | ''   | '20150413'
 '0.22UF'   | '6.3V'  | '10%'     | '0201'      | 'X5R'     | 'CH4221K9E00'(!)   = ''              | ''                 | ''       | 'CH4221K9E00'     |'C0201'| '(SMC0201AW)'                                                        | '0.22UF'   | '6.3V'        | '10%'    | 'DISCRETE' | 'CAP CHIP 0.22UF 6.3V(+-10%,X5R,0201)'                         | 'CHIP0201'     | ''          | ''   | '20150511'
 '0.22UF'   | '6.3V'  | '10%'     | '0201'      | 'EMPTY'   | 'CH4221K9E00'(!)   = ''              | ''                 | ''       | 'CH4221K9E00'     |'C0201'| '(SMC0201AW)'                                                        | 'NA'       | '6.3V'        | '10%'    | 'IO'       | 'CAP CHIP 0.22UF 6.3V(+-10%,X5R,0201)'                         | 'CHIP0201'     | ''          | ''   | '20150511'
 '100UF'    | '4V'    | '20%'     | 'C0805'     | 'X6S'     | 'CH710KMEA00'(!)   = ''              | ''                 | ''       | 'CH710KMEA00'     |'C0805_H61'| '(SMC0805AW)'                                                        | '100UF'    | '4V'          | '20%'    | 'DISCRETE' | 'CAP CHIP 100U 4V(+-20%,X6S,0805)'                             | 'CHIP0805'     | ''          | ''   | '20150602'
 '100UF'    | '4V'    | '20%'     | 'C0805'     | 'EMPTY'   | 'CH710KMEA00'(!)   = ''              | ''                 | ''       | 'CH710KMEA00'     |'C0805_H61'| '(SMC0805AW)'                                                        | 'NA'       | '4V'          | '20%'    | 'IO'       | 'CAP CHIP 100U 4V(+-20%,X6S,0805)'                             | 'CHIP0805'     | ''          | ''   | '20150602'
 '2.2UF'    | '10V'   | '10%'     | 'C0402'     | 'X6S'     | 'CH5222KEB01'(!)   = ''              | ''                 | ''       | 'CH5222KEB01'     |'C0402'| '(C0402_OCTAGONXA,C0402-0201)'                                       | '2.2UF'    | '10V'         | '10%'    | 'DISCRETE' | 'CAP CHIP 2.2UF 10V(+-10%,X6S,0402)'                           | 'CHIP0402'     | ''          | ''   | '20150612'
 '2.2UF'    | '10V'   | '10%'     | 'C0402'     | 'EMPTY'   | 'CH5222KEB01'(!)   = ''              | ''                 | ''       | 'CH5222KEB01'     |'C0402'| '(C0402_OCTAGONXA,C0402-0201)'                                       | 'NA'       | '10V'         | '10%'    | 'IO'       | 'CAP CHIP 2.2UF 10V(+-10%,X6S,0402)'                           | 'CHIP0402'     | ''          | ''   | '20150612'
 '470PF'    | '50V'   | '5%'      | 'C0402'     | 'NPO'     | 'CH1476J0B04'(!)   = ''              | ''                 | ''       | 'CH1476J0B04'     |'C0402'| '(C0402-0201)'                                                       | '470PF'    | '50V'         | '5%'     | 'DISCRETE' | 'CAP CHIP 470P,50V(+-5%,NPO,0402)MUR'                          | 'CHIP0402'     | ''          | ''   | '20150612'
 '470PF'    | '50V'   | '5%'      | 'C0402'     | 'EMPTY'   | 'CH1476J0B04'(!)   = ''              | ''                 | ''       | 'CH1476J0B04'     |'C0402'| '(C0402-0201)'                                                       | 'NA'       | '50V'         | '5%'     | 'IO'       | 'CAP CHIP 470P,50V(+-5%,NPO,0402)MUR'                          | 'CHIP0402'     | ''          | ''   | '20150612'
 '4700PF'   | '50V'   | '10%'     | 'C0402'     | 'X7R'     | 'CH2476K1B04'(!)   = ''              | ''                 | ''       | 'CH2476K1B04'     |'C0402'| '(C0402-0201)'                                                       | '4700PF'   | '50V'         | '10%'    | 'DISCRETE' | 'CAP CHIP 4700PF 50V(10%,X7R,0402)MUR'                         | 'CHIP0402'     | ''          | ''   | '20150612'
 '4700PF'   | '50V'   | '10%'     | 'C0402'     | 'EMPTY'   | 'CH2476K1B04'(!)   = ''              | ''                 | ''       | 'CH2476K1B04'     |'C0402'| '(C0402-0201)'                                                       | 'NA'       | '50V'         | '10%'    | 'IO'       | 'CAP CHIP 4700PF 50V(10%,X7R,0402)MUR'                         | 'CHIP0402'     | ''          | ''   | '20150612'
 '0.1UF'    | '10V'   | '10%'     | 'C0402'     | 'X7R'     | 'CH4102K1B08'(!)   = 'End of Design' | 'Comp-Approve'     | ''       | 'CH4102K1B08'     |'C0402'| '(C0402-0201)'                                                       | '0.1UF'    | '10V'         | '10%'    | 'DISCRETE' | 'CAP CHIP 0.1U 10V(+-10%,X7R,0402)MUR'                         | 'CHIP0402'     | ''          | ''   | '20150612'
 '0.1UF'    | '10V'   | '10%'     | 'C0402'     | 'EMPTY'   | 'CH4102K1B08'(!)   = 'End of Design' | 'Comp-Approve'     | ''       | 'CH4102K1B08'     |'C0402'| '(C0402-0201)'                                                       | 'NA'       | '10V'         | '10%'    | 'IO'       | 'CAP CHIP 0.1U 10V(+-10%,X7R,0402)MUR'                         | 'CHIP0402'     | ''          | ''   | '20150612'
 '0.022UF'  | '16V'   | '10%'     | 'C0402'     | 'X7R'     | 'CH3223K1B11'(!)   = ''              | ''                 | ''       | 'CH3223K1B11'     |'C0402'| '(C0402-0201)'                                                       | '0.022UF'  | '16V'         | '10%'    | 'DISCRETE' | 'CAP CHIP 0.022U 16V(+-10%,X7R,0402)SAM'                       | 'CHIP0402'     | ''          | ''   | '20150612'
 '0.022UF'  | '16V'   | '10%'     | 'C0402'     | 'EMPTY'   | 'CH3223K1B11'(!)   = ''              | ''                 | ''       | 'CH3223K1B11'     |'C0402'| '(C0402-0201)'                                                       | 'NA'       | '16V'         | '10%'    | 'IO'       | 'CAP CHIP 0.022U 16V(+-10%,X7R,0402)SAM'                       | 'CHIP0402'     | ''          | ''   | '20150612'
 '0.01UF'   | '16V'   | '10%'     | 'C0402'     | 'X7R'     | 'CH3103K1B17'(!)   = ''              | ''                 | ''       | 'CH3103K1B17'     |'C0402'| '(C0402-0201)'                                                       | '0.01UF'   | '16V'         | '10%'    | 'DISCRETE' | 'CAP CHIP 0.01U 16V,+-10%,X7R,0402)SAM'                        | 'CHIP0402'     | ''          | ''   | '20150612'
 '0.01UF'   | '16V'   | '10%'     | 'C0402'     | 'EMPTY'   | 'CH3103K1B17'(!)   = ''              | ''                 | ''       | 'CH3103K1B17'     |'C0402'| '(C0402-0201)'                                                       | 'NA'       | '16V'         | '10%'    | 'IO'       | 'CAP CHIP 0.01U 16V,+-10%,X7R,0402)SAM'                        | 'CHIP0402'     | ''          | ''   | '20150612'
 '2700PF'   | '50V'   | '10%'     | 'C0402'     | 'X7R'     | 'CH2276K1B07'(!)   = ''              | ''                 | ''       | 'CH2276K1B07'     |'C0402'| '(C0402-0201)'                                                       | '2700PF'   | '50V'         | '10%'    | 'DISCRETE' | 'CAP CHIP 2700P 50V(+-10%,X7R,0402)SAM'                        | 'CHIP0402'     | ''          | ''   | '20150612'
 '2700PF'   | '50V'   | '10%'     | 'C0402'     | 'EMPTY'   | 'CH2276K1B07'(!)   = ''              | ''                 | ''       | 'CH2276K1B07'     |'C0402'| '(C0402-0201)'                                                       | 'NA'       | '50V'         | '10%'    | 'IO'       | 'CAP CHIP 2700P 50V(+-10%,X7R,0402)SAM'                        | 'CHIP0402'     | ''          | ''   | '20150612'
 '470PF'    | '50V'   | '5%'      | 'C0402'     | 'NPO'     | 'CH1476J0B03'(!)   = ''              | ''                 | ''       | 'CH1476J0B03'     |'C0402'| '(C0402-0201)'                                                       | '470PF'    | '50V'         | '5%'     | 'DISCRETE' | 'CAP CHIP 470P,50V(+-5%,NPO,0402)SAM'                          | 'CHIP0402'     | ''          | ''   | '20150612'
 '470PF'    | '50V'   | '5%'      | 'C0402'     | 'EMPTY'   | 'CH1476J0B03'(!)   = ''              | ''                 | ''       | 'CH1476J0B03'     |'C0402'| '(C0402-0201)'                                                       | 'NA'       | '50V'         | '5%'     | 'IO'       | 'CAP CHIP 470P,50V(+-5%,NPO,0402)SAM'                          | 'CHIP0402'     | ''          | ''   | '20150612'
 '47PF'     | '50V'   | '5%'      | 'C0402'     | 'NPO'     | 'CH0476J0B11'(!)   = 'End of Design' | 'Comp-Approve'     | ''       | 'CH0476J0B11'     |'C0402'| '(C0402-0201)'                                                       | '47PF'     | '50V'         | '5%'     | 'DISCRETE' | 'CAP CHIP 47P 50V(+-5%,NPO,0402)SAM'                           | 'CHIP0402'     | ''          | ''   | '20150612'
 '47PF'     | '50V'   | '5%'      | 'C0402'     | 'EMPTY'   | 'CH0476J0B11'(!)   = 'End of Design' | 'Comp-Approve'     | ''       | 'CH0476J0B11'     |'C0402'| '(C0402-0201)'                                                       | 'NA'       | '50V'         | '5%'     | 'IO'       | 'CAP CHIP 47P 50V(+-5%,NPO,0402)SAM'                           | 'CHIP0402'     | ''          | ''   | '20150612'
 '0.22UF'   | '6.3V'  | '20%'     | 'C0201'     | 'X6S'     | 'CH4221MEE01'(!)   = ''              | ''                 | ''       | 'CH4221MEE01'     |'C0201'| '(SMC0201AW)'                                                        | '0.22UF'   | '6.3V'        | '20%'    | 'DISCRETE' | 'CAP CHIP 0.22UF 6.3V(20%,X6S,0201)'                           | 'CHIP0201'     | ''          | ''   | '20150612'
 '0.22UF'   | '6.3V'  | '20%'     | 'C0201'     | 'EMPTY'   | 'CH4221MEE01'(!)   = ''              | ''                 | ''       | 'CH4221MEE01'     |'C0201'| '(SMC0201AW)'                                                        | 'NA'       | '6.3V'        | '20%'    | 'IO'       | 'CAP CHIP 0.22UF 6.3V(20%,X6S,0201)'                           | 'CHIP0201'     | ''          | ''   | '20150612'
 '220UF'    | '4V'    | '20%'     | 'C1206'     | 'X6S'     | 'CH722KME200'(!)   = 'End of Design' | 'Comp-Approve'     | ''       | 'CH722KME200'     |'C1206_H66'| '(SMC1206AW)'                                                        | '220UF'    | '4V'          | '20%'    | 'DISCRETE' | 'CAP CHIP 220U 4V(+-20%,X6S,1206)'                             | 'CHIP1206'     | ''          | ''   | '20150612'
 '220UF'    | '4V'    | '20%'     | 'C1206'     | 'EMPTY'   | 'CH722KME200'(!)   = 'End of Design' | 'Comp-Approve'     | ''       | 'CH722KME200'     |'C1206_H66'| '(SMC1206AW)'                                                        | 'NA'       | '4V'          | '20%'    | 'IO'       | 'CAP CHIP 220U 4V(+-20%,X6S,1206)'                             | 'CHIP1206'     | ''          | ''   | '20150612'
 '2.2UF'    | '16V'   | '10%'     | 'C0603'     | 'X6S'     | 'CH5223KE902'(!)   = ''              | ''                 | ''       | 'CH5223KE902'     |'C0603'| '(SMC0603AW)'                                                        | '2.2UF'    | '16V'         | '10%'    | 'DISCRETE' | 'CAP CHIP 2.2U 16V(+-10%,X6S,0603)MUR'                         | 'CHIP0603'     | ''          | ''   | '20150612'
 '2.2UF'    | '16V'   | '10%'     | 'C0603'     | 'EMPTY'   | 'CH5223KE902'(!)   = ''              | ''                 | ''       | 'CH5223KE902'     |'C0603'| '(SMC0603AW)'                                                        | 'NA'       | '16V'         | '10%'    | 'IO'       | 'CAP CHIP 2.2U 16V(+-10%,X6S,0603)MUR'                         | 'CHIP0603'     | ''          | ''   | '20150612'
 '1UF'      | '10V'   | '10%'     | 'C0603'     | 'X7R'     | 'CH5102K1902'(!)   = 'End of Design' | 'Comp-Approve'     | ''       | 'CH5102K1902'     |'C0603'| '(SMC0603AW)'                                                        | '1UF'      | '10V'         | '10%'    | 'DISCRETE' | 'CAP CHIP 1U 10V(+-10%,X7R,0603)SAM'                           | 'CHIP0603'     | ''          | ''   | '20150612'
 '1UF'      | '10V'   | '10%'     | 'C0603'     | 'EMPTY'   | 'CH5102K1902'(!)   = 'End of Design' | 'Comp-Approve'     | ''       | 'CH5102K1902'     |'C0603'| '(SMC0603AW)'                                                        | 'NA'       | '10V'         | '10%'    | 'IO'       | 'CAP CHIP 1U 10V(+-10%,X7R,0603)SAM'                           | 'CHIP0603'     | ''          | ''   | '20150612'
 '10UF'     | '10V'   | '20%'     | 'C0603'     | 'X7R'     | 'CH6102M1900'(!)   = ''              | 'End of Life'      | ''       | 'CH6102M1900'     |'C0603_EOL'| '(SMC0603AW)'                                                        | '10UF'     | '10V'         | '20%'    | 'DISCRETE' | 'CAP CHIP 10U,10V(+-20%,X7R,0603)SAM'                          | 'CHIP0603'     | ''          | ''   | '20150612'
 '10UF'     | '10V'   | '20%'     | 'C0603'     | 'EMPTY'   | 'CH6102M1900'(!)   = ''              | 'End of Life'      | ''       | 'CH6102M1900'     |'C0603_EOL'| '(SMC0603AW)'                                                        | 'NA'       | '10V'         | '20%'    | 'IO'       | 'CAP CHIP 10U,10V(+-20%,X7R,0603)SAM'                          | 'CHIP0603'     | ''          | ''   | '20150612'
 '10UF'     | '10V'   | '20%'     | 'C0603'     | 'X7R'     | 'CH6102M1901'(!)   = ''              | 'End of Life'      | ''       | 'CH6102M1901'     |'C0603_EOL'| '(SMC0603AW)'                                                        | '10UF'     | '10V'         | '20%'    | 'DISCRETE' | 'CAP CHIP 10U,10V(+-20%,X7R,0603)MUR'                          | 'CHIP0603'     | ''          | ''   | '20150612'
 '10UF'     | '10V'   | '20%'     | 'C0603'     | 'EMPTY'   | 'CH6102M1901'(!)   = ''              | 'End of Life'      | ''       | 'CH6102M1901'     |'C0603_EOL'| '(SMC0603AW)'                                                        | 'NA'       | '10V'         | '20%'    | 'IO'       | 'CAP CHIP 10U,10V(+-20%,X7R,0603)MUR'                          | 'CHIP0603'     | ''          | ''   | '20150612'
 '22UF'     | '4V'    | '20%'     | 'C0603'     | 'X6S'     | 'CH622KME905'(!)   = ''              | ''                 | ''       | 'CH622KME905'     |'C0603'| '(SMC0603AW)'                                                        | '22UF'     | '4V'          | '20%'    | 'DISCRETE' | 'CAP CHIP 22UF 4V(+-20%,X6S,0603)MUR'                          | 'CHIP0603'     | ''          | ''   | '20150612'
 '22UF'     | '4V'    | '20%'     | 'C0603'     | 'EMPTY'   | 'CH622KME905'(!)   = ''              | ''                 | ''       | 'CH622KME905'     |'C0603'| '(SMC0603AW)'                                                        | 'NA'       | '4V'          | '20%'    | 'IO'       | 'CAP CHIP 22UF 4V(+-20%,X6S,0603)MUR'                          | 'CHIP0603'     | ''          | ''   | '20150612'
 '1UF'      | '25V'   | '10%'     | 'C0402'     | 'X7R'     | 'CH-104K6B00'(!)   = 'End of Design' | 'End of Life'      | ''       | 'CH-104K6B00'     |'C0402_EOL'| '(C0402-0201)'                                                       | '1UF'      | '25V'         | '10%'    | 'DISCRETE' | 'CAP CHIP 1U 25V (+-10%,X7S,0402)'                             | 'CHIP0402'     | ''          | ''   | '20150612'
 '1UF'      | '25V'   | '10%'     | 'C0402'     | 'EMPTY'   | 'CH-104K6B00'(!)   = 'End of Design' | 'End of Life'      | ''       | 'CH-104K6B00'     |'C0402_EOL'| '(C0402-0201)'                                                       | 'NA'       | '25V'         | '10%'    | 'IO'       | 'CAP CHIP 1U 25V (+-10%,X7S,0402)'                             | 'CHIP0402'     | ''          | ''   | '20150612'
 '2.2UF'    | '10V'   | '10%'     | 'C0402'     | 'X7S'     | 'CH5222K6B00'(!)   = 'End of Design' | 'Comp-Approve'     | ''       | 'CH5222K6B00'     |'C0402'| '(C0402-0201)'                                                       | '2.2UF'    | '10V'         | '10%'    | 'DISCRETE' | 'CAP CHIP 2.2UF 10V(10%,X7S,0402)'                             | 'CHIP0402'     | ''          | ''   | '20150612'
 '2.2UF'    | '10V'   | '10%'     | 'C0402'     | 'EMPTY'   | 'CH5222K6B00'(!)   = 'End of Design' | 'Comp-Approve'     | ''       | 'CH5222K6B00'     |'C0402'| '(C0402-0201)'                                                       | 'NA'       | '10V'         | '10%'    | 'IO'       | 'CAP CHIP 2.2UF 10V(10%,X7S,0402)'                             | 'CHIP0402'     | ''          | ''   | '20150612'
 '0.22UF'   | '10V'   | '10%'     | 'C0402'     | 'X7R'     | 'CH4222K1B00'(!)   = 'End of Design' | 'Comp-Release Qty' | ''       | 'CH4222K1B00'     |'C0402'| '(C0402-0201)'                                                       | '0.22UF'   | '10V'         | '10%'    | 'DISCRETE' | 'CAP CHIP 0.22U 10V(+-10%,X7R,0402)'                           | 'CHIP0402'     | ''          | ''   | '20150612'
 '0.22UF'   | '10V'   | '10%'     | 'C0402'     | 'EMPTY'   | 'CH4222K1B00'(!)   = 'End of Design' | 'Comp-Release Qty' | ''       | 'CH4222K1B00'     |'C0402'| '(C0402-0201)'                                                       | 'NA'       | '10V'         | '10%'    | 'IO'       | 'CAP CHIP 0.22U 10V(+-10%,X7R,0402)'                           | 'CHIP0402'     | ''          | ''   | '20150612'
 '15PF'     | '50V'   | '5%'      | 'C0402'     | 'C0G'     | 'CH0156J0B07'(!)   = ''              | ''                 | ''       | 'CH0156J0B07'     |'C0402'| '(C0402-0201)'                                                       | '15PF'     | '50V'         | '5%'     | 'DISCRETE' | 'CAP CHIP 15P 50V(+-5% C0G 0402)MUR'                           | 'CHIP0402'     | ''          | ''   | '20150614'
 '15PF'     | '50V'   | '5%'      | 'C0402'     | 'EMPTY'   | 'CH0156J0B07'(!)   = ''              | ''                 | ''       | 'CH0156J0B07'     |'C0402'| '(C0402-0201)'                                                       | 'NA'       | '50V'         | '5%'     | 'IO'       | 'CAP CHIP 15P 50V(+-5% C0G 0402)MUR'                           | 'CHIP0402'     | ''          | ''   | '20150614'
 '18PF'     | '50V'   | '5%'      | 'C0402'     | 'C0G'     | 'CH0186J0B05'(!)   = ''              | ''                 | ''       | 'CH0186J0B05'     |'C0402'| '(C0402-0201)'                                                       | '18PF'     | '50V'         | '5%'     | 'DISCRETE' | 'CAP CHIP 18P 50V(+-5% C0G 0402)MUR'                           | 'CHIP0402'     | ''          | ''   | '20150614'
 '18PF'     | '50V'   | '5%'      | 'C0402'     | 'EMPTY'   | 'CH0186J0B05'(!)   = ''              | ''                 | ''       | 'CH0186J0B05'     |'C0402'| '(C0402-0201)'                                                       | 'NA'       | '50V'         | '5%'     | 'IO'       | 'CAP CHIP 18P 50V(+-5% C0G 0402)MUR'                           | 'CHIP0402'     | ''          | ''   | '20150614'
 '22PF'     | '50V'   | '5%'      | 'C0402'     | 'NPO'     | 'CH0226J0B16'(!)   = ''              | ''                 | ''       | 'CH0226J0B16'     |'C0402'| '(C0402-0201)'                                                       | '22PF'     | '50V'         | '5%'     | 'DISCRETE' | 'CAP CHIP 22P 50V(+-5%,NPO,0402)MUR'                           | 'CHIP0402'     | ''          | ''   | '20150614'
 '22PF'     | '50V'   | '5%'      | 'C0402'     | 'EMPTY'   | 'CH0226J0B16'(!)   = ''              | ''                 | ''       | 'CH0226J0B16'     |'C0402'| '(C0402-0201)'                                                       | 'NA'       | '50V'         | '5%'     | 'IO'       | 'CAP CHIP 22P 50V(+-5%,NPO,0402)MUR'                           | 'CHIP0402'     | ''          | ''   | '20150614'
 '100PF'    | '50V'   | '5%'      | 'C0402'     | 'NPO'     | 'CH1106J0B16'(!)   = ''              | ''                 | ''       | 'CH1106J0B16'     |'C0402'| '(C0402-0201)'                                                       | '100PF'    | '50V'         | '5%'     | 'DISCRETE' | 'CAP CHIP 100P 50V(+-5%,NPO,0402)MUR'                          | 'CHIP0402'     | ''          | ''   | '20150614'
 '100PF'    | '50V'   | '5%'      | 'C0402'     | 'EMPTY'   | 'CH1106J0B16'(!)   = ''              | ''                 | ''       | 'CH1106J0B16'     |'C0402'| '(C0402-0201)'                                                       | 'NA'       | '50V'         | '5%'     | 'IO'       | 'CAP CHIP 100P 50V(+-5%,NPO,0402)MUR'                          | 'CHIP0402'     | ''          | ''   | '20150614'
 '470PF'    | '50V'   | '10%'     | 'C0402'     | 'X7R'     | 'CH1476K1B11'(!)   = ''              | ''                 | ''       | 'CH1476K1B11'     |'C0402'| '(C0402-0201)'                                                       | '470PF'    | '50V'         | '10%'    | 'DISCRETE' | 'CAP CHIP 470P 50V(+-10%,X7R,0402)MUR'                         | 'CHIP0402'     | ''          | ''   | '20150614'
 '470PF'    | '50V'   | '10%'     | 'C0402'     | 'EMPTY'   | 'CH1476K1B11'(!)   = ''              | ''                 | ''       | 'CH1476K1B11'     |'C0402'| '(C0402-0201)'                                                       | 'NA'       | '50V'         | '10%'    | 'IO'       | 'CAP CHIP 470P 50V(+-10%,X7R,0402)MUR'                         | 'CHIP0402'     | ''          | ''   | '20150614'
 '1000PF'   | '50V'   | '5%'      | 'C0402'     | 'X7R'     | 'CH2106J1B04'(!)   = ''              | ''                 | ''       | 'CH2106J1B04'     |'C0402'| '(C0402-0201)'                                                       | '1000PF'   | '50V'         | '5%'     | 'DISCRETE' | 'CAP CHIP 1000P 50V(+-5%,X7R,0402)MUR'                         | 'CHIP0402'     | ''          | ''   | '20150614'
 '1000PF'   | '50V'   | '5%'      | 'C0402'     | 'EMPTY'   | 'CH2106J1B04'(!)   = ''              | ''                 | ''       | 'CH2106J1B04'     |'C0402'| '(C0402-0201)'                                                       | 'NA'       | '50V'         | '5%'     | 'IO'       | 'CAP CHIP 1000P 50V(+-5%,X7R,0402)MUR'                         | 'CHIP0402'     | ''          | ''   | '20150614'
 '1000PF'   | '16V'   | '10%'     | 'C0402'     | 'X7R'     | 'CH2103K1B03'(!)   = ''              | ''                 | ''       | 'CH2103K1B03'     |'C0402'| '(C0402_OCTAGONXA,C0402-0201)'                                       | '1000PF'   | '16V'         | '10%'    | 'DISCRETE' | 'CAP CHIP 1000PF 16V (+-10%,X7R,0402)MUR'                      | 'CHIP0402'     | ''          | ''   | '20150614'
 '1000PF'   | '16V'   | '10%'     | 'C0402'     | 'EMPTY'   | 'CH2103K1B03'(!)   = ''              | ''                 | ''       | 'CH2103K1B03'     |'C0402'| '(C0402_OCTAGONXA,C0402-0201)'                                       | 'NA'       | '16V'         | '10%'    | 'IO'       | 'CAP CHIP 1000PF 16V (+-10%,X7R,0402)MUR'                      | 'CHIP0402'     | ''          | ''   | '20150614'
 '1500PF'   | '50V'   | '10%'     | 'C0402'     | 'X7R'     | 'CH2156K1B08'(!)   = ''              | ''                 | ''       | 'CH2156K1B08'     |'C0402'| '(C0402-0201)'                                                       | '1500PF'   | '50V'         | '10%'    | 'DISCRETE' | 'CAP CHIP1500PF 50V(+-10%,X7R,0402)MUR'                        | 'CHIP0402'     | ''          | ''   | '20150614'
 '1500PF'   | '50V'   | '10%'     | 'C0402'     | 'EMPTY'   | 'CH2156K1B08'(!)   = ''              | ''                 | ''       | 'CH2156K1B08'     |'C0402'| '(C0402-0201)'                                                       | 'NA'       | '50V'         | '10%'    | 'IO'       | 'CAP CHIP1500PF 50V(+-10%,X7R,0402)MUR'                        | 'CHIP0402'     | ''          | ''   | '20150614'
 '2200PF'   | '50V'   | '10%'     | 'C0402'     | 'X7R'     | 'CH2226K1B06'(!)   = ''              | ''                 | ''       | 'CH2226K1B06'     |'C0402'| '(C0402-0201)'                                                       | '2200PF'   | '50V'         | '10%'    | 'DISCRETE' | 'CAP CHIP 2200P 50V(+-10%,X7R,0402)MUR'                        | 'CHIP0402'     | ''          | ''   | '20150614'
 '2200PF'   | '50V'   | '10%'     | 'C0402'     | 'EMPTY'   | 'CH2226K1B06'(!)   = ''              | ''                 | ''       | 'CH2226K1B06'     |'C0402'| '(C0402-0201)'                                                       | 'NA'       | '50V'         | '10%'    | 'IO'       | 'CAP CHIP 2200P 50V(+-10%,X7R,0402)MUR'                        | 'CHIP0402'     | ''          | ''   | '20150614'
 '4700P'    | '25V'   | '10%'     | 'C0402'     | 'X7R'     | 'CH2474K1B08'(!)   = ''              | ''                 | ''       | 'CH2474K1B08'     |'C0402'| '(C0402-0201)'                                                       | '4700P'    | '25V'         | '10%'    | 'DISCRETE' | 'CAP CHIP 4700P 25V(+-10%,X7R,0402)MUR'                        | 'CHIP0402'     | ''          | ''   | '20150614'
 '4700P'    | '25V'   | '10%'     | 'C0402'     | 'EMPTY'   | 'CH2474K1B08'(!)   = ''              | ''                 | ''       | 'CH2474K1B08'     |'C0402'| '(C0402-0201)'                                                       | 'NA'       | '25V'         | '10%'    | 'IO'       | 'CAP CHIP 4700P 25V(+-10%,X7R,0402)MUR'                        | 'CHIP0402'     | ''          | ''   | '20150614'
 '0.01UF'   | '25V'   | '10%'     | 'C0402'     | 'X7R'     | 'CH3104K1B11'(!)   = ''              | ''                 | ''       | 'CH3104K1B11'     |'C0402'| '(C0402-0201)'                                                       | '0.01UF'   | '25V'         | '10%'    | 'DISCRETE' | 'CAP CHIP 0.01U 25V(+-10%,X7R,0402)MUR'                        | 'CHIP0402'     | ''          | ''   | '20150614'
 '0.01UF'   | '25V'   | '10%'     | 'C0402'     | 'EMPTY'   | 'CH3104K1B11'(!)   = ''              | ''                 | ''       | 'CH3104K1B11'     |'C0402'| '(C0402-0201)'                                                       | 'NA'       | '25V'         | '10%'    | 'IO'       | 'CAP CHIP 0.01U 25V(+-10%,X7R,0402)MUR'                        | 'CHIP0402'     | ''          | ''   | '20150614'
 '0.015UF'  | '16V'   | '10%'     | 'C0402'     | 'X7R'     | 'CH3153K1B03'(!)   = ''              | ''                 | ''       | 'CH3153K1B03'     |'C0402'| '(C0402-0201)'                                                       | '0.015UF'  | '16V'         | '10%'    | 'DISCRETE' | 'CAP CHIP 0.015U 16V(+-10%.X7R.0402)MUR'                       | 'CHIP0402'     | ''          | ''   | '20150614'
 '0.015UF'  | '16V'   | '10%'     | 'C0402'     | 'EMPTY'   | 'CH3153K1B03'(!)   = ''              | ''                 | ''       | 'CH3153K1B03'     |'C0402'| '(C0402-0201)'                                                       | 'NA'       | '16V'         | '10%'    | 'IO'       | 'CAP CHIP 0.015U 16V(+-10%.X7R.0402)MUR'                       | 'CHIP0402'     | ''          | ''   | '20150614'
 '0.047UF'  | '10V'   | '10%'     | 'C0402'     | 'X7R'     | 'CH3472K1B04'(!)   = 'End of Design' | 'Comp-Approve'     | ''       | 'CH3472K1B04'     |'C0402'| '(C0402-0201)'                                                       | '0.047UF'  | '10V'         | '10%'    | 'DISCRETE' | 'CAP CHIP 0.047U 10V(+-10% X7R 0402)MUR'                       | 'CHIP0402'     | ''          | ''   | '20150614'
 '0.047UF'  | '10V'   | '10%'     | 'C0402'     | 'EMPTY'   | 'CH3472K1B04'(!)   = 'End of Design' | 'Comp-Approve'     | ''       | 'CH3472K1B04'     |'C0402'| '(C0402-0201)'                                                       | 'NA'       | '10V'         | '10%'    | 'IO'       | 'CAP CHIP 0.047U 10V(+-10% X7R 0402)MUR'                       | 'CHIP0402'     | ''          | ''   | '20150614'
 '0.047UF'  | '25V'   | '10%'     | 'C0402'     | 'X7R'     | 'CH3474K1B03'(!)   = ''              | ''                 | ''       | 'CH3474K1B03'     |'C0402'| '(C0402-0201)'                                                       | '0.047UF'  | '25V'         | '10%'    | 'DISCRETE' | 'CAP CHIP 0.047U 25V(+-10% X7R 0402)MUR'                       | 'CHIP0402'     | ''          | ''   | '20150614'
 '0.047UF'  | '25V'   | '10%'     | 'C0402'     | 'EMPTY'   | 'CH3474K1B03'(!)   = ''              | ''                 | ''       | 'CH3474K1B03'     |'C0402'| '(C0402-0201)'                                                       | 'NA'       | '25V'         | '10%'    | 'IO'       | 'CAP CHIP 0.047U 25V(+-10% X7R 0402)MUR'                       | 'CHIP0402'     | ''          | ''   | '20150614'
 '0.068UF'  | '16V'   | '10%'     | 'C0402'     | 'X7R'     | 'CH3683K1B02'(!)   = ''              | ''                 | ''       | 'CH3683K1B02'     |'C0402'| '(C0402-0201)'                                                       | '0.068UF'  | '16V'         | '10%'    | 'DISCRETE' | 'CAP CHIP 0.068UF 16V(+-10%,X7R 0402)MUR'                      | 'CHIP0402'     | ''          | ''   | '20150614'
 '0.068UF'  | '16V'   | '10%'     | 'C0402'     | 'EMPTY'   | 'CH3683K1B02'(!)   = ''              | ''                 | ''       | 'CH3683K1B02'     |'C0402'| '(C0402-0201)'                                                       | 'NA'       | '16V'         | '10%'    | 'IO'       | 'CAP CHIP 0.068UF 16V(+-10%,X7R 0402)MUR'                      | 'CHIP0402'     | ''          | ''   | '20150614'
 '0.1UF'    | '25V'   | '10%'     | 'C0402'     | 'X7R'     | 'CH4104K1B03'(!)   = 'End of Design' | 'Comp-Approve'     | ''       | 'CH4104K1B03'     |'C0402'| '(C0402_OCTAGONXA,C0402-0201,C0402_OCTAGONXA_BOUND22)'               | '0.1UF'    | '25V'         | '10%'    | 'DISCRETE' | 'CAP CHIP 0.1U 25V(+-10%,X7R,0402)MUR'                         | 'CHIP0402'     | ''          | ''   | '20150615'
 '0.1UF'    | '25V'   | '10%'     | 'C0402'     | 'EMPTY'   | 'CH4104K1B03'(!)   = 'End of Design' | 'Comp-Approve'     | ''       | 'CH4104K1B03'     |'C0402'| '(C0402_OCTAGONXA,C0402-0201,C0402_OCTAGONXA_BOUND22)'               | 'NA'       | '25V'         | '10%'    | 'IO'       | 'CAP CHIP 0.1U 25V(+-10%,X7R,0402)MUR'                         | 'CHIP0402'     | ''          | ''   | '20150615'
 '1UF'      | '16V'   | '10%'     | 'C0402'     | 'X6S'     | 'CH5103KEB03'(!)   = ''              | ''                 | ''       | 'CH5103KEB03'     |'C0402'| '(C0402_OCTAGONXA,C0402-0201)'                                       | '1UF'      | '16V'         | '10%'    | 'DISCRETE' | 'CAP CHIP 1UF 16V(10%,X6S,0402)MUR'                            | 'CHIP0402'     | ''          | ''   | '20150615'
 '1UF'      | '16V'   | '10%'     | 'C0402'     | 'EMPTY'   | 'CH5103KEB03'(!)   = ''              | ''                 | ''       | 'CH5103KEB03'     |'C0402'| '(C0402_OCTAGONXA,C0402-0201)'                                       | 'NA'       | '16V'         | '10%'    | 'IO'       | 'CAP CHIP 1UF 16V(10%,X6S,0402)MUR'                            | 'CHIP0402'     | ''          | ''   | '20150615'
 '0.47UF'   | '16V'   | '10%'     | 'C0603'     | 'X7R'     | 'CH4473K1904'(!)   = ''              | ''                 | ''       | 'CH4473K1904'     |'C0603'| '(SMC0603AW)'                                                        | '0.47UF'   | '16V'         | '10%'    | 'DISCRETE' | 'CAP CHIP 0.47U 16V (+-10%,X7R,0603)MUR'                       | 'CHIP0603'     | ''          | ''   | '20150615'
 '0.47UF'   | '16V'   | '10%'     | 'C0603'     | 'EMPTY'   | 'CH4473K1904'(!)   = ''              | ''                 | ''       | 'CH4473K1904'     |'C0603'| '(SMC0603AW)'                                                        | 'NA'       | '16V'         | '10%'    | 'IO'       | 'CAP CHIP 0.47U 16V (+-10%,X7R,0603)MUR'                       | 'CHIP0603'     | ''          | ''   | '20150615'
 '0.47UF'   | '25V'   | '10%'     | 'C0603'     | 'X7R'     | 'CH4474K1902'(!)   = 'End of Design' | 'Comp-Approve'     | ''       | 'CH4474K1902'     |'C0603'| '(SMC0603AW)'                                                        | '0.47UF'   | '25V'         | '10%'    | 'DISCRETE' | 'CAP CHIP 0.47UF 25V(+-10%,X7R,0603)MUR'                       | 'CHIP0603'     | ''          | ''   | '20150615'
 '0.47UF'   | '25V'   | '10%'     | 'C0603'     | 'EMPTY'   | 'CH4474K1902'(!)   = 'End of Design' | 'Comp-Approve'     | ''       | 'CH4474K1902'     |'C0603'| '(SMC0603AW)'                                                        | 'NA'       | '25V'         | '10%'    | 'IO'       | 'CAP CHIP 0.47UF 25V(+-10%,X7R,0603)MUR'                       | 'CHIP0603'     | ''          | ''   | '20150615'
 '4.7UF'    | '25V'   | '10%'     | 'C0603'     | 'X6S'     | 'CH5474KE902'(!)   = ''              | ''                 | ''       | 'CH5474KE902'     |'C0603'| '(SMC0603AW)'                                                        | '4.7UF'    | '25V'         | '10%'    | 'DISCRETE' | 'CAP CHIP 4.7UF 25V(+-10%,X6S,0603)MUR'                        | 'CHIP0603'     | ''          | ''   | '20150615'
 '4.7UF'    | '25V'   | '10%'     | 'C0603'     | 'EMPTY'   | 'CH5474KE902'(!)   = ''              | ''                 | ''       | 'CH5474KE902'     |'C0603'| '(SMC0603AW)'                                                        | 'NA'       | '25V'         | '10%'    | 'IO'       | 'CAP CHIP 4.7UF 25V(+-10%,X6S,0603)MUR'                        | 'CHIP0603'     | ''          | ''   | '20150615'
 '1UF'      | '25V'   | '10%'     | 'C0603'     | 'X7R'     | 'CH5104K1903'(!)   = 'End of Design' | 'Comp-Approve'     | ''       | 'CH5104K1903'     |'C0603'| '(SMC0603AW)'                                                        | '1UF'      | '25V'         | '10%'    | 'DISCRETE' | 'CAP CHIP 1U 25V(+-10%.X7R.0603)MUR'                           | 'CHIP0603'     | ''          | ''   | '20150615'
 '1UF'      | '25V'   | '10%'     | 'C0603'     | 'EMPTY'   | 'CH5104K1903'(!)   = 'End of Design' | 'Comp-Approve'     | ''       | 'CH5104K1903'     |'C0603'| '(SMC0603AW)'                                                        | 'NA'       | '25V'         | '10%'    | 'IO'       | 'CAP CHIP 1U 25V(+-10%.X7R.0603)MUR'                           | 'CHIP0603'     | ''          | ''   | '20150615'
 '2.2UF'    | '10V'   | '10%'     | 'C0603'     | 'X7R'     | 'CH5222K1904'(!)   = ''              | ''                 | ''       | 'CH5222K1904'     |'C0603'| '(SMC0603AW)'                                                        | '2.2UF'    | '10V'         | '10%'    | 'DISCRETE' | 'CAP CHIP 2.2UF 10V(+-10%,X7R,0603)MUR'                        | 'CHIP0603'     | ''          | ''   | '20150615'
 '2.2UF'    | '10V'   | '10%'     | 'C0603'     | 'EMPTY'   | 'CH5222K1904'(!)   = ''              | ''                 | ''       | 'CH5222K1904'     |'C0603'| '(SMC0603AW)'                                                        | 'NA'       | '10V'         | '10%'    | 'IO'       | 'CAP CHIP 2.2UF 10V(+-10%,X7R,0603)MUR'                        | 'CHIP0603'     | ''          | ''   | '20150615'
 '4.7UF'    | '6.3V'  | '10%'     | 'C0603'     | 'X6S'     | 'CH5471KE903'(!)   = 'End of Design' | 'Comp-Approve'     | ''       | 'CH5471KE903'     |'C0603'| '(SMC0603AW)'                                                        | '4.7UF'    | '6.3V'        | '10%'    | 'DISCRETE' | 'CAP CHIP 4.7U 6.3V(+-10%,X6S,0603)MUR'                        | 'CHIP0603'     | ''          | ''   | '20150615'
 '4.7UF'    | '6.3V'  | '10%'     | 'C0603'     | 'EMPTY'   | 'CH5471KE903'(!)   = 'End of Design' | 'Comp-Approve'     | ''       | 'CH5471KE903'     |'C0603'| '(SMC0603AW)'                                                        | 'NA'       | '6.3V'        | '10%'    | 'IO'       | 'CAP CHIP 4.7U 6.3V(+-10%,X6S,0603)MUR'                        | 'CHIP0603'     | ''          | ''   | '20150615'
 '10UF'     | '6.3V'  | '20%'     | 'C0603'     | 'X6S'     | 'CH6101ME902'(!)   = ''              | ''                 | ''       | 'CH6101ME902'     |'C0603'| '(SMC0603AW)'                                                        | '10UF'     | '6.3V'        | '20%'    | 'DISCRETE' | 'CAP CHIP 10U 6.3V(+-20%,X6S,0603)MUR'                         | 'CHIP0603'     | ''          | ''   | '20150615'
 '10UF'     | '6.3V'  | '20%'     | 'C0603'     | 'EMPTY'   | 'CH6101ME902'(!)   = ''              | ''                 | ''       | 'CH6101ME902'     |'C0603'| '(SMC0603AW)'                                                        | 'NA'       | '6.3V'        | '20%'    | 'IO'       | 'CAP CHIP 10U 6.3V(+-20%,X6S,0603)MUR'                         | 'CHIP0603'     | ''          | ''   | '20150615'
 '10UF'     | '4V'    | '20%'     | 'C0603'     | 'X6S'     | 'CH610KME905'(!)   = 'End of Design' | 'Comp-Approve'     | ''       | 'CH610KME905'     |'C0603'| '(SMC0603AW)'                                                        | '10UF'     | '4V'          | '20%'    | 'DISCRETE' | 'CAP CHIP 10U 4V(+-20%,X6S,0603)MUR'                           | 'CHIP0603'     | ''          | ''   | '20150615'
 '10UF'     | '4V'    | '20%'     | 'C0603'     | 'EMPTY'   | 'CH610KME905'(!)   = 'End of Design' | 'Comp-Approve'     | ''       | 'CH610KME905'     |'C0603'| '(SMC0603AW)'                                                        | 'NA'       | '4V'          | '20%'    | 'IO'       | 'CAP CHIP 10U 4V(+-20%,X6S,0603)MUR'                           | 'CHIP0603'     | ''          | ''   | '20150615'
 '0.1UF'    | '25V'   | '10%'     | 'C0603'     | 'X7R'     | 'CH4104K1909'(!)   = 'End of Design' | 'Comp-Approve'     | ''       | 'CH4104K1909'     |'C0603'| '(SMC0603AW)'                                                        | '0.1UF'    | '25V'         | '10%'    | 'DISCRETE' | 'CAP CHIP 0.1UF 25V(+-10%,X7R,0603)MUR'                        | 'CHIP0603'     | ''          | ''   | '20150615'
 '0.1UF'    | '25V'   | '10%'     | 'C0603'     | 'EMPTY'   | 'CH4104K1909'(!)   = 'End of Design' | 'Comp-Approve'     | ''       | 'CH4104K1909'     |'C0603'| '(SMC0603AW)'                                                        | 'NA'       | '25V'         | '10%'    | 'IO'       | 'CAP CHIP 0.1UF 25V(+-10%,X7R,0603)MUR'                        | 'CHIP0603'     | ''          | ''   | '20150615'
 '10UF'     | '6.3V'  | '20%'     | 'C0805'     | 'X6S'     | 'CH6101MEA00'(!)   = 'End of Design' | 'Comp-Approve'     | ''       | 'CH6101MEA00'     |'C0805_H61'| '(SMC0805AW)'                                                        | '10UF'     | '6.3V'        | '20%'    | 'DISCRETE' | 'CAP CHIP 10UF 6.3V(+-20%,X6S,0805)MUR'                        | 'CHIP0805'     | ''          | ''   | '20150615'
 '10UF'     | '6.3V'  | '20%'     | 'C0805'     | 'EMPTY'   | 'CH6101MEA00'(!)   = 'End of Design' | 'Comp-Approve'     | ''       | 'CH6101MEA00'     |'C0805_H61'| '(SMC0805AW)'                                                        | 'NA'       | '6.3V'        | '20%'    | 'IO'       | 'CAP CHIP 10UF 6.3V(+-20%,X6S,0805)MUR'                        | 'CHIP0805'     | ''          | ''   | '20150615'
 '100UF'    | '4V'    | '20%'     | 'C0805'     | 'X6S'     | 'CH710KMEA01'(!)   = ''              | ''                 | ''       | 'CH710KMEA01'     |'C0805_H61'| '(SMC0805AW)'                                                        | '100UF'    | '4V'          | '20%'    | 'DISCRETE' | 'CAP CHIP 100U 4V(+-20%,X6S,0805)MUR'                          | 'CHIP0805'     | ''          | ''   | '20150615'
 '100UF'    | '4V'    | '20%'     | 'C0805'     | 'EMPTY'   | 'CH710KMEA01'(!)   = ''              | ''                 | ''       | 'CH710KMEA01'     |'C0805_H61'| '(SMC0805AW)'                                                        | 'NA'       | '4V'          | '20%'    | 'IO'       | 'CAP CHIP 100U 4V(+-20%,X6S,0805)MUR'                          | 'CHIP0805'     | ''          | ''   | '20150615'
 '22UF'     | '10V'   | '20%'     | 'C0805'     | 'X6S'     | 'CH6222MEA01'(!)   = ''              | ''                 | ''       | 'CH6222MEA01'     |'C0805_H61'| '(SMC0805AW)'                                                        | '22UF'     | '10V'         | '20%'    | 'DISCRETE' | 'CAP CHIP 22U 10V(+-20%,X6S,0805)MUR'                          | 'CHIP0805'     | ''          | ''   | '20150615'
 '22UF'     | '10V'   | '20%'     | 'C0805'     | 'EMPTY'   | 'CH6222MEA01'(!)   = ''              | ''                 | ''       | 'CH6222MEA01'     |'C0805_H61'| '(SMC0805AW)'                                                        | 'NA'       | '10V'         | '20%'    | 'IO'       | 'CAP CHIP 22U 10V(+-20%,X6S,0805)MUR'                          | 'CHIP0805'     | ''          | ''   | '20150615'
 '10UF'     | '10V'   | '10%'     | 'C0805'     | 'X7R'     | 'CH6102K1A02'(!)   = ''              | ''                 | ''       | 'CH6102K1A02'     |'C0805_H61'| '(SMC0805AW)'                                                        | '10UF'     | '10V'         | '10%'    | 'DISCRETE' | 'CAP CHIP10UF 10V(+-10%,X7R,0805)MUR'                          | 'CHIP0805'     | ''          | ''   | '20150615'
 '10UF'     | '10V'   | '10%'     | 'C0805'     | 'EMPTY'   | 'CH6102K1A02'(!)   = ''              | ''                 | ''       | 'CH6102K1A02'     |'C0805_H61'| '(SMC0805AW)'                                                        | 'NA'       | '10V'         | '10%'    | 'IO'       | 'CAP CHIP10UF 10V(+-10%,X7R,0805)MUR'                          | 'CHIP0805'     | ''          | ''   | '20150615'
 '0.1UF'    | '100V'  | '10%'     | 'C0805'     | 'X7R'     | 'CH4108K1A01'(!)   = ''              | ''                 | ''       | 'CH4108K1A01'     |'C0805_H61'| '(SMC0805AW)'                                                        | '0.1UF'    | '100V'        | '10%'    | 'DISCRETE' | 'CAP CHIP 0.1UF 100V(+-10%,X7R,0805)MUR'                       | 'CHIP0805'     | ''          | ''   | '20150615'
 '0.1UF'    | '100V'  | '10%'     | 'C0805'     | 'EMPTY'   | 'CH4108K1A01'(!)   = ''              | ''                 | ''       | 'CH4108K1A01'     |'C0805_H61'| '(SMC0805AW)'                                                        | 'NA'       | '100V'        | '10%'    | 'IO'       | 'CAP CHIP 0.1UF 100V(+-10%,X7R,0805)MUR'                       | 'CHIP0805'     | ''          | ''   | '20150615'
 '4.7UF'    | '16V'   | '10%'     | 'C0805'     | 'X7R'     | 'CH5473K1A01'(!)   = 'End of Design' | 'Comp-Approve'     | ''       | 'CH5473K1A01'     |'C0805_H61'| '(SMC0805AW)'                                                        | '4.7UF'    | '16V'         | '10%'    | 'DISCRETE' | 'CAP CHIP 4.7UF 16V(+-10%,X7R,0805)MUR'                        | 'CHIP0805'     | ''          | ''   | '20150615'
 '4.7UF'    | '16V'   | '10%'     | 'C0805'     | 'EMPTY'   | 'CH5473K1A01'(!)   = 'End of Design' | 'Comp-Approve'     | ''       | 'CH5473K1A01'     |'C0805_H61'| '(SMC0805AW)'                                                        | 'NA'       | '16V'         | '10%'    | 'IO'       | 'CAP CHIP 4.7UF 16V(+-10%,X7R,0805)MUR'                        | 'CHIP0805'     | ''          | ''   | '20150615'
 '10UF'     | '25V'   | '10%'     | 'C0805'     | 'X6S'     | 'CH6104KEA03'(!)   = ''              | ''                 | ''       | 'CH6104KEA03'     |'C0805_H61'| '(SMC0805AW)'                                                        | '10UF'     | '25V'         | '10%'    | 'DISCRETE' | 'CAP CHIP 10U 25V(+-10%,X6S,0805)MUR'                          | 'CHIP0805'     | ''          | ''   | '20150615'
 '10UF'     | '25V'   | '10%'     | 'C0805'     | 'EMPTY'   | 'CH6104KEA03'(!)   = ''              | ''                 | ''       | 'CH6104KEA03'     |'C0805_H61'| '(SMC0805AW)'                                                        | 'NA'       | '25V'         | '10%'    | 'IO'       | 'CAP CHIP 10U 25V(+-10%,X6S,0805)MUR'                          | 'CHIP0805'     | ''          | ''   | '20150615'
 '22UF'     | '6.3V'  | '20%'     | 'C0805'     | 'X6S'     | 'CH6221MEA04'(!)   = 'End of Design' | 'Comp-Approve'     | ''       | 'CH6221MEA04'     |'C0805_H61'| '(SMC0805AW)'                                                        | '22UF'     | '6.3V'        | '20%'    | 'DISCRETE' | 'CAP CHIP 22U 6.3V(+-20%,X6S,0805)MUR'                         | 'CHIP0805'     | ''          | ''   | '20150615'
 '22UF'     | '6.3V'  | '20%'     | 'C0805'     | 'EMPTY'   | 'CH6221MEA04'(!)   = 'End of Design' | 'Comp-Approve'     | ''       | 'CH6221MEA04'     |'C0805_H61'| '(SMC0805AW)'                                                        | 'NA'       | '6.3V'        | '20%'    | 'IO'       | 'CAP CHIP 22U 6.3V(+-20%,X6S,0805)MUR'                         | 'CHIP0805'     | ''          | ''   | '20150615'
 '22UF'     | '4V'    | '20%'     | 'C0805'     | 'X6S'     | 'CH622KMEA03'(!)   = ''              | ''                 | ''       | 'CH622KMEA03'     |'C0805_H61'| '(SMC0805AW)'                                                        | '22UF'     | '4V'          | '20%'    | 'DISCRETE' | 'CAP CHIP 22U 4V(+-20%,X6S,0805)MUR'                           | 'CHIP0805'     | ''          | ''   | '20150615'
 '22UF'     | '4V'    | '20%'     | 'C0805'     | 'EMPTY'   | 'CH622KMEA03'(!)   = ''              | ''                 | ''       | 'CH622KMEA03'     |'C0805_H61'| '(SMC0805AW)'                                                        | 'NA'       | '4V'          | '20%'    | 'IO'       | 'CAP CHIP 22U 4V(+-20%,X6S,0805)MUR'                           | 'CHIP0805'     | ''          | ''   | '20150615'
 '2.2UF'    | '100V'  | '10%'     | 'C1206'     | 'X7R'     | 'CH5228K1207'(!)   = ''              | ''                 | ''       | 'CH5228K1207'     |'C1206_H66'| '(SMC1206AW)'                                                        | '2.2UF'    | '100V'        | '10%'    | 'DISCRETE' | 'CAP CHIP 2.2UF 100V(+-10%,X7R,1206)MUR'                       | 'CHIP1206'     | ''          | ''   | '20150615'
 '2.2UF'    | '100V'  | '10%'     | 'C1206'     | 'EMPTY'   | 'CH5228K1207'(!)   = ''              | ''                 | ''       | 'CH5228K1207'     |'C1206_H66'| '(SMC1206AW)'                                                        | 'NA'       | '100V'        | '10%'    | 'IO'       | 'CAP CHIP 2.2UF 100V(+-10%,X7R,1206)MUR'                       | 'CHIP1206'     | ''          | ''   | '20150615'
 '10UF'     | '25V'   | '10%'     | 'C1206'     | 'X7R'     | 'CH6104K1203'(!)   = 'End of Design' | 'Comp-Approve'     | ''       | 'CH6104K1203'     |'C1206_H66'| '(SMC1206AW)'                                                        | '10UF'     | '25V'         | '10%'    | 'DISCRETE' | 'CAP CHIP 10U 25V(+-10%,X7R,1206)MUR'                          | 'CHIP1206'     | ''          | ''   | '20150615'
 '10UF'     | '25V'   | '10%'     | 'C1206'     | 'EMPTY'   | 'CH6104K1203'(!)   = 'End of Design' | 'Comp-Approve'     | ''       | 'CH6104K1203'     |'C1206_H66'| '(SMC1206AW)'                                                        | 'NA'       | '25V'         | '10%'    | 'IO'       | 'CAP CHIP 10U 25V(+-10%,X7R,1206)MUR'                          | 'CHIP1206'     | ''          | ''   | '20150615'
 '1UF'      | '100V'  | '10%'     | 'C1206'     | 'X7R'     | 'CH5108K1201'(!)   = ''              | ''                 | ''       | 'CH5108K1201'     |'C1206_H66'| '(SMC1206AW)'                                                        | '1UF'      | '100V'        | '10%'    | 'DISCRETE' | 'CAP CHIP 1U 100V(10%.1206.X7R)MUR'                            | 'CHIP1206'     | ''          | ''   | '20150615'
 '1UF'      | '100V'  | '10%'     | 'C1206'     | 'EMPTY'   | 'CH5108K1201'(!)   = ''              | ''                 | ''       | 'CH5108K1201'     |'C1206_H66'| '(SMC1206AW)'                                                        | 'NA'       | '100V'        | '10%'    | 'IO'       | 'CAP CHIP 1U 100V(10%.1206.X7R)MUR'                            | 'CHIP1206'     | ''          | ''   | '20150615'
 '10UF'     | '25V'   | '10%'     | 'C1206'     | 'X7R'     | 'CH6104K1204'(!)   = 'End of Design' | 'Comp-Approve'     | ''       | 'CH6104K1204'     |'C1206_H66'| '(SMC1206AW)'                                                        | '10UF'     | '25V'         | '10%'    | 'DISCRETE' | 'CAP CHIP 10U,25V(+-10%,X7R,1206)SAM'                          | 'CHIP1206'     | ''          | ''   | '20150616'
 '10UF'     | '25V'   | '10%'     | 'C1206'     | 'EMPTY'   | 'CH6104K1204'(!)   = 'End of Design' | 'Comp-Approve'     | ''       | 'CH6104K1204'     |'C1206_H66'| '(SMC1206AW)'                                                        | 'NA'       | '25V'         | '10%'    | 'IO'       | 'CAP CHIP 10U,25V(+-10%,X7R,1206)SAM'                          | 'CHIP1206'     | ''          | ''   | '20150616'
 '10UF'     | '6.3V'  | '10%'     | 'C0805'     | 'X6S'     | 'CH6101KEA01'(!)   = ''              | ''                 | ''       | 'CH6101KEA01'     |'C0805_H61'| '(SMC0805AW)'                                                        | '10UF'     | '6.3V'        | '10%'    | 'DISCRETE' | 'CAP CHIP 10UF,6.3V (+-10%,X6S,0805)SAM'                       | 'CHIP0805'     | ''          | ''   | '20150616'
 '10UF'     | '6.3V'  | '10%'     | 'C0805'     | 'EMPTY'   | 'CH6101KEA01'(!)   = ''              | ''                 | ''       | 'CH6101KEA01'     |'C0805_H61'| '(SMC0805AW)'                                                        | 'NA'       | '6.3V'        | '10%'    | 'IO'       | 'CAP CHIP 10UF,6.3V (+-10%,X6S,0805)SAM'                       | 'CHIP0805'     | ''          | ''   | '20150616'
 '10UF'     | '16V'   | '10%'     | 'C0805'     | 'X7R'     | 'CH6103K1A01'(!)   = ''              | ''                 | ''       | 'CH6103K1A01'     |'C0805_H61'| '(SMC0805AW)'                                                        | '10UF'     | '16V'         | '10%'    | 'DISCRETE' | 'CAP CHIP 10UF 16V(+-10%,X7R,0805)SAM'                         | 'CHIP0805'     | ''          | ''   | '20150616'
 '10UF'     | '16V'   | '10%'     | 'C0805'     | 'EMPTY'   | 'CH6103K1A01'(!)   = ''              | ''                 | ''       | 'CH6103K1A01'     |'C0805_H61'| '(SMC0805AW)'                                                        | 'NA'       | '16V'         | '10%'    | 'IO'       | 'CAP CHIP 10UF 16V(+-10%,X7R,0805)SAM'                         | 'CHIP0805'     | ''          | ''   | '20150616'
 '0.01UF'   | '50V'   | '10%'     | 'C0402'     | 'X7R'     | 'CH31006KB00'(!)   = ''              | ''                 | ''       | 'CH31006KB00'     |'C0402'| '(C0402_OCTAGONXA,C0402-0201)'                                       | '0.01UF'   | '50V'         | '10%'    | 'DISCRETE' | 'CAP CHIP 0.01U 50V(+-10%,X7R,0402)MUR'                        | 'CHIP0402'     | ''          | ''   | '20150616'
 '0.01UF'   | '50V'   | '10%'     | 'C0402'     | 'EMPTY'   | 'CH31006KB00'(!)   = ''              | ''                 | ''       | 'CH31006KB00'     |'C0402'| '(C0402_OCTAGONXA,C0402-0201)'                                       | 'NA'       | '50V'         | '10%'    | 'IO'       | 'CAP CHIP 0.01U 50V(+-10%,X7R,0402)MUR'                        | 'CHIP0402'     | ''          | ''   | '20150616'
 '0.22UF'   | '16V'   | '10%'     | 'C0402'     | 'X7R'     | 'CH4223K1B04'(!)   = 'End of Design' | 'Comp-Approve'     | ''       | 'CH4223K1B04'     |'C0402'| '(C0402-0201)'                                                       | '0.22UF'   | '16V'         | '10%'    | 'DISCRETE' | 'CAP CHIP 0.22U 16V(10%,X7R,0402)MUR'                          | 'CHIP0402'     | ''          | ''   | '20150616'
 '0.22UF'   | '16V'   | '10%'     | 'C0402'     | 'EMPTY'   | 'CH4223K1B04'(!)   = 'End of Design' | 'Comp-Approve'     | ''       | 'CH4223K1B04'     |'C0402'| '(C0402-0201)'                                                       | 'NA'       | '16V'         | '10%'    | 'IO'       | 'CAP CHIP 0.22U 16V(10%,X7R,0402)MUR'                          | 'CHIP0402'     | ''          | ''   | '20150616'
 '3300PF'   | '50V'   | '10%'     | 'C0402'     | 'X7R'     | 'CH2336K1B06'(!)   = ''              | ''                 | ''       | 'CH2336K1B06'     |'C0402'| '(C0402-0201)'                                                       | '3300PF'   | '50V'         | '10%'    | 'DISCRETE' | 'CAP CHIP 3300P 50V(+-10%,X7R,0402)MUR'                        | 'CHIP0402'     | ''          | ''   | '20150617'
 '3300PF'   | '50V'   | '10%'     | 'C0402'     | 'EMPTY'   | 'CH2336K1B06'(!)   = ''              | ''                 | ''       | 'CH2336K1B06'     |'C0402'| '(C0402-0201)'                                                       | 'NA'       | '50V'         | '10%'    | 'IO'       | 'CAP CHIP 3300P 50V(+-10%,X7R,0402)MUR'                        | 'CHIP0402'     | ''          | ''   | '20150617'
 '10PF'     | '50V'   | '2%'      | 'C0402'     | 'NPO'     | 'CH0106G0B03'(!)   = ''              | ''                 | ''       | 'CH0106G0B03'     |'C0402'| '(C0402-0201)'                                                       | '10PF'     | '50V'         | '2%'     | 'DISCRETE' | 'CAP CHIP 10P 50V(+-2%,NPO,0402)MUR'                           | 'CHIP0402'     | ''          | ''   | '20150622'
 '10PF'     | '50V'   | '2%'      | 'C0402'     | 'EMPTY'   | 'CH0106G0B03'(!)   = ''              | ''                 | ''       | 'CH0106G0B03'     |'C0402'| '(C0402-0201)'                                                       | 'NA'       | '50V'         | '2%'     | 'IO'       | 'CAP CHIP 10P 50V(+-2%,NPO,0402)MUR'                           | 'CHIP0402'     | ''          | ''   | '20150622'
 '820PF'    | '50V'   | '10%'     | 'C0402'     | 'X7R'     | 'CH1826K1B07'(!)   = ''              | ''                 | ''       | 'CH1826K1B07'     |'C0402'| '(C0402-0201)'                                                       | '820PF'    | '50V'         | '10%'    | 'DISCRETE' | 'CAP CHIP 820P 50V(+-10%,X7R,0402)MUR'                         | 'CHIP0402'     | ''          | ''   | '20150622'
 '820PF'    | '50V'   | '10%'     | 'C0402'     | 'EMPTY'   | 'CH1826K1B07'(!)   = ''              | ''                 | ''       | 'CH1826K1B07'     |'C0402'| '(C0402-0201)'                                                       | 'NA'       | '50V'         | '10%'    | 'IO'       | 'CAP CHIP 820P 50V(+-10%,X7R,0402)MUR'                         | 'CHIP0402'     | ''          | ''   | '20150622'
 '33PF'     | '50V'   | '5%'      | 'C0402'     | 'NPO'     | 'CH0336J0B11'(!)   = ''              | ''                 | ''       | 'CH0336J0B11'     |'C0402'| '(C0402-0201)'                                                       | '33PF'     | '50V'         | '5%'     | 'DISCRETE' | 'CAP CHIP 33P 50V(+-5%,NPO,0402)SAM'                           | 'CHIP0402'     | ''          | ''   | '20150622'
 '33PF'     | '50V'   | '5%'      | 'C0402'     | 'EMPTY'   | 'CH0336J0B11'(!)   = ''              | ''                 | ''       | 'CH0336J0B11'     |'C0402'| '(C0402-0201)'                                                       | 'NA'       | '50V'         | '5%'     | 'IO'       | 'CAP CHIP 33P 50V(+-5%,NPO,0402)SAM'                           | 'CHIP0402'     | ''          | ''   | '20150622'
 '0.1UF'    | '100V'  | '10%'     | 'C1206'     | 'X7R'     | 'CH4108K1205'(!)   = ''              | ''                 | ''       | 'CH4108K1205'     |'C1206_H42'| '(SMC1206AW)'                                                        | '0.1UF'    | '100V'        | '10%'    | 'DISCRETE' | 'CAP CHIP 0.1U 100V(+-10%,X7R,1206)MUR'                        | 'CHIP1206'     | ''          | ''   | '20150622'
 '0.1UF'    | '100V'  | '10%'     | 'C1206'     | 'EMPTY'   | 'CH4108K1205'(!)   = ''              | ''                 | ''       | 'CH4108K1205'     |'C1206_H42'| '(SMC1206AW)'                                                        | 'NA'       | '100V'        | '10%'    | 'IO'       | 'CAP CHIP 0.1U 100V(+-10%,X7R,1206)MUR'                        | 'CHIP1206'     | ''          | ''   | '20150622'
 '22UF'     | '4V'    | '20%'     | 'C0402'     | 'X5R'     | 'CH622KM9B03'(!)   = ''              | ''                 | ''       | 'CH622KM9B03'     |'C0402'| '(C0402-0201)'                                                       | '22UF'     | '4V'          | '20%'    | 'DISCRETE' | 'CAP CHIP 22UF 4V (+-20%, X5R,0402)MUR'                        | 'CHIP0402'     | ''          | ''   | '20150625'
 '22UF'     | '4V'    | '20%'     | 'C0402'     | 'EMPTY'   | 'CH622KM9B03'(!)   = ''              | ''                 | ''       | 'CH622KM9B03'     |'C0402'| '(C0402-0201)'                                                       | 'NA'       | '4V'          | '20%'    | 'IO'       | 'CAP CHIP 22UF 4V (+-20%, X5R,0402)MUR'                        | 'CHIP0402'     | ''          | ''   | '20150625'
 '47UF'     | '4V'    | '20%'     | '0805'      | 'X6S'     | 'CH647KMEA00'(!)   = ''              | ''                 | ''       | 'CH647KMEA00'     |'C0805_H57'| '(C0805_BHS)'                                                        | '47UF'     | '4V'          | '20%'    | 'DISCRETE' | 'CAP CHIP 47U 4V(+-20%,X6S,0805)'                              | 'CHIP0805'     | ''          | ''   | '20150706'
 '47UF'     | '4V'    | '20%'     | '0805'      | 'EMPTY'   | 'CH647KMEA00'(!)   = ''              | ''                 | ''       | 'CH647KMEA00'     |'C0805_H57'| '(C0805_BHS)'                                                        | 'NA'       | '4V'          | '20%'    | 'IO'       | 'CAP CHIP 47U 4V(+-20%,X6S,0805)'                              | 'CHIP0805'     | ''          | ''   | '20150706'
 '1UF'      | '4V'    | '20%'     | '0201'      | 'X6S'     | 'CH-10KMEE00'(!)   = 'End of Design' | 'Comp-Approve'     | ''       | 'CH-10KMEE00'     |'C0201'| '(SMC0201AW)'                                                        | '1UF'      | '4V'          | '20%'    | 'DISCRETE' | 'CAP CHIP 1U 4V(+-20%,X6S,0201)'                               | 'CHIP0201'     | ''          | ''   | '20150713'
 '1UF'      | '4V'    | '20%'     | '0201'      | 'EMPTY'   | 'CH-10KMEE00'(!)   = 'End of Design' | 'Comp-Approve'     | ''       | 'CH-10KMEE00'     |'C0201'| '(SMC0201AW)'                                                        | 'NA'       | '4V'          | '20%'    | 'IO'       | 'CAP CHIP 1U 4V(+-20%,X6S,0201)'                               | 'CHIP0201'     | ''          | ''   | '20150713'
 '10UF'     | '10V'   | '20%'     | 'C0603'     | 'X6S'     | 'CH6102ME902'(!)   = ''              | ''                 | ''       | 'CH6102ME902'     |'C0603'| '(SMC0603AW)'                                                        | '10UF'     | '10V'         | '20%'    | 'DISCRETE' | 'CAP CHIP 10U,10V(+-20%,X6S,0603)TAY'                          | 'CHIP0603'     | ''          | ''   | '20150716'
 '10UF'     | '10V'   | '20%'     | 'C0603'     | 'EMPTY'   | 'CH6102ME902'(!)   = ''              | ''                 | ''       | 'CH6102ME902'     |'C0603'| '(SMC0603AW)'                                                        | 'NA'       | '10V'         | '20%'    | 'IO'       | 'CAP CHIP 10U,10V(+-20%,X6S,0603)TAY'                          | 'CHIP0603'     | ''          | ''   | '20150716'
 '0.047UF'  | '100V'  | '10%'     | 'C0805'     | 'X7R'     | 'CH3478K1A00'(!)   = ''              | ''                 | ''       | 'CH3478K1A00'     |'C0805_H57'| '(SMC0805AW)'                                                        | '0.047UF'  | '100V'        | '10%'    | 'DISCRETE' | 'CAP CHIP 0.047UF 100V(+-10%,X7R,0805)'                        | 'CHIP0805'     | ''          | ''   | '20150803'
 '0.047UF'  | '100V'  | '10%'     | 'C0805'     | 'EMPTY'   | 'CH3478K1A00'(!)   = ''              | ''                 | ''       | 'CH3478K1A00'     |'C0805_H57'| '(SMC0805AW)'                                                        | 'NA'       | '100V'        | '10%'    | 'IO'       | 'CAP CHIP 0.047UF 100V(+-10%,X7R,0805)'                        | 'CHIP0805'     | ''          | ''   | '20150803'
 '0.033UF'  | '16V'   | '10%'     | 'C0402'     | 'X7R'     | 'CH3333K1B06'(!)   = ''              | ''                 | ''       | 'CH3333K1B06'     |'C0402'| '(C0402-0201)'                                                       | '0.033UF'  | '16V'         | '10%'    | 'DISCRETE' | 'CAP CHIP 0.033U 16V(+-10%.X7R.0402)MUR'                       | 'CHIP0402'     | ''          | ''   | '20150825'
 '0.033UF'  | '16V'   | '10%'     | 'C0402'     | 'EMPTY'   | 'CH3333K1B06'(!)   = ''              | ''                 | ''       | 'CH3333K1B06'     |'C0402'| '(C0402-0201)'                                                       | 'NA'       | '16V'         | '10%'    | 'IO'       | 'CAP CHIP 0.033U 16V(+-10%.X7R.0402)MUR'                       | 'CHIP0402'     | ''          | ''   | '20150825'
 '330PF'    | '50V'   | '10%'     | 'C0402'     | 'X7R'     | 'CH1336K1B06'(!)   = ''              | ''                 | ''       | 'CH1336K1B06'     |'C0402'| '(C0402-0201)'                                                       | '330PF'    | '50V'         | '10%'    | 'DISCRETE' | 'CAP CHIP 330P 50V(+-10%,X7R,0402)MUR'                         | 'CHIP0402'     | ''          | ''   | '20150902'
 '330PF'    | '50V'   | '10%'     | 'C0402'     | 'EMPTY'   | 'CH1336K1B06'(!)   = ''              | ''                 | ''       | 'CH1336K1B06'     |'C0402'| '(C0402-0201)'                                                       | 'NA'       | '50V'         | '10%'    | 'IO'       | 'CAP CHIP 330P 50V(+-10%,X7R,0402)MUR'                         | 'CHIP0402'     | ''          | ''   | '20150902'
 '0.1UF'    | '16V'   | '10%'     | 'C0402'     | 'X7R'     | 'CH4103K1B08'(!)   = ''              | ''                 | ''       | 'CH4103K1B08'     |'C0402'| '(C0402_OCTAGONXA,C0402_OCTAGON,C0402-0201)'                         | '0.1UF'    | '16V'         | '10%'    | 'DISCRETE' | 'CAP CHIP 0.1U 16V(10%,X7R,0402)'                              | 'CHIP0402'     | ''          | ''   | '20150911'
 '0.1UF'    | '16V'   | '10%'     | 'C0402'     | 'EMPTY'   | 'CH4103K1B08'(!)   = ''              | ''                 | ''       | 'CH4103K1B08'     |'C0402'| '(C0402_OCTAGONXA,C0402_OCTAGON,C0402-0201)'                         | 'NA'       | '16V'         | '10%'    | 'IO'       | 'CAP CHIP 0.1U 16V(10%,X7R,0402)'                              | 'CHIP0402'     | ''          | ''   | '20150911'
 '1UF'      | '6.3V'  | '10%'     | 'C0402'     | 'X7R'     | 'CH5101K1B05'(!)   = ''              | ''                 | ''       | 'CH5101K1B05'     |'C0402'| '(C0402_OCTAGONXA,C0402_OCTAGON,C0402-0201,C0402_OCTAGONXA_BOUND22)' | '1UF'      | '6.3V'        | '10%'    | 'DISCRETE' | 'CAP CHIP 1U,6.3V(+-10%,X7R,0402)MUR'                          | 'CHIP0402'     | ''          | ''   | '20150911'
 '1UF'      | '6.3V'  | '10%'     | 'C0402'     | 'EMPTY'   | 'CH5101K1B05'(!)   = ''              | ''                 | ''       | 'CH5101K1B05'     |'C0402'| '(C0402_OCTAGONXA,C0402_OCTAGON,C0402-0201,C0402_OCTAGONXA_BOUND22)' | 'NA'       | '6.3V'        | '10%'    | 'IO'       | 'CAP CHIP 1U,6.3V(+-10%,X7R,0402)MUR'                          | 'CHIP0402'     | ''          | ''   | '20150911'
 '10UF'     | '4V'    | '20%'     | 'C0603'     | 'X6S'     | 'CH610KME902'(!)   = 'End of Design' | 'Comp-Approve'     | ''       | 'CH610KME902'     |'C0603'| '(SMC0603AW)'                                                        | '10UF'     | '4V'          | '20%'    | 'DISCRETE' | 'CAP CHIP 10U 4V(+-20%,X6S,0603)'                              | 'CHIP0603'     | ''          | ''   | '20151006'
 '10UF'     | '4V'    | '20%'     | 'C0603'     | 'EMPTY'   | 'CH610KME902'(!)   = 'End of Design' | 'Comp-Approve'     | ''       | 'CH610KME902'     |'C0603'| '(SMC0603AW)'                                                        | 'NA'       | '4V'          | '20%'    | 'IO'       | 'CAP CHIP 10U 4V(+-20%,X6S,0603)'                              | 'CHIP0603'     | ''          | ''   | '20151006'
 '0.01UF'   | '16V'   | '10%'     | 'C0201'     | 'X7R'     | 'CH3103K1E01'(!)   = ''              | ''                 | ''       | 'CH3103K1E01'     |'C0201'| '(SMC0201AW)'                                                        | '0.01UF'   | '16V'         | '10%'    | 'DISCRETE' | 'CAP CHIP 0.01U 16V(+-10%.X7R.0201)TAY'                        | 'CHIP0201'     | ''          | ''   | '20151022'
 '0.01UF'   | '16V'   | '10%'     | 'C0201'     | 'EMPTY'   | 'CH3103K1E01'(!)   = ''              | ''                 | ''       | 'CH3103K1E01'     |'C0201'| '(SMC0201AW)'                                                        | 'NA'       | '16V'         | '10%'    | 'IO'       | 'CAP CHIP 0.01U 16V(+-10%.X7R.0201)TAY'                        | 'CHIP0201'     | ''          | ''   | '20151022'
 '100UF'    | '6.3V'  | '20%'     | 'C1206'     | 'X6T'     | 'CH7101MH201'(!)   = ''              | ''                 | ''       | 'CH7101MH201'     |'C1206_H66'| '(SMC1206AW)'                                                        | '100UF'    | '6.3V'        | '20%'    | 'DISCRETE' | 'CAP CHIP 100U 6.3V(+-20%,X6T,1206)MUR'                        | 'CHIP1206'     | ''          | ''   | '20151022'
 '100UF'    | '6.3V'  | '20%'     | 'C1206'     | 'EMPTY'   | 'CH7101MH201'(!)   = ''              | ''                 | ''       | 'CH7101MH201'     |'C1206_H66'| '(SMC1206AW)'                                                        | 'NA'       | '6.3V'        | '20%'    | 'IO'       | 'CAP CHIP 100U 6.3V(+-20%,X6T,1206)MUR'                        | 'CHIP1206'     | ''          | ''   | '20151022'
 '2.2UF'    | '10V'   | '10%'     | 'C0402'     | 'X6S'     | 'CH5222KEB02'(!)   = ''              | ''                 | ''       | 'CH5222KEB02'     |'C0402_H28'| '(C0402-0201_H28,C0402_OCTAGONXA)'                                   | '2.2UF'    | '10V'         | '10%'    | 'DISCRETE' | 'CAP CHIP 2.2UF 10V(+-10%,X6S,0402)MUR'                        | 'CHIP0402'     | ''          | ''   | '20151022'
 '2.2UF'    | '10V'   | '10%'     | 'C0402'     | 'EMPTY'   | 'CH5222KEB02'(!)   = ''              | ''                 | ''       | 'CH5222KEB02'     |'C0402_H28'| '(C0402-0201_H28,C0402_OCTAGONXA)'                                   | 'NA'       | '10V'         | '10%'    | 'IO'       | 'CAP CHIP 2.2UF 10V(+-10%,X6S,0402)MUR'                        | 'CHIP0402'     | ''          | ''   | '20151022'
 '2.2UF'    | '100V'  | '10%'     | 'C1206'     | 'X7R'     | 'CH5228K1208'(!)   = ''              | ''                 | ''       | 'CH5228K1208'     |'C1206_H66'| '(SMC1206AW)'                                                        | '2.2UF'    | '100V'        | '10%'    | 'DISCRETE' | 'CAP CHIP 2.2UF 100V(+-10%,X7R,1206)SAM'                       | 'CHIP1206'     | ''          | ''   | '20151022'
 '2.2UF'    | '100V'  | '10%'     | 'C1206'     | 'EMPTY'   | 'CH5228K1208'(!)   = ''              | ''                 | ''       | 'CH5228K1208'     |'C1206_H66'| '(SMC1206AW)'                                                        | 'NA'       | '100V'        | '10%'    | 'IO'       | 'CAP CHIP 2.2UF 100V(+-10%,X7R,1206)SAM'                       | 'CHIP1206'     | ''          | ''   | '20151022'
 '47UF'     | '4V'    | '20%'     | 'C0805'     | 'X6S'     | 'CH647KMEA06'(!)   = ''              | ''                 | ''       | 'CH647KMEA06'     |'C0805_H57'| '(SMC0805AW)'                                                        | '47UF'     | '4V'          | '20%'    | 'DISCRETE' | 'CAP CHIP 47U 4V(+-20%.X6S.0805)SAM'                           | 'CHIP0805'     | ''          | ''   | '20151022'
 '47UF'     | '4V'    | '20%'     | 'C0805'     | 'EMPTY'   | 'CH647KMEA06'(!)   = ''              | ''                 | ''       | 'CH647KMEA06'     |'C0805_H57'| '(SMC0805AW)'                                                        | 'NA'       | '4V'          | '20%'    | 'IO'       | 'CAP CHIP 47U 4V(+-20%.X6S.0805)SAM'                           | 'CHIP0805'     | ''          | ''   | '20151022'
 '12PF'     | '50V'   | '2%'      | 'C0402'     | 'C0G'     | 'CH0126G0B07'(!)   = ''              | ''                 | ''       | 'CH0126G0B07'     |'C0402'| '(C0402-0201)'                                                       | '12P'      | '50V'         | '2%'     | 'DISCRETE' | 'CAP CHIP 12P 50V(+-2%,C0G,0402)SAM'                           | 'CHIP0402'     | ''          | ''   | '20151022'
 '12PF'     | '50V'   | '2%'      | 'C0402'     | 'EMPTY'   | 'CH0126G0B07'(!)   = ''              | ''                 | ''       | 'CH0126G0B07'     |'C0402'| '(C0402-0201)'                                                       | 'NA'       | '50V'         | '2%'     | 'IO'       | 'CAP CHIP 12P 50V(+-2%,C0G,0402)SAM'                           | 'CHIP0402'     | ''          | ''   | '20151022'
 '1UF'      | '25V'   | '10%'     | 'C0402'     | 'X6S'     | 'CH5104KEB04'(!)   = ''              | ''                 | ''       | 'CH5104KEB04'     |'C0402'| '(C0402-0201)'                                                       | '1UF'      | '25V'         | '10%'    | 'DISCRETE' | 'CAP CHIP 1UF 25V(+-10%,X6S,0402)SAM'                          | 'CHIP0402'     | ''          | ''   | '20151022'
 '1UF'      | '25V'   | '10%'     | 'C0402'     | 'EMPTY'   | 'CH5104KEB04'(!)   = ''              | ''                 | ''       | 'CH5104KEB04'     |'C0402'| '(C0402-0201)'                                                       | 'NA'       | '25V'         | '10%'    | 'IO'       | 'CAP CHIP 1UF 25V(+-10%,X6S,0402)SAM'                          | 'CHIP0402'     | ''          | ''   | '20151022'
 '12PF'     | '50V'   | '2%'      | 'C0402'     | 'C0G'     | 'CH0126G0B06'(!)   = ''              | ''                 | ''       | 'CH0126G0B06'     |'C0402'| '(C0402-0201)'                                                       | '12PF'     | '50V'         | '2%'     | 'DISCRETE' | 'CAP CHIP 12P 50V(+-2%,C0G,0402)MUR'                           | 'CHIP0402'     | ''          | ''   | '20151029'
 '12PF'     | '50V'   | '2%'      | 'C0402'     | 'EMPTY'   | 'CH0126G0B06'(!)   = ''              | ''                 | ''       | 'CH0126G0B06'     |'C0402'| '(C0402-0201)'                                                       | 'NA'       | '50V'         | '2%'     | 'IO'       | 'CAP CHIP 12P 50V(+-2%,C0G,0402)MUR'                           | 'CHIP0402'     | ''          | ''   | '20151029'
 '0.01UF'   | '1KV'   | '10%'     | 'C1206'     | 'X7R'     | 'CH310FK1202'(!)   = ''              | ''                 | ''       | 'CH310FK1202'     |'C1206_H76'| '(SMC1206AW)'                                                        | '0.01UF'   | '1KV'         | '10%'    | 'DISCRETE' | 'CAP CHIP 0.01U 1KV(+-10%,X7R,1206)MUR'                        | 'CHIP1206'     | ''          | ''   | '20151029'
 '0.01UF'   | '1KV'   | '10%'     | 'C1206'     | 'EMPTY'   | 'CH310FK1202'(!)   = ''              | ''                 | ''       | 'CH310FK1202'     |'C1206_H76'| '(SMC1206AW)'                                                        | 'NA'       | '1KV'         | '10%'    | 'IO'       | 'CAP CHIP 0.01U 1KV(+-10%,X7R,1206)MUR'                        | 'CHIP1206'     | ''          | ''   | '20151029'
 '22UF'     | '25V'   | '20%'     | 'C1206'     | 'X7S'     | 'CH6224M6200'(!)   = 'End of Design' | 'Comp-Approve'     | ''       | 'CH6224M6200'     |'C1206_H76'| '(SMC1206AW)'                                                        | '22UF'     | '25V'         | '20%'    | 'DISCRETE' | 'CAP CHIP 22UF 25V(+-20%,X7S,1206)'                            | 'CHIP1206'     | ''          | ''   | '20151110'
 '22UF'     | '25V'   | '20%'     | 'C1206'     | 'EMPTY'   | 'CH6224M6200'(!)   = 'End of Design' | 'Comp-Approve'     | ''       | 'CH6224M6200'     |'C1206_H76'| '(SMC1206AW)'                                                        | 'NA'       | '25V'         | '20%'    | 'IO'       | 'CAP CHIP 22UF 25V(+-20%,X7S,1206)'                            | 'CHIP1206'     | ''          | ''   | '20151110'
 '1000PF'   | '50V'   | '10%'     | 'C0402'     | 'X7R'     | 'CH2106K1B20'(!)   = ''              | ''                 | ''       | 'CH2106K1B20'     |'C0402'| '(C0402-0201)'                                                       | '1000PF'   | '50V'         | '10%'    | 'DISCRETE' | 'CAP CHIP 1000P 50V(+-10%,X7R,0402)MUR'                        | 'CHIP0402'     | ''          | ''   | '20151112'
 '1000PF'   | '50V'   | '10%'     | 'C0402'     | 'EMPTY'   | 'CH2106K1B20'(!)   = ''              | ''                 | ''       | 'CH2106K1B20'     |'C0402'| '(C0402-0201)'                                                       | 'NA'       | '50V'         | '10%'    | 'IO'       | 'CAP CHIP 1000P 50V(+-10%,X7R,0402)MUR'                        | 'CHIP0402'     | ''          | ''   | '20151112'
 '47UF'     | '6.3V'  | '20%'     | 'C1206'     | 'X6S'     | 'CH6471ME201'(!)   = ''              | ''                 | ''       | 'CH6471ME201'     |'C1206_H76'| '(SMC1206AW)'                                                        | '47UF'     | '6.3V'        | '20%'    | 'DISCRETE' | 'CAP CHIP 47U 6.3V(+-20%,X6S,1206)MUR'                         | 'CHIP1206'     | ''          | ''   | '20151112'
 '47UF'     | '6.3V'  | '20%'     | 'C1206'     | 'EMPTY'   | 'CH6471ME201'(!)   = ''              | ''                 | ''       | 'CH6471ME201'     |'C1206_H76'| '(SMC1206AW)'                                                        | 'NA'       | '6.3V'        | '20%'    | 'IO'       | 'CAP CHIP 47U 6.3V(+-20%,X6S,1206)MUR'                         | 'CHIP1206'     | ''          | ''   | '20151112'
 '47UF'     | '6.3V'  | '20%'     | 'C1206'     | 'X6S'     | 'CH6471ME200'(!)   = 'End of Design' | 'Comp-Approve'     | ''       | 'CH6471ME200'     |'C1206_H76'| '(SMC1206AW)'                                                        | '47UF'     | '6.3V'        | '20%'    | 'DISCRETE' | 'CAP CHIP 47U 6.3V(+-20%,X6S,1206)'                            | 'CHIP1206'     | ''          | ''   | '20151112'
 '47UF'     | '6.3V'  | '20%'     | 'C1206'     | 'EMPTY'   | 'CH6471ME200'(!)   = 'End of Design' | 'Comp-Approve'     | ''       | 'CH6471ME200'     |'C1206_H76'| '(SMC1206AW)'                                                        | 'NA'       | '6.3V'        | '20%'    | 'IO'       | 'CAP CHIP 47U 6.3V(+-20%,X6S,1206)'                            | 'CHIP1206'     | ''          | ''   | '20151112'
 '0.1UF'    | '50V'   | '10%'     | 'C0603'     | 'X7R'     | 'CH4106K1910'(!)   = 'End of Design' | 'Comp-Approve'     | ''       | 'CH4106K1910'     |'C0603'| '(SMC0603AW)'                                                        | '0.1UF'    | '50V'         | '10%'    | 'DISCRETE' | 'CAP CHIP 0.1U 50V(+-10%,X7R,0603)MUR'                         | 'CHIP0603'     | ''          | ''   | '20151120'
 '0.1UF'    | '50V'   | '10%'     | 'C0603'     | 'EMPTY'   | 'CH4106K1910'(!)   = 'End of Design' | 'Comp-Approve'     | ''       | 'CH4106K1910'     |'C0603'| '(SMC0603AW)'                                                        | 'NA'       | '50V'         | '10%'    | 'IO'       | 'CAP CHIP 0.1U 50V(+-10%,X7R,0603)MUR'                         | 'CHIP0603'     | ''          | ''   | '20151120'
 '270PF'    | '25V'   | '5%'      | 'C0402'     | 'NPO'     | 'CH1274J0B01'(!)   = ''              | ''                 | ''       | 'CH1274J0B01'     |'C0402'| '(C0402-0201)'                                                       | '270PF'    | '25V'         | '5%'     | 'DISCRETE' | 'CAP CHIP 270P 25V(+-5%,NPO,0402)MUR'                          | 'CHIP0402'     | ''          | ''   | '20151201'
 '270PF'    | '25V'   | '5%'      | 'C0402'     | 'EMPTY'   | 'CH1274J0B01'(!)   = ''              | ''                 | ''       | 'CH1274J0B01'     |'C0402'| '(C0402-0201)'                                                       | 'NA'       | '25V'         | '5%'     | 'IO'       | 'CAP CHIP 270P 25V(+-5%,NPO,0402)MUR'                          | 'CHIP0402'     | ''          | ''   | '20151201'
 '1UF'      | '25V'   | '10%'     | 'C0805'     | 'X7R'     | 'CH5104K1A06'(!)   = ''              | ''                 | ''       | 'CH5104K1A06'     |'C0805_H57'| '(SMC0805AW)'                                                        | '1UF'      | '25V'         | '10%'    | 'DISCRETE' | 'CAP CHIP 1U 25V(+-10%.X7R.0805)MUR'                           | 'CHIP0805'     | ''          | ''   | '20151209'
 '1UF'      | '25V'   | '10%'     | 'C0805'     | 'EMPTY'   | 'CH5104K1A06'(!)   = ''              | ''                 | ''       | 'CH5104K1A06'     |'C0805_H57'| '(SMC0805AW)'                                                        | 'NA'       | '25V'         | '10%'    | 'IO'       | 'CAP CHIP 1U 25V(+-10%.X7R.0805)MUR'                           | 'CHIP0805'     | ''          | ''   | '20151209'
 '10PF'     | '3KV'   | '5%'      | 'C1808'     | 'NPO'     | 'CH010GJ0I08'(!)   = ''              | ''                 | ''       | 'CH010GJ0I08'     |'C1808_H71'| '(SMC1808AW)'                                                        | '10PF'     | '3KV'         | '5%'     | 'DISCRETE' | 'CAP CHIP 10P 3KV(+-5%,NPO,1808)EP'                            | 'CHIP1808'     | ''          | ''   | '20151211'
 '10PF'     | '3KV'   | '5%'      | 'C1808'     | 'EMPTY'   | 'CH010GJ0I08'(!)   = ''              | ''                 | ''       | 'CH010GJ0I08'     |'C1808_H71'| '(SMC1808AW)'                                                        | 'NA'       | '3KV'         | '5%'     | 'IO'       | 'CAP CHIP 10P 3KV(+-5%,NPO,1808)EP'                            | 'CHIP1808'     | ''          | ''   | '20151211'
 '4.7UF'    | '6.3V'  | '20%'     | '0402'      | 'X6S'     | 'CH5471MEB01'(!)   = ''              | ''                 | ''       | 'CH5471MEB01'     |'C0402'| '(C0402_OCTAGON,C0402_OCTAGONXA,C0402-0201)'                         | '4.7UF'    | '6.3V'        | '20%'    | 'DISCRETE' | 'CAP CHIP 4.7UF 6.3V(+-20%,X6S,0402)'                          | 'CHIP0402'     | ''          | ''   | '20151211'
 '4.7UF'    | '6.3V'  | '20%'     | '0402'      | 'EMPTY'   | 'CH5471MEB01'(!)   = ''              | ''                 | ''       | 'CH5471MEB01'     |'C0402'| '(C0402_OCTAGON,C0402_OCTAGONXA,C0402-0201)'                         | 'NA'       | '6.3V'        | '20%'    | 'IO'       | 'CAP CHIP 4.7UF 6.3V(+-20%,X6S,0402)'                          | 'CHIP0402'     | ''          | ''   | '20151211'
 '0.039UF'  | '50V'   | '10%'     | 'C0603'     | 'X7R'     | 'CH3396K1901'(!)   = 'End of Design' | 'Comp-Approve'     | ''       | 'CH3396K1901'     |'C0603'| '(SMC0603AW)'                                                        | '0.039UF'  | '50V'         | '10%'    | 'DISCRETE' | 'CAP CHIP 0.039U 50V(+-10%,X7R,0603)MUR'                       | 'CHIP0603'     | ''          | ''   | '20151229'
 '0.039UF'  | '50V'   | '10%'     | 'C0603'     | 'EMPTY'   | 'CH3396K1901'(!)   = 'End of Design' | 'Comp-Approve'     | ''       | 'CH3396K1901'     |'C0603'| '(SMC0603AW)'                                                        | 'NA'       | '50V'         | '10%'    | 'IO'       | 'CAP CHIP 0.039U 50V(+-10%,X7R,0603)MUR'                       | 'CHIP0603'     | ''          | ''   | '20151229'
 '0.1UF'    | '10V'   | '10%'     | 'C0402'     | 'X7R'     | 'CH3104K1B15'(!)   = ''              | 'End of Life'      | ''       | 'CH3104K1B15'     |'C0402_EOL'| '(C0402-0201)'                                                       | '0.1UF'    | '10V'         | '10%'    | 'DISCRETE' | 'CAP CHIP 0.1U 10V(+-10%,X7R,0402)AEC'                         | 'CHIP0402'     | ''          | ''   | '20151231'
 '0.1UF'    | '10V'   | '10%'     | 'C0402'     | 'EMPTY'   | 'CH3104K1B15'(!)   = ''              | 'End of Life'      | ''       | 'CH3104K1B15'     |'C0402_EOL'| '(C0402-0201)'                                                       | 'NA'       | '10V'         | '10%'    | 'IO'       | 'CAP CHIP 0.1U 10V(+-10%,X7R,0402)AEC'                         | 'CHIP0402'     | ''          | ''   | '20151231'
 '0.1UF'    | '16V'   | '10%'     | 'C0402'     | 'X7R'     | 'CH4103K1B21'(!)   = ''              | ''                 | ''       | 'CH4103K1B21'     |'C0402'| '(C0402-0201)'                                                       | '0.1UF'    | '16V'         | '10%'    | 'DISCRETE' | 'CAP CHIP 0.1U 16V(+-10%,X7R,0402)AEC'                         | 'CHIP0402'     | ''          | ''   | '20151231'
 '0.1UF'    | '16V'   | '10%'     | 'C0402'     | 'EMPTY'   | 'CH4103K1B21'(!)   = ''              | ''                 | ''       | 'CH4103K1B21'     |'C0402'| '(C0402-0201)'                                                       | 'NA'       | '16V'         | '10%'    | 'IO'       | 'CAP CHIP 0.1U 16V(+-10%,X7R,0402)AEC'                         | 'CHIP0402'     | ''          | ''   | '20151231'
 '0.1UF'    | '25V'   | '10%'     | 'C0603'     | 'X7R'     | 'CH4104K1914'(!)   = ''              | ''                 | ''       | 'CH4104K1914'     |'C0603'| '(SMC0603AW)'                                                        | '0.1UF'    | '25V'         | '10%'    | 'DISCRETE' | 'CAP CHIP 0.1U 25V(+-10%,X7R,0603)AEC'                         | 'CHIP0603'     | ''          | ''   | '20151231'
 '0.1UF'    | '25V'   | '10%'     | 'C0603'     | 'EMPTY'   | 'CH4104K1914'(!)   = ''              | ''                 | ''       | 'CH4104K1914'     |'C0603'| '(SMC0603AW)'                                                        | 'NA'       | '25V'         | '10%'    | 'IO'       | 'CAP CHIP 0.1U 25V(+-10%,X7R,0603)AEC'                         | 'CHIP0603'     | ''          | ''   | '20151231'
 '1000PF'   | '50V'   | '5%'      | 'C0402'     | 'X7R'     | 'CH2106J1B06'(!)   = ''              | ''                 | ''       | 'CH2106J1B06'     |'C0402'| '(C0402-0201)'                                                       | '1000PF'   | '50V'         | '5%'     | 'DISCRETE' | 'CAP CHIP 1000P 50V(+-5%,X7R,0402)AEC'                         | 'CHIP0402'     | ''          | ''   | '20151231'
 '1000PF'   | '50V'   | '5%'      | 'C0402'     | 'EMPTY'   | 'CH2106J1B06'(!)   = ''              | ''                 | ''       | 'CH2106J1B06'     |'C0402'| '(C0402-0201)'                                                       | 'NA'       | '50V'         | '5%'     | 'IO'       | 'CAP CHIP 1000P 50V(+-5%,X7R,0402)AEC'                         | 'CHIP0402'     | ''          | ''   | '20151231'
 '100PF'    | '50V'   | '5%'      | 'C0402'     | 'NPO'     | 'CH1106J0B18'(!)   = ''              | ''                 | ''       | 'CH1106J0B18'     |'C0402'| '(C0402-0201)'                                                       | '100PF'    | '50V'         | '5%'     | 'DISCRETE' | 'CAP CHIP 100P 50V(+-5%,NPO,0402)AEC'                          | 'CHIP0402'     | ''          | ''   | '20151231'
 '100PF'    | '50V'   | '5%'      | 'C0402'     | 'EMPTY'   | 'CH1106J0B18'(!)   = ''              | ''                 | ''       | 'CH1106J0B18'     |'C0402'| '(C0402-0201)'                                                       | 'NA'       | '50V'         | '5%'     | 'IO'       | 'CAP CHIP 100P 50V(+-5%,NPO,0402)AEC'                          | 'CHIP0402'     | ''          | ''   | '20151231'
 '15PF'     | '50V'   | '5%'      | 'C0402'     | 'NPO'     | 'CH0156J0B11'(!)   = ''              | ''                 | ''       | 'CH0156J0B11'     |'C0402'| '(C0402-0201)'                                                       | '15PF'     | '50V'         | '5%'     | 'DISCRETE' | 'CAP CHIP 15P 50V(+-5%,NPO,0402)AEC'                           | 'CHIP0402'     | ''          | ''   | '20151231'
 '15PF'     | '50V'   | '5%'      | 'C0402'     | 'EMPTY'   | 'CH0156J0B11'(!)   = ''              | ''                 | ''       | 'CH0156J0B11'     |'C0402'| '(C0402-0201)'                                                       | 'NA'       | '50V'         | '5%'     | 'IO'       | 'CAP CHIP 15P 50V(+-5%,NPO,0402)AEC'                           | 'CHIP0402'     | ''          | ''   | '20151231'
 '18PF'     | '50V'   | '5%'      | 'C0402'     | 'NPO'     | 'CH0186J0B07'(!)   = ''              | ''                 | ''       | 'CH0186J0B07'     |'C0402'| '(C0402-0201)'                                                       | '18PF'     | '50V'         | '5%'     | 'DISCRETE' | 'CAP CHIP 18P 50V(+-5%,NPO,0402)AEC'                           | 'CHIP0402'     | ''          | ''   | '20151231'
 '18PF'     | '50V'   | '5%'      | 'C0402'     | 'EMPTY'   | 'CH0186J0B07'(!)   = ''              | ''                 | ''       | 'CH0186J0B07'     |'C0402'| '(C0402-0201)'                                                       | 'NA'       | '50V'         | '5%'     | 'IO'       | 'CAP CHIP 18P 50V(+-5%,NPO,0402)AEC'                           | 'CHIP0402'     | ''          | ''   | '20151231'
 '2200PF'   | '50V'   | '10%'     | 'C0402'     | 'X7R'     | 'CH2226K1B13'(!)   = ''              | ''                 | ''       | 'CH2226K1B13'     |'C0402'| '(C0402-0201)'                                                       | '2200PF'   | '50V'         | '10%'    | 'DISCRETE' | 'CAP CHIP 2200P 50V(+-10%,X7R,0402)AEC'                        | 'CHIP0402'     | ''          | ''   | '20151231'
 '2200PF'   | '50V'   | '10%'     | 'C0402'     | 'EMPTY'   | 'CH2226K1B13'(!)   = ''              | ''                 | ''       | 'CH2226K1B13'     |'C0402'| '(C0402-0201)'                                                       | 'NA'       | '50V'         | '10%'    | 'IO'       | 'CAP CHIP 2200P 50V(+-10%,X7R,0402)AEC'                        | 'CHIP0402'     | ''          | ''   | '20151231'
 '22PF'     | '50V'   | '5%'      | 'C0402'     | 'NPO'     | 'CH0226J0B20'(!)   = ''              | ''                 | ''       | 'CH0226J0B20'     |'C0402'| '(C0402-0201)'                                                       | '22PF'     | '50V'         | '5%'     | 'DISCRETE' | 'CAP CHIP 22P 50V(+-5%,NPO,0402)AEC'                           | 'CHIP0402'     | ''          | ''   | '20151231'
 '22PF'     | '50V'   | '5%'      | 'C0402'     | 'EMPTY'   | 'CH0226J0B20'(!)   = ''              | ''                 | ''       | 'CH0226J0B20'     |'C0402'| '(C0402-0201)'                                                       | 'NA'       | '50V'         | '5%'     | 'IO'       | 'CAP CHIP 22P 50V(+-5%,NPO,0402)AEC'                           | 'CHIP0402'     | ''          | ''   | '20151231'
 '3300PF'   | '50V'   | '10%'     | 'C0402'     | 'X7R'     | 'CH2336K1B09'(!)   = ''              | ''                 | ''       | 'CH2336K1B09'     |'C0402'| '(C0402-0201)'                                                       | '3300PF'   | '50V'         | '10%'    | 'DISCRETE' | 'CAP CHIP 3300P 50V(+-10%,X7R,0402)AEC'                        | 'CHIP0402'     | ''          | ''   | '20151231'
 '3300PF'   | '50V'   | '10%'     | 'C0402'     | 'EMPTY'   | 'CH2336K1B09'(!)   = ''              | ''                 | ''       | 'CH2336K1B09'     |'C0402'| '(C0402-0201)'                                                       | 'NA'       | '50V'         | '10%'    | 'IO'       | 'CAP CHIP 3300P 50V(+-10%,X7R,0402)AEC'                        | 'CHIP0402'     | ''          | ''   | '20151231'
 '0.01UF'   | '16V'   | '10%'     | 'C0402'     | 'X7R'     | 'CH3103K1B22'(!)   = ''              | ''                 | ''       | 'CH3103K1B22'     |'C0402'| '(C0402-0201)'                                                       | '0.01UF'   | '16V'         | '10%'    | 'DISCRETE' | 'CAP CHIP 0.01U 16V(+-10%,X7R,0402)AEC'                        | 'CHIP0402'     | ''          | ''   | '20151231'
 '0.01UF'   | '16V'   | '10%'     | 'C0402'     | 'EMPTY'   | 'CH3103K1B22'(!)   = ''              | ''                 | ''       | 'CH3103K1B22'     |'C0402'| '(C0402-0201)'                                                       | 'NA'       | '16V'         | '10%'    | 'IO'       | 'CAP CHIP 0.01U 16V(+-10%,X7R,0402)AEC'                        | 'CHIP0402'     | ''          | ''   | '20151231'
 '0.01UF'   | '25V'   | '10%'     | 'C0402'     | 'X7R'     | 'CH3104K1B14'(!)   = ''              | ''                 | ''       | 'CH3104K1B14'     |'C0402'| '(C0402-0201)'                                                       | '0.01UF'   | '25V'         | '10%'    | 'DISCRETE' | 'CAP CHIP 0.01U 25V(+-10%,X7R,0402)AEC'                        | 'CHIP0402'     | ''          | ''   | '20151231'
 '0.01UF'   | '25V'   | '10%'     | 'C0402'     | 'EMPTY'   | 'CH3104K1B14'(!)   = ''              | ''                 | ''       | 'CH3104K1B14'     |'C0402'| '(C0402-0201)'                                                       | 'NA'       | '25V'         | '10%'    | 'IO'       | 'CAP CHIP 0.01U 25V(+-10%,X7R,0402)AEC'                        | 'CHIP0402'     | ''          | ''   | '20151231'
 '0.1UF'    | '25V'   | '10%'     | 'C0402'     | 'X7R'     | 'CH4104K1B05'(!)   = ''              | ''                 | ''       | 'CH4104K1B05'     |'C0402'| '(C0402-0201)'                                                       | '0.1UF'    | '25V'         | '10%'    | 'DISCRETE' | 'CAP CHIP 0.1U 25V(+-10%,X7R,0402)AEC'                         | 'CHIP0402'     | ''          | ''   | '20160104'
 '0.1UF'    | '25V'   | '10%'     | 'C0402'     | 'EMPTY'   | 'CH4104K1B05'(!)   = ''              | ''                 | ''       | 'CH4104K1B05'     |'C0402'| '(C0402-0201)'                                                       | 'NA'       | '25V'         | '10%'    | 'IO'       | 'CAP CHIP 0.1U 25V(+-10%,X7R,0402)AEC'                         | 'CHIP0402'     | ''          | ''   | '20160104'
 '0.47UF'   | '10V'   | '10%'     | 'C0402'     | 'X7S'     | 'CH4472K6B00'(!)   = ''              | ''                 | ''       | 'CH4472K6B00'     |'C0402'| '(C0402-0201)'                                                       | '0.47UF'   | '10V'         | '10%'    | 'DISCRETE' | 'CAP CHIP 0.47U 10V(+10%,X7S,0402)AEC'                         | 'CHIP0402'     | ''          | ''   | '20160104'
 '0.47UF'   | '10V'   | '10%'     | 'C0402'     | 'EMPTY'   | 'CH4472K6B00'(!)   = ''              | ''                 | ''       | 'CH4472K6B00'     |'C0402'| '(C0402-0201)'                                                       | 'NA'       | '10V'         | '10%'    | 'IO'       | 'CAP CHIP 0.47U 10V(+10%,X7S,0402)AEC'                         | 'CHIP0402'     | ''          | ''   | '20160104'
 '1000PF'   | '50V'   | '10%'     | 'C0402'     | 'X7R'     | 'CH2106K1B24'(!)   = ''              | ''                 | ''       | 'CH2106K1B24'     |'C0402'| '(C0402-0201)'                                                       | '1000PF'   | '50V'         | '10%'    | 'DISCRETE' | 'CAP CHIP 1000P 50V(+10%,X7R,0402)AEC'                         | 'CHIP0402'     | ''          | ''   | '20160104'
 '1000PF'   | '50V'   | '10%'     | 'C0402'     | 'EMPTY'   | 'CH2106K1B24'(!)   = ''              | ''                 | ''       | 'CH2106K1B24'     |'C0402'| '(C0402-0201)'                                                       | 'NA'       | '50V'         | '10%'    | 'IO'       | 'CAP CHIP 1000P 50V(+10%,X7R,0402)AEC'                         | 'CHIP0402'     | ''          | ''   | '20160104'
 '10UF'     | '10V'   | '20%'     | 'C0603'     | 'X6S'     | 'CH6102ME903'(!)   = ''              | ''                 | ''       | 'CH6102ME903'     |'C0603'| '(SMC0603AW)'                                                        | '10UF'     | '10V'         | '20%'    | 'DISCRETE' | 'CAP CHIP 10U 10V(+-20%,X6S,0603)AEC'                          | 'CHIP0603'     | ''          | ''   | '20160104'
 '10UF'     | '10V'   | '20%'     | 'C0603'     | 'EMPTY'   | 'CH6102ME903'(!)   = ''              | ''                 | ''       | 'CH6102ME903'     |'C0603'| '(SMC0603AW)'                                                        | 'NA'       | '10V'         | '20%'    | 'IO'       | 'CAP CHIP 10U 10V(+-20%,X6S,0603)AEC'                          | 'CHIP0603'     | ''          | ''   | '20160104'
 '10UF'     | '4V'    | '20%'     | 'C0603'     | 'X6S'     | 'CH610KME907'(!)   = ''              | ''                 | ''       | 'CH610KME907'     |'C0603'| '(SMC0603AW)'                                                        | '10UF'     | '4V'          | '20%'    | 'DISCRETE' | 'CAP CHIP 10U 4V(+-20%,X6S,0603)AEC'                           | 'CHIP0603'     | ''          | ''   | '20160104'
 '10UF'     | '4V'    | '20%'     | 'C0603'     | 'EMPTY'   | 'CH610KME907'(!)   = ''              | ''                 | ''       | 'CH610KME907'     |'C0603'| '(SMC0603AW)'                                                        | 'NA'       | '4V'          | '20%'    | 'IO'       | 'CAP CHIP 10U 4V(+-20%,X6S,0603)AEC'                           | 'CHIP0603'     | ''          | ''   | '20160104'
 '1UF'      | '16V'   | '10%'     | 'C0603'     | 'X7R'     | 'CH5103K1912'(!)   = ''              | ''                 | ''       | 'CH5103K1912'     |'C0603'| '(SMC0603AW)'                                                        | '1UF'      | '16V'         | '10%'    | 'DISCRETE' | 'CAP CHIP 1U 16V(+-10%,X7R,0603)AEC'                           | 'CHIP0603'     | ''          | ''   | '20160104'
 '1UF'      | '16V'   | '10%'     | 'C0603'     | 'EMPTY'   | 'CH5103K1912'(!)   = ''              | ''                 | ''       | 'CH5103K1912'     |'C0603'| '(SMC0603AW)'                                                        | 'NA'       | '16V'         | '10%'    | 'IO'       | 'CAP CHIP 1U 16V(+-10%,X7R,0603)AEC'                           | 'CHIP0603'     | ''          | ''   | '20160104'
 '1UF'      | '16V'   | '10%'     | 'C0402'     | 'X6S'     | 'CH5103KEB05'(!)   = ''              | ''                 | ''       | 'CH5103KEB05'     |'C0402'| '(C0402-0201)'                                                       | '1UF'      | '16V'         | '10%'    | 'DISCRETE' | 'CAP CHIP 1U 16V(10%,X6S,0402)AEC'                             | 'CHIP0402'     | ''          | ''   | '20160104'
 '1UF'      | '16V'   | '10%'     | 'C0402'     | 'EMPTY'   | 'CH5103KEB05'(!)   = ''              | ''                 | ''       | 'CH5103KEB05'     |'C0402'| '(C0402-0201)'                                                       | 'NA'       | '16V'         | '10%'    | 'IO'       | 'CAP CHIP 1U 16V(10%,X6S,0402)AEC'                             | 'CHIP0402'     | ''          | ''   | '20160104'
 '1UF'      | '25V'   | '10%'     | 'C0402'     | 'X6S'     | 'CH5104KEB05'(!)   = ''              | ''                 | ''       | 'CH5104KEB05'     |'C0402'| '(C0402-0201)'                                                       | '1UF'      | '25V'         | '10%'    | 'DISCRETE' | 'CAP CHIP 1U 25V(+-10%,X6S,0402)AEC'                           | 'CHIP0402'     | ''          | ''   | '20160104'
 '1UF'      | '25V'   | '10%'     | 'C0402'     | 'EMPTY'   | 'CH5104KEB05'(!)   = ''              | ''                 | ''       | 'CH5104KEB05'     |'C0402'| '(C0402-0201)'                                                       | 'NA'       | '25V'         | '10%'    | 'IO'       | 'CAP CHIP 1U 25V(+-10%,X6S,0402)AEC'                           | 'CHIP0402'     | ''          | ''   | '20160104'
 '1UF'      | '6.3V'  | '10%'     | 'C0402'     | 'X7R'     | 'CH5101K1B08'(!)   = ''              | ''                 | ''       | 'CH5101K1B08'     |'C0402'| '(C0402-0201)'                                                       | '1UF'      | '6.3V'        | '10%'    | 'DISCRETE' | 'CAP CHIP 1U 6.3V(+-10%,X7R,0402)AEC'                          | 'CHIP0402'     | ''          | ''   | '20160104'
 '1UF'      | '6.3V'  | '10%'     | 'C0402'     | 'EMPTY'   | 'CH5101K1B08'(!)   = ''              | ''                 | ''       | 'CH5101K1B08'     |'C0402'| '(C0402-0201)'                                                       | 'NA'       | '6.3V'        | '10%'    | 'IO'       | 'CAP CHIP 1U 6.3V(+-10%,X7R,0402)AEC'                          | 'CHIP0402'     | ''          | ''   | '20160104'
 '2.2UF'    | '10V'   | '10%'     | 'C0402'     | 'X6S'     | 'CH5222KEB03'(!)   = ''              | ''                 | ''       | 'CH5222KEB03'     |'C0402'| '(C0402-0201)'                                                       | '2.2UF'    | '10V'         | '10%'    | 'DISCRETE' | 'CAP CHIP 2.2U 10V(+-10%,X6S,0402)AEC'                         | 'CHIP0402'     | ''          | ''   | '20160104'
 '2.2UF'    | '10V'   | '10%'     | 'C0402'     | 'EMPTY'   | 'CH5222KEB03'(!)   = ''              | ''                 | ''       | 'CH5222KEB03'     |'C0402'| '(C0402-0201)'                                                       | 'NA'       | '10V'         | '10%'    | 'IO'       | 'CAP CHIP 2.2U 10V(+-10%,X6S,0402)AEC'                         | 'CHIP0402'     | ''          | ''   | '20160104'
 '10UF'     | '16V'   | '10%'     | 'C0805'     | 'X7S'     | 'CH6103K6A00'(!)   = ''              | ''                 | ''       | 'CH6103K6A00'     |'C0805_H57'| '(SMC0805AW)'                                                        | '10UF'     | '16V'         | '10%'    | 'DISCRETE' | 'CAP CHIP 10U 16V(+-10%,X7S,0805)AEC'                          | 'CHIP0805'     | ''          | ''   | '20160106'
 '10UF'     | '16V'   | '10%'     | 'C0805'     | 'EMPTY'   | 'CH6103K6A00'(!)   = ''              | ''                 | ''       | 'CH6103K6A00'     |'C0805_H57'| '(SMC0805AW)'                                                        | 'NA'       | '16V'         | '10%'    | 'IO'       | 'CAP CHIP 10U 16V(+-10%,X7S,0805)AEC'                          | 'CHIP0805'     | ''          | ''   | '20160106'
 '10UF'     | '6.3V'  | '10%'     | 'C0805'     | 'X7R'     | 'CH6101K1A01'(!)   = ''              | ''                 | ''       | 'CH6101K1A01'     |'C0805_H57'| '(SMC0805AW)'                                                        | '10UF'     | '6.3V'        | '10%'    | 'DISCRETE' | 'CAP CHIP 10U 6.3V(+-10%,X7R,0805)AEC'                         | 'CHIP0805'     | ''          | ''   | '20160106'
 '10UF'     | '6.3V'  | '10%'     | 'C0805'     | 'EMPTY'   | 'CH6101K1A01'(!)   = ''              | ''                 | ''       | 'CH6101K1A01'     |'C0805_H57'| '(SMC0805AW)'                                                        | 'NA'       | '6.3V'        | '10%'    | 'IO'       | 'CAP CHIP 10U 6.3V(+-10%,X7R,0805)AEC'                         | 'CHIP0805'     | ''          | ''   | '20160106'
 '2.2UF'    | '10V'   | '10%'     | 'C0805'     | 'X7R'     | 'CH5222K1A01'(!)   = 'End of Design' | 'Comp-Approve'     | ''       | 'CH5222K1A01'     |'C0805_H57'| '(SMC0805AW)'                                                        | '2.2UF'    | '10V'         | '10%'    | 'DISCRETE' | 'CAP CHIP 2.2U 10V(+-10%,X7R,0805)AEC'                         | 'CHIP0805'     | ''          | ''   | '20160106'
 '2.2UF'    | '10V'   | '10%'     | 'C0805'     | 'EMPTY'   | 'CH5222K1A01'(!)   = 'End of Design' | 'Comp-Approve'     | ''       | 'CH5222K1A01'     |'C0805_H57'| '(SMC0805AW)'                                                        | 'NA'       | '10V'         | '10%'    | 'IO'       | 'CAP CHIP 2.2U 10V(+-10%,X7R,0805)AEC'                         | 'CHIP0805'     | ''          | ''   | '20160106'
 '22UF'     | '10V'   | '20%'     | 'C0805'     | 'X6S'     | 'CH6222MEA03'(!)   = ''              | ''                 | ''       | 'CH6222MEA03'     |'C0805_H57'| '(SMC0805AW)'                                                        | '22UF'     | '10V'         | '20%'    | 'DISCRETE' | 'CAP CHIP 22U 10V(+-20%,X6S,0805)AEC'                          | 'CHIP0805'     | ''          | ''   | '20160106'
 '22UF'     | '10V'   | '20%'     | 'C0805'     | 'EMPTY'   | 'CH6222MEA03'(!)   = ''              | ''                 | ''       | 'CH6222MEA03'     |'C0805_H57'| '(SMC0805AW)'                                                        | 'NA'       | '10V'         | '20%'    | 'IO'       | 'CAP CHIP 22U 10V(+-20%,X6S,0805)AEC'                          | 'CHIP0805'     | ''          | ''   | '20160106'
 '4.7UF'    | '16V'   | '10%'     | 'C0805'     | 'X7R'     | 'CH5473K1A03'(!)   = 'End of Design' | 'Comp-Approve'     | ''       | 'CH5473K1A03'     |'C0805_H57'| '(SMC0805AW)'                                                        | '4.7UF'    | '16V'         | '10%'    | 'DISCRETE' | 'CAP CHIP 4.7UF 16V(+-10%,X7R,0805)AEC'                        | 'CHIP0805'     | ''          | ''   | '20160106'
 '4.7UF'    | '16V'   | '10%'     | 'C0805'     | 'EMPTY'   | 'CH5473K1A03'(!)   = 'End of Design' | 'Comp-Approve'     | ''       | 'CH5473K1A03'     |'C0805_H57'| '(SMC0805AW)'                                                        | 'NA'       | '16V'         | '10%'    | 'IO'       | 'CAP CHIP 4.7UF 16V(+-10%,X7R,0805)AEC'                        | 'CHIP0805'     | ''          | ''   | '20160106'
 '47UF'     | '4V'    | '20%'     | 'C0805'     | 'X6S'     | 'CH647KMEA07'(!)   = ''              | ''                 | ''       | 'CH647KMEA07'     |'C0805_H57'| '(SMC0805AW)'                                                        | '47UF'     | '4V'          | '20%'    | 'DISCRETE' | 'CAP CHIP 47U 4V(+-20%,X6S,0805)AEC'                           | 'CHIP0805'     | ''          | ''   | '20160106'
 '47UF'     | '4V'    | '20%'     | 'C0805'     | 'EMPTY'   | 'CH647KMEA07'(!)   = ''              | ''                 | ''       | 'CH647KMEA07'     |'C0805_H57'| '(SMC0805AW)'                                                        | 'NA'       | '4V'          | '20%'    | 'IO'       | 'CAP CHIP 47U 4V(+-20%,X6S,0805)AEC'                           | 'CHIP0805'     | ''          | ''   | '20160106'
 '22UF'     | '6.3V'  | '20%'     | 'C0805'     | 'X7T'     | 'CH6221MJA00'(!)   = ''              | ''                 | ''       | 'CH6221MJA00'     |'C0805_H57'| '(SMC0805AW)'                                                        | '22UF'     | '6.3V'        | '20%'    | 'DISCRETE' | 'CAP CHIP 22U 6.3V(+-20%,X7T,0805)AEC'                         | 'CHIP0805'     | ''          | ''   | '20160106'
 '22UF'     | '6.3V'  | '20%'     | 'C0805'     | 'EMPTY'   | 'CH6221MJA00'(!)   = ''              | ''                 | ''       | 'CH6221MJA00'     |'C0805_H57'| '(SMC0805AW)'                                                        | 'NA'       | '6.3V'        | '20%'    | 'IO'       | 'CAP CHIP 22U 6.3V(+-20%,X7T,0805)AEC'                         | 'CHIP0805'     | ''          | ''   | '20160106'
 '4.7UF'    | '6.3V'  | '10%'     | 'C0603'     | 'X6S'     | 'CH5471KE905'(!)   = ''              | ''                 | ''       | 'CH5471KE905'     |'C0603'| '(SMC0603AW)'                                                        | '4.7UF'    | '6.3V'        | '10%'    | 'DISCRETE' | 'CAP CHIP 4.7U 6.3V(+-10%,X6S,0603)AEC'                        | 'CHIP0603'     | ''          | ''   | '20160106'
 '4.7UF'    | '6.3V'  | '10%'     | 'C0603'     | 'EMPTY'   | 'CH5471KE905'(!)   = ''              | ''                 | ''       | 'CH5471KE905'     |'C0603'| '(SMC0603AW)'                                                        | 'NA'       | '6.3V'        | '10%'    | 'IO'       | 'CAP CHIP 4.7U 6.3V(+-10%,X6S,0603)AEC'                        | 'CHIP0603'     | ''          | ''   | '20160106'
 '470PF'    | '50V'   | '10%'     | 'C0402'     | 'X7R'     | 'CH1476K1B13'(!)   = ''              | ''                 | ''       | 'CH1476K1B13'     |'C0402'| '(C0402-0201)'                                                       | '470PF'    | '50V'         | '10%'    | 'DISCRETE' | 'CAP CHIP 470P 50V(+10%,X7R,0402)AEC'                          | 'CHIP0402'     | ''          | ''   | '20160106'
 '470PF'    | '50V'   | '10%'     | 'C0402'     | 'EMPTY'   | 'CH1476K1B13'(!)   = ''              | ''                 | ''       | 'CH1476K1B13'     |'C0402'| '(C0402-0201)'                                                       | 'NA'       | '50V'         | '10%'    | 'IO'       | 'CAP CHIP 470P 50V(+10%,X7R,0402)AEC'                          | 'CHIP0402'     | ''          | ''   | '20160106'
 '47PF'     | '50V'   | '5%'      | 'C0402'     | 'C0G'     | 'CH0476J0B13'(!)   = ''              | ''                 | ''       | 'CH0476J0B13'     |'C0402'| '(C0402-0201)'                                                       | '47PF'     | '50V'         | '5%'     | 'DISCRETE' | 'CAP CHIP 47P 50V(+5%,C0G,0402)AEC'                            | 'CHIP0402'     | ''          | ''   | '20160106'
 '47PF'     | '50V'   | '5%'      | 'C0402'     | 'EMPTY'   | 'CH0476J0B13'(!)   = ''              | ''                 | ''       | 'CH0476J0B13'     |'C0402'| '(C0402-0201)'                                                       | 'NA'       | '50V'         | '5%'     | 'IO'       | 'CAP CHIP 47P 50V(+5%,C0G,0402)AEC'                            | 'CHIP0402'     | ''          | ''   | '20160106'
 '10UF'     | '6.3V'  | '20%'     | 'C0402'     | 'X6S'     | 'CH6101MEB03'(!)   = ''              | ''                 | ''       | 'CH6101MEB03'     |'C0402'| '(C0402_OCTAGONXA,C0402-0201)'                                       | '10UF'     | '6.3V'        | '20%'    | 'DISCRETE' | 'CAP CHIP 10UF 6.3V(+-20%,X6S,0402)MUR'                        | 'CHIP0402'     | ''          | ''   | '20160111'
 '10UF'     | '6.3V'  | '20%'     | 'C0402'     | 'EMPTY'   | 'CH6101MEB03'(!)   = ''              | ''                 | ''       | 'CH6101MEB03'     |'C0402'| '(C0402_OCTAGONXA,C0402-0201)'                                       | 'NA'       | '6.3V'        | '20%'    | 'IO'       | 'CAP CHIP 10UF 6.3V(+-20%,X6S,0402)MUR'                        | 'CHIP0402'     | ''          | ''   | '20160111'
 '47UF'     | '6.3V'  | '20%'     | 'C1206'     | 'X6S'     | 'CH6471ME203'(!)   = ''              | ''                 | ''       | 'CH6471ME203'     |'C1206_H76'| '(SMC1206AW)'                                                        | '47UF'     | '6.3V'        | '20%'    | 'DISCRETE' | 'CAP CHIP 47U 6.3V(+-20%,X6S,1206)AEC'                         | 'CHIP1206'     | ''          | ''   | '20160111'
 '47UF'     | '6.3V'  | '20%'     | 'C1206'     | 'EMPTY'   | 'CH6471ME203'(!)   = ''              | ''                 | ''       | 'CH6471ME203'     |'C1206_H76'| '(SMC1206AW)'                                                        | 'NA'       | '6.3V'        | '20%'    | 'IO'       | 'CAP CHIP 47U 6.3V(+-20%,X6S,1206)AEC'                         | 'CHIP1206'     | ''          | ''   | '20160111'
 '22UF'     | '25V'   | '10%'     | 'C1206'     | 'X5R'     | 'CH6224K9203'(!)   = ''              | ''                 | ''       | 'CH6224K9203'     |'C1206_H76'| '(SMC1206AW)'                                                        | '22UF'     | '25V'         | '10%'    | 'DISCRETE' | 'CAP CHIP 22U 25V(+-10%,X5R,1206)AEC'                          | 'CHIP1206'     | ''          | ''   | '20160111'
 '22UF'     | '25V'   | '10%'     | 'C1206'     | 'EMPTY'   | 'CH6224K9203'(!)   = ''              | ''                 | ''       | 'CH6224K9203'     |'C1206_H76'| '(SMC1206AW)'                                                        | 'NA'       | '25V'         | '10%'    | 'IO'       | 'CAP CHIP 22U 25V(+-10%,X5R,1206)AEC'                          | 'CHIP1206'     | ''          | ''   | '20160111'
 '10UF'     | '25V'   | '10%'     | 'C1206'     | 'X7S'     | 'CH6104K6200'(!)   = ''              | ''                 | ''       | 'CH6104K6200'     |'C1206_H76'| '(SMC1206AW)'                                                        | '10UF'     | '25V'         | '10%'    | 'DISCRETE' | 'CAP CHIP 10U 25V(+-10%,X7S,1206)AEC'                          | 'CHIP1206'     | ''          | ''   | '20160111'
 '10UF'     | '25V'   | '10%'     | 'C1206'     | 'EMPTY'   | 'CH6104K6200'(!)   = ''              | ''                 | ''       | 'CH6104K6200'     |'C1206_H76'| '(SMC1206AW)'                                                        | 'NA'       | '25V'         | '10%'    | 'IO'       | 'CAP CHIP 10U 25V(+-10%,X7S,1206)AEC'                          | 'CHIP1206'     | ''          | ''   | '20160111'
 '10UF'     | '16V'   | '10%'     | 'C1206'     | 'X7R'     | 'CH6103K1202'(!)   = ''              | ''                 | ''       | 'CH6103K1202'     |'C1206_H76'| '(SMC1206AW)'                                                        | '10UF'     | '16V'         | '10%'    | 'DISCRETE' | 'CAP CHIP 10U 16V(+-10%,X7R,1206)AEC'                          | 'CHIP1206'     | ''          | ''   | '20160111'
 '10UF'     | '16V'   | '10%'     | 'C1206'     | 'EMPTY'   | 'CH6103K1202'(!)   = ''              | ''                 | ''       | 'CH6103K1202'     |'C1206_H76'| '(SMC1206AW)'                                                        | 'NA'       | '16V'         | '10%'    | 'IO'       | 'CAP CHIP 10U 16V(+-10%,X7R,1206)AEC'                          | 'CHIP1206'     | ''          | ''   | '20160111'
 '0.01UF'   | '50V'   | '5%'      | 'C0603'     | 'X7R'     | 'CH3106J1900'(!)   = 'End of Design' | 'Comp-Approve'     | ''       | 'CH3106J1900'     |'C0603'| '(SMC0603AW)'                                                        | '0.01UF'   | '50V'         | '10%'    | 'DISCRETE' | 'CAP CHIP 0.01U 50V(+-5%,X7R,0603)MUR'                         | 'CHIP0603'     | ''          | ''   | '20161113'
 '0.01UF'   | '50V'   | '5%'      | 'C0603'     | 'EMPTY'   | 'CH3106J1900'(!)   = 'End of Design' | 'Comp-Approve'     | ''       | 'CH3106J1900'     |'C0603'| '(SMC0603AW)'                                                        | 'NA'       | '50V'         | '10%'    | 'IO'       | 'CAP CHIP 0.01U 50V(+-5%,X7R,0603)MUR'                         | 'CHIP0603'     | ''          | ''   | '20161113'
 '0.1UF'    | '25V'   | '10%'     | '0402'      | 'X7R'     | 'CH4104K1B00'(!)   = ''              | ''                 | ''       | 'CH4104K1B00'     |'C0402'| '(C0402_OCTAGONXA,C0402-0201)'                                       | '0.1UF'    | '25V'         | '10%'    | 'DISCRETE' | 'CAP CHIP 0.1U 25V(+-10%,X7R,0402)'                            | 'CHIP0402'     | ''          | ''   | '20160113'
 '0.1UF'    | '25V'   | '10%'     | '0402'      | 'EMPTY'   | 'CH4104K1B00'(!)   = ''              | ''                 | ''       | 'CH4104K1B00'     |'C0402'| '(C0402_OCTAGONXA,C0402-0201)'                                       | 'NA'       | '25V'         | '10%'    | 'IO'       | 'CAP CHIP 0.1U 25V(+-10%,X7R,0402)'                            | 'CHIP0402'     | ''          | ''   | '20160113'
 '0.033UF'  | '50V'   | '10%'     | 'C0603'     | 'X7R'     | 'CH3336K1905'(!)   = 'End of Design' | 'Comp-Approve'     | ''       | 'CH3336K1905'     |'C0603'| '(SMC0603AW)'                                                        | '0.033UF'  | '50V'         | '10%'    | 'DISCRETE' | 'CAP CHIP 0.033U 50V(+-10%,X7R,0603)MUR'                       | 'CHIP0603'     | ''          | ''   | '20160114'
 '0.033UF'  | '50V'   | '10%'     | 'C0603'     | 'EMPTY'   | 'CH3336K1905'(!)   = 'End of Design' | 'Comp-Approve'     | ''       | 'CH3336K1905'     |'C0603'| '(SMC0603AW)'                                                        | 'NA'       | '50V'         | '10%'    | 'IO'       | 'CAP CHIP 0.033U 50V(+-10%,X7R,0603)MUR'                       | 'CHIP0603'     | ''          | ''   | '20160114'
 '8200PF'   | '25V'   | '10%'     | 'C0402'     | 'X7R'     | 'CH2824K1B04'(!)   = ''              | ''                 | ''       | 'CH2824K1B04'     |'C0402'| '(C0402-0201)'                                                       | '8200PF'   | '25V'         | '10%'    | 'DISCRETE' | 'CAP CHIP 8200P 25V (+-10%.X7R.0402)MUR'                       | 'CHIP0402'     | ''          | ''   | '20160115'
 '8200PF'   | '25V'   | '10%'     | 'C0402'     | 'EMPTY'   | 'CH2824K1B04'(!)   = ''              | ''                 | ''       | 'CH2824K1B04'     |'C0402'| '(C0402-0201)'                                                       | 'NA'       | '25V'         | '10%'    | 'IO'       | 'CAP CHIP 8200P 25V (+-10%.X7R.0402)MUR'                       | 'CHIP0402'     | ''          | ''   | '20160115'
 '22UF'     | '25V'   | '20%'     | 'C1206'     | 'X7S'     | 'CH6224M6201'(!)   = ''              | ''                 | ''       | 'CH6224M6201'     |'C1206_H76'| '(SMC1206AW)'                                                        | '22UF'     | '25V'         | '20%'    | 'DISCRETE' | 'CAP CHIP 22UF 25V(+-20%,X7S,1206)MUR'                         | 'CHIP1206'     | ''          | ''   | '20160115'
 '22UF'     | '25V'   | '20%'     | 'C1206'     | 'EMPTY'   | 'CH6224M6201'(!)   = ''              | ''                 | ''       | 'CH6224M6201'     |'C1206_H76'| '(SMC1206AW)'                                                        | 'NA'       | '25V'         | '20%'    | 'IO'       | 'CAP CHIP 22UF 25V(+-20%,X7S,1206)MUR'                         | 'CHIP1206'     | ''          | ''   | '20160115'
 '6800PF'   | '50V'   | '10%'     | 'C0402'     | 'X7R'     | 'CH2686K1B03'(!)   = ''              | ''                 | ''       | 'CH2686K1B03'     |'C0402'| '(C0402-0201)'                                                       | '6800PF'   | '50V'         | '10%'    | 'DISCRETE' | 'CAP CHIP 6800P 50V(+-10%,X7R,0402)MUR'                        | 'CHIP0402'     | ''          | ''   | '20160118'
 '6800PF'   | '50V'   | '10%'     | 'C0402'     | 'EMPTY'   | 'CH2686K1B03'(!)   = ''              | ''                 | ''       | 'CH2686K1B03'     |'C0402'| '(C0402-0201)'                                                       | 'NA'       | '50V'         | '10%'    | 'IO'       | 'CAP CHIP 6800P 50V(+-10%,X7R,0402)MUR'                        | 'CHIP0402'     | ''          | ''   | '20160118'
 '10UF'     | '10V'   | '20%'     | 'C0402'     | 'X5R'     | 'CH6102M9B00'(!)   = ''              | ''                 | ''       | 'CH6102M9B00'     |'C0402'| '(C0402-0201)'                                                       | '10UF'     | '10V'         | '20%'    | 'DISCRETE' | 'CAP CHIP 10U 10V (+-20%, X5R, 0402)'                          | 'CHIP0402'     | ''          | ''   | '20160118'
 '10UF'     | '10V'   | '20%'     | 'C0402'     | 'EMPTY'   | 'CH6102M9B00'(!)   = ''              | ''                 | ''       | 'CH6102M9B00'     |'C0402'| '(C0402-0201)'                                                       | 'NA'       | '10V'         | '20%'    | 'IO'       | 'CAP CHIP 10U 10V (+-20%, X5R, 0402)'                          | 'CHIP0402'     | ''          | ''   | '20160118'
 '22UF'     | '16V'   | '20%'     | 'C0805'     | 'X6S'     | 'CH6223MEA00'(!)   = ''              | ''                 | ''       | 'CH6223MEA00'     |'C0805_H57'| '(SMC0805AW)'                                                        | '22UF'     | '16V'         | '20%'    | 'DISCRETE' | 'CAP CHIP 22U 16V(+-20%,X6S,0805)'                             | 'CHIP0805'     | ''          | ''   | '2016019' 
 '22UF'     | '16V'   | '20%'     | 'C0805'     | 'EMPTY'   | 'CH6223MEA00'(!)   = ''              | ''                 | ''       | 'CH6223MEA00'     |'C0805_H57'| '(SMC0805AW)'                                                        | 'NA'       | '16V'         | '20%'    | 'IO'       | 'CAP CHIP 22U 16V(+-20%,X6S,0805)'                             | 'CHIP0805'     | ''          | ''   | '2016019' 
 '47NF'     | '100V'  | '10%'     | 'C1206'     | 'X7R'     | 'CH3478K1200'(!)   = ''              | ''                 | ''       | 'CH3478K1200'     |'C1206_H56'| '(SMC1206AW)'                                                        | '47NF'     | '100V'        | '10%'    | 'DISCRETE' | 'CAP CHIP 47N 100V (+-10%,X7R,1206)MUR'                        | 'CHIP1206'     | ''          | ''   | '20160219'
 '47NF'     | '100V'  | '10%'     | 'C1206'     | 'EMPTY'   | 'CH3478K1200'(!)   = ''              | ''                 | ''       | 'CH3478K1200'     |'C1206_H56'| '(SMC1206AW)'                                                        | 'NA'       | '100V'        | '10%'    | 'IO'       | 'CAP CHIP 47N 100V (+-10%,X7R,1206)MUR'                        | 'CHIP1206'     | ''          | ''   | '20160219'
 '22UF'     | '10V'   | '20%'     | 'C0805'     | 'X5R'     | 'CH6222M9A02'(!)   = 'End of Design' | 'Comp-Approve'     | ''       | 'CH6222M9A02'     |'C0805_H61'| '(SMC0805AW)'                                                        | '22UF'     | '10V'         | '20%'    | 'DISCRETE' | 'CAP CHIP 22U 10V(+-20%,X5R,0805)'                             | 'CHIP0805'     | ''          | ''   | '20160226'
 '22UF'     | '10V'   | '20%'     | 'C0805'     | 'EMPTY'   | 'CH6222M9A02'(!)   = 'End of Design' | 'Comp-Approve'     | ''       | 'CH6222M9A02'     |'C0805_H61'| '(SMC0805AW)'                                                        | 'NA'       | '10V'         | '20%'    | 'IO'       | 'CAP CHIP 22U 10V(+-20%,X5R,0805)'                             | 'CHIP0805'     | ''          | ''   | '20160226'
 '33000PF'  | '50V'   | '5%'      | 'C0805'     | 'U2J'     | 'CH3336JFA00'(!)   = ''              | ''                 | ''       | 'CH3336JFA00'     |'C0805_H43'| '(SMC0805AW)'                                                        | '33000PF'  | '50V'         | '5%'     | 'DISCRETE' | 'CAP CHIP 33000P 50V(+-5%,U2J,0805)'                           | 'CHIP0805'     | ''          | ''   | '20160310'
 '33000PF'  | '50V'   | '5%'      | 'C0805'     | 'EMPTY'   | 'CH3336JFA00'(!)   = ''              | ''                 | ''       | 'CH3336JFA00'     |'C0805_H43'| '(SMC0805AW)'                                                        | 'NA'       | '50V'         | '5%'     | 'IO'       | 'CAP CHIP 33000P 50V(+-5%,U2J,0805)'                           | 'CHIP0805'     | ''          | ''   | '20160310'
 '39000PF'  | '50V'   | '5%'      | 'C0805'     | 'U2J'     | 'CH3396JFA00'(!)   = ''              | ''                 | ''       | 'CH3396JFA00'     |'C0805_H57'| '(SMC0805AW)'                                                        | '39000PF'  | '50V'         | '5%'     | 'DISCRETE' | 'CAP CHIP 39000P 50V(+-5%,U2J,0805)'                           | 'CHIP0805'     | ''          | ''   | '20160310'
 '39000PF'  | '50V'   | '5%'      | 'C0805'     | 'EMPTY'   | 'CH3396JFA00'(!)   = ''              | ''                 | ''       | 'CH3396JFA00'     |'C0805_H57'| '(SMC0805AW)'                                                        | 'NA'       | '50V'         | '5%'     | 'IO'       | 'CAP CHIP 39000P 50V(+-5%,U2J,0805)'                           | 'CHIP0805'     | ''          | ''   | '20160310'
 '220PF'    | '50V'   | '5%'      | 'C0402'     | 'C0G'     | 'CH12206JB00'(!)   = ''              | ''                 | ''       | 'CH12206JB00'     |'C0402'| '(C0402-0201)'                                                       | '220PF'    | '50V'         | '5%'     | 'DISCRETE' | 'CAP CHIP 220P 50V(+-5%.COG.0402)'                             | 'CHIP0402'     | ''          | ''   | '20160314'
 '220PF'    | '50V'   | '5%'      | 'C0402'     | 'EMPTY'   | 'CH12206JB00'(!)   = ''              | ''                 | ''       | 'CH12206JB00'     |'C0402'| '(C0402-0201)'                                                       | 'NA'       | '50V'         | '5%'     | 'IO'       | 'CAP CHIP 220P 50V(+-5%.COG.0402)'                             | 'CHIP0402'     | ''          | ''   | '20160314'
 '560PF'    | '50V'   | '5%'      | 'C0402'     | 'C0G'     | 'CH1566J0B00'(!)   = ''              | ''                 | ''       | 'CH1566J0B00'     |'C0402'| '(C0402-0201)'                                                       | '560PF'    | '50V'         | '5%'     | 'DISCRETE' | 'CAP CHIP 560P 50V(+-5%,C0G,0402)'                             | 'CHIP0402'     | ''          | ''   | '20160314'
 '560PF'    | '50V'   | '5%'      | 'C0402'     | 'EMPTY'   | 'CH1566J0B00'(!)   = ''              | ''                 | ''       | 'CH1566J0B00'     |'C0402'| '(C0402-0201)'                                                       | 'NA'       | '50V'         | '5%'     | 'IO'       | 'CAP CHIP 560P 50V(+-5%,C0G,0402)'                             | 'CHIP0402'     | ''          | ''   | '20160314'
 '1200PF'   | '50V'   | '10%'     | 'C0402'     | 'X7R'     | 'CH2126K1B05'(!)   = ''              | ''                 | ''       | 'CH2126K1B05'     |'C0402'| '(C0402-0201)'                                                       | '1200PF'   | '50V'         | '10%'    | 'DISCRETE' | 'CAP CHIP 1200P 50V(+-10%.X7R.0402)'                           | 'CHIP0402'     | ''          | ''   | '20160322'
 '1200PF'   | '50V'   | '10%'     | 'C0402'     | 'EMPTY'   | 'CH2126K1B05'(!)   = ''              | ''                 | ''       | 'CH2126K1B05'     |'C0402'| '(C0402-0201)'                                                       | 'NA'       | '50V'         | '10%'    | 'IO'       | 'CAP CHIP 1200P 50V(+-10%.X7R.0402)'                           | 'CHIP0402'     | ''          | ''   | '20160322'
 '0.01UF'   | '100V'  | '5%'      | 'C1206'     | 'C0G'     | 'CH3108J0200'(!)   = ''              | ''                 | ''       | 'CH3108J0200'     |'C1206_H42'| '(SMC1206AW)'                                                        | '0.01UF'   | '100V'        | '5%'     | 'DISCRETE' | 'CAP CHIP 0.01U 100V(+-5%,C0G,1206)MUR'                        | 'CHIP1206'     | ''          | ''   | '20160324'
 '0.01UF'   | '100V'  | '5%'      | 'C1206'     | 'EMPTY'   | 'CH3108J0200'(!)   = ''              | ''                 | ''       | 'CH3108J0200'     |'C1206_H42'| '(SMC1206AW)'                                                        | 'NA'       | '100V'        | '5%'     | 'IO'       | 'CAP CHIP 0.01U 100V(+-5%,C0G,1206)MUR'                        | 'CHIP1206'     | ''          | ''   | '20160324'
 '27PF'     | '50V'   | '5%'      | 'C0402'     | 'C0G'     | 'CH0276J0B07'(!)   = ''              | ''                 | ''       | 'CH0276J0B07'     |'C0402'| '(C0402-0201)'                                                       | '27PF'     | '50V'         | '5%'     | 'DISCRETE' | 'CAP CHIP 27P 50V(+-5%,C0G,0402)AEC'                           | 'CHIP0402'     | ''          | ''   | '20160328'
 '27PF'     | '50V'   | '5%'      | 'C0402'     | 'EMPTY'   | 'CH0276J0B07'(!)   = ''              | ''                 | ''       | 'CH0276J0B07'     |'C0402'| '(C0402-0201)'                                                       | 'NA'       | '50V'         | '5%'     | 'IO'       | 'CAP CHIP 27P 50V(+-5%,C0G,0402)AEC'                           | 'CHIP0402'     | ''          | ''   | '20160328'
 '1UF'      | '10V'   | '10%'     | 'C0402'     | 'X7S'     | 'CH5102K6B01'(!)   = ''              | ''                 | ''       | 'CH5102K6B01'     |'C0402'| '(C0402-0201)'                                                       | '1UF'      | '10V'         | '10%'    | 'DISCRETE' | 'CAP CHIP 1U 10V(10%,X7S,0402)AEC'                             | 'CHIP0402'     | ''          | ''   | '20160328'
 '1UF'      | '10V'   | '10%'     | 'C0402'     | 'EMPTY'   | 'CH5102K6B01'(!)   = ''              | ''                 | ''       | 'CH5102K6B01'     |'C0402'| '(C0402-0201)'                                                       | 'NA'       | '10V'         | '10%'    | 'IO'       | 'CAP CHIP 1U 10V(10%,X7S,0402)AEC'                             | 'CHIP0402'     | ''          | ''   | '20160328'
 '0.22UF'   | '16V'   | '10%'     | 'C0402'     | 'X7R'     | 'CH4223K1B07'(!)   = ''              | ''                 | ''       | 'CH4223K1B07'     |'C0402'| '(C0402-0201)'                                                       | '0.22UF'   | '16V'         | '10%'    | 'DISCRETE' | 'CAP CHIP 0.22U 16V(10%,X7R,0402)MUR_AEC'                      | 'CHIP0402'     | ''          | ''   | '20160518'
 '0.22UF'   | '16V'   | '10%'     | 'C0402'     | 'EMPTY'   | 'CH4223K1B07'(!)   = ''              | ''                 | ''       | 'CH4223K1B07'     |'C0402'| '(C0402-0201)'                                                       | 'NA'       | '16V'         | '10%'    | 'IO'       | 'CAP CHIP 0.22U 16V(10%,X7R,0402)MUR_AEC'                      | 'CHIP0402'     | ''          | ''   | '20160518'
 '0.01UF'   | '50V'   | '10%'     | 'C0402'     | 'X7R'     | 'CH3106K1B09'(!)   = ''              | ''                 | ''       | 'CH3106K1B09'     |'C0402'| '(C0402-0201)'                                                       | '0.01UF'   | '50V'         | '10%'    | 'DISCRETE' | 'CAP CHIP 0.01U 50V(10%,X7R,0402)MUR_AEC'                      | 'CHIP0402'     | ''          | ''   | '20160518'
 '0.01UF'   | '50V'   | '10%'     | 'C0402'     | 'EMPTY'   | 'CH3106K1B09'(!)   = ''              | ''                 | ''       | 'CH3106K1B09'     |'C0402'| '(C0402-0201)'                                                       | 'NA'       | '50V'         | '10%'    | 'IO'       | 'CAP CHIP 0.01U 50V(10%,X7R,0402)MUR_AEC'                      | 'CHIP0402'     | ''          | ''   | '20160518'
 '330PF'    | '50V'   | '10%'     | 'C0402'     | 'X7R'     | 'CH1336K1B08'(!)   = ''              | ''                 | ''       | 'CH1336K1B08'     |'C0402'| '(C0402-0201)'                                                       | '330PF'    | '50V'         | '10%'    | 'DISCRETE' | 'CAP CHIP 330P 50V(10%,X7R,0402)MUR_AEC'                       | 'CHIP0402'     | ''          | ''   | '20160520'
 '330PF'    | '50V'   | '10%'     | 'C0402'     | 'EMPTY'   | 'CH1336K1B08'(!)   = ''              | ''                 | ''       | 'CH1336K1B08'     |'C0402'| '(C0402-0201)'                                                       | 'NA'       | '50V'         | '10%'    | 'IO'       | 'CAP CHIP 330P 50V(10%,X7R,0402)MUR_AEC'                       | 'CHIP0402'     | ''          | ''   | '20160520'
 '0.1UF'    | '16V'   | '10%'     | 'C0402'     | 'X7R'     | 'CH4103K1B22'(!)   = 'End of Design' | 'Comp-Approve'     | ''       | 'CH4103K1B22'     |'C0402'| '(C0402_OCTAGONXA,C0402-0201)'                                       | '0.1UF'    | '16V'         | '10%'    | 'DISCRETE' | 'CAP CHIP 0.1U 16V(10%,X7R,0402)MUR_AEC'                       | 'CHIP0402'     | ''          | ''   | '20160520'
 '0.1UF'    | '16V'   | '10%'     | 'C0402'     | 'EMPTY'   | 'CH4103K1B22'(!)   = 'End of Design' | 'Comp-Approve'     | ''       | 'CH4103K1B22'     |'C0402'| '(C0402_OCTAGONXA,C0402-0201)'                                       | 'NA'       | '16V'         | '10%'    | 'IO'       | 'CAP CHIP 0.1U 16V(10%,X7R,0402)MUR_AEC'                       | 'CHIP0402'     | ''          | ''   | '20160520'
 '2.2UF'    | '10V'   | '10%'     | 'C0402'     | 'X6S'     | 'CH5222KEB05'(!)   = ''              | ''                 | ''       | 'CH5222KEB05'     |'C0402'| '(C0402_OCTAGONXA,C0402-0201)'                                       | '2.2UF'    | '10V'         | '10%'    | 'DISCRETE' | 'CAP CHIP 2.2U 10V(10%,X6S,0402)MUR_AEC'                       | 'CHIP0402'     | ''          | ''   | '20160520'
 '2.2UF'    | '10V'   | '10%'     | 'C0402'     | 'EMPTY'   | 'CH5222KEB05'(!)   = ''              | ''                 | ''       | 'CH5222KEB05'     |'C0402'| '(C0402_OCTAGONXA,C0402-0201)'                                       | 'NA'       | '10V'         | '10%'    | 'IO'       | 'CAP CHIP 2.2U 10V(10%,X6S,0402)MUR_AEC'                       | 'CHIP0402'     | ''          | ''   | '20160520'
 '1UF'      | '6.3V'  | '10%'     | 'C0402'     | 'X7R'     | 'CH5101K1B09'(!)   = ''              | ''                 | ''       | 'CH5101K1B09'     |'C0402'| '(C0402_OCTAGONXA,C0402-0201)'                                       | '1UF'      | '6.3V'        | '10%'    | 'DISCRETE' | 'CAP CHIP 1U 6.3V(10%,X7R,0402)MUR_AEC'                        | 'CHIP0402'     | ''          | ''   | '20160520'
 '1UF'      | '6.3V'  | '10%'     | 'C0402'     | 'EMPTY'   | 'CH5101K1B09'(!)   = ''              | ''                 | ''       | 'CH5101K1B09'     |'C0402'| '(C0402_OCTAGONXA,C0402-0201)'                                       | 'NA'       | '6.3V'        | '10%'    | 'IO'       | 'CAP CHIP 1U 6.3V(10%,X7R,0402)MUR_AEC'                        | 'CHIP0402'     | ''          | ''   | '20160520'
 '0.022UF'  | '25V'   | '10%'     | 'C0402'     | 'X7R'     | 'CH3224K1B03'(!)   = ''              | ''                 | ''       | 'CH3224K1B03'     |'C0402'| '(C0402_OCTAGONXA,C0402-0201)'                                       | '0.022UF'  | '25V'         | '10%'    | 'DISCRETE' | 'CAP CHIP 0.022U 25V(+-10%,X7R,0402)MUR'                       | 'CHIP0402'     | ''          | ''   | '20160520'
 '0.022UF'  | '25V'   | '10%'     | 'C0402'     | 'EMPTY'   | 'CH3224K1B03'(!)   = ''              | ''                 | ''       | 'CH3224K1B03'     |'C0402'| '(C0402_OCTAGONXA,C0402-0201)'                                       | 'NA'       | '25V'         | '10%'    | 'IO'       | 'CAP CHIP 0.022U 25V(+-10%,X7R,0402)MUR'                       | 'CHIP0402'     | ''          | ''   | '20160520'
 '0.047UF'  | '25V'   | '10%'     | 'C0402'     | 'X7R'     | 'CH3474K1B07'(!)   = ''              | ''                 | ''       | 'CH3474K1B07'     |'C0402'| '(C0402_OCTAGONXA,C0402-0201)'                                       | '0.047UF'  | '25V'         | '10%'    | 'DISCRETE' | 'CAP CHIP 0.047U 25V(+10% X7R 0402)AEC'                        | 'CHIP0402'     | ''          | ''   | '20160520'
 '0.047UF'  | '25V'   | '10%'     | 'C0402'     | 'EMPTY'   | 'CH3474K1B07'(!)   = ''              | ''                 | ''       | 'CH3474K1B07'     |'C0402'| '(C0402_OCTAGONXA,C0402-0201)'                                       | 'NA'       | '25V'         | '10%'    | 'IO'       | 'CAP CHIP 0.047U 25V(+10% X7R 0402)AEC'                        | 'CHIP0402'     | ''          | ''   | '20160520'
 '10PF'     | '50V'   | '2%'      | 'C0402'     | 'NPO'     | 'CH0106G0B04'(!)   = ''              | ''                 | ''       | 'CH0106G0B04'     |'C0402'| '(C0402_OCTAGONXA,C0402-0201)'                                       | '10PF'     | '50V'         | '2%'     | 'DISCRETE' | 'CAP CHIP 10P 50V(+-2%,NPO,0402)AEC'                           | 'CHIP0402'     | ''          | ''   | '20160520'
 '10PF'     | '50V'   | '2%'      | 'C0402'     | 'EMPTY'   | 'CH0106G0B04'(!)   = ''              | ''                 | ''       | 'CH0106G0B04'     |'C0402'| '(C0402_OCTAGONXA,C0402-0201)'                                       | 'NA'       | '50V'         | '2%'     | 'IO'       | 'CAP CHIP 10P 50V(+-2%,NPO,0402)AEC'                           | 'CHIP0402'     | ''          | ''   | '20160520'
 '0.01UF'   | '50V'   | '10%'     | 'C0402'     | 'X7R'     | 'CH3106K1B08'(!)   = ''              | ''                 | ''       | 'CH3106K1B08'     |'C0402'| '(C0402_OCTAGONXA,C0402-0201)'                                       | '0.01UF'   | '50V'         | '10%'    | 'DISCRETE' | 'CAP CHIP 0.01U 50V(+-10%,X7R,0402)AEC'                        | 'CHIP0402'     | ''          | ''   | '20160520'
 '0.01UF'   | '50V'   | '10%'     | 'C0402'     | 'EMPTY'   | 'CH3106K1B08'(!)   = ''              | ''                 | ''       | 'CH3106K1B08'     |'C0402'| '(C0402_OCTAGONXA,C0402-0201)'                                       | 'NA'       | '50V'         | '10%'    | 'IO'       | 'CAP CHIP 0.01U 50V(+-10%,X7R,0402)AEC'                        | 'CHIP0402'     | ''          | ''   | '20160520'
 '4700PF'   | '25V'   | '10%'     | 'C0402'     | 'X7R'     | 'CH2474K1B10'(!)   = ''              | ''                 | ''       | 'CH2474K1B10'     |'C0402'| '(C0402_OCTAGONXA,C0402-0201)'                                       | '4700PF'   | '25V'         | '10%'    | 'DISCRETE' | 'CAP CHIP 4700P 25V(+-10%,X7R,0402)AEC'                        | 'CHIP0402'     | ''          | ''   | '20160520'
 '4700PF'   | '25V'   | '10%'     | 'C0402'     | 'EMPTY'   | 'CH2474K1B10'(!)   = ''              | ''                 | ''       | 'CH2474K1B10'     |'C0402'| '(C0402_OCTAGONXA,C0402-0201)'                                       | 'NA'       | '25V'         | '10%'    | 'IO'       | 'CAP CHIP 4700P 25V(+-10%,X7R,0402)AEC'                        | 'CHIP0402'     | ''          | ''   | '20160520'
 '4.7UF'    | '6.3V'  | '20%'     | 'C0402'     | 'X6S'     | 'CH5471MEB02'(!)   = ''              | ''                 | ''       | 'CH5471MEB02'     |'C0402'| '(C0402_OCTAGON,C0402_OCTAGONXA,C0402-0201,C0402_OCTAGONXA_BOUND22)' | '4.7UF'    | '6.3V'        | '20%'    | 'DISCRETE' | 'CAP CHIP 4.7UF 6.3V(+-20%,X6S,0402)MUR'                       | 'CHIP0402'     | ''          | ''   | '20160520'
 '4.7UF'    | '6.3V'  | '20%'     | 'C0402'     | 'EMPTY'   | 'CH5471MEB02'(!)   = ''              | ''                 | ''       | 'CH5471MEB02'     |'C0402'| '(C0402_OCTAGON,C0402_OCTAGONXA,C0402-0201,C0402_OCTAGONXA_BOUND22)' | 'NA'       | '6.3V'        | '20%'    | 'IO'       | 'CAP CHIP 4.7UF 6.3V(+-20%,X6S,0402)MUR'                       | 'CHIP0402'     | ''          | ''   | '20160520'
 '0.01UF'   | '16V'   | '10%'     | 'C0402'     | 'X7R'     | 'CH3103K1B16'(!)   = ''              | ''                 | ''       | 'CH3103K1B16'     |'C0402'| '(C0402_OCTAGONXA,C0402-0201)'                                       | '0.01UF'   | '16V'         | '10%'    | 'DISCRETE' | 'CAP CHIP 0.01U 16V(10%,X7R,0402)MUR'                          | 'CHIP0402'     | ''          | ''   | '20160520'
 '0.01UF'   | '16V'   | '10%'     | 'C0402'     | 'EMPTY'   | 'CH3103K1B16'(!)   = ''              | ''                 | ''       | 'CH3103K1B16'     |'C0402'| '(C0402_OCTAGONXA,C0402-0201)'                                       | 'NA'       | '16V'         | '10%'    | 'IO'       | 'CAP CHIP 0.01U 16V(10%,X7R,0402)MUR'                          | 'CHIP0402'     | ''          | ''   | '20160520'
 '0.22UF'   | '16V'   | '10%'     | 'C0402'     | 'X7R'     | 'CH4223K1B06'(!)   = ''              | ''                 | ''       | 'CH4223K1B06'     |'C0402'| '(C0402_OCTAGONXA,C0402-0201)'                                       | '0.22UF'   | '16V'         | '10%'    | 'DISCRETE' | 'CAP CHIP 0.22U 16V(10%,X7R,0402)AEC'                          | 'CHIP0402'     | ''          | ''   | '20160520'
 '0.22UF'   | '16V'   | '10%'     | 'C0402'     | 'EMPTY'   | 'CH4223K1B06'(!)   = ''              | ''                 | ''       | 'CH4223K1B06'     |'C0402'| '(C0402_OCTAGONXA,C0402-0201)'                                       | 'NA'       | '16V'         | '10%'    | 'IO'       | 'CAP CHIP 0.22U 16V(10%,X7R,0402)AEC'                          | 'CHIP0402'     | ''          | ''   | '20160520'
 '0.01UF'   | '25V'   | '10%'     | 'C0402'     | 'X7R'     | 'CH3104K1B16'(!)   = ''              | ''                 | ''       | 'CH3104K1B16'     |'C0402'| '(C0402-0201)'                                                       | '0.01UF'   | '25V'         | '10%'    | 'DISCRETE' | 'CAP CHIP 0.01U 25V(10%,X7R,0402)MUR_AEC'                      | 'CHIP0402'     | ''          | ''   | '20160525'
 '0.01UF'   | '25V'   | '10%'     | 'C0402'     | 'EMPTY'   | 'CH3104K1B16'(!)   = ''              | ''                 | ''       | 'CH3104K1B16'     |'C0402'| '(C0402-0201)'                                                       | 'NA'       | '25V'         | '10%'    | 'IO'       | 'CAP CHIP 0.01U 25V(10%,X7R,0402)MUR_AEC'                      | 'CHIP0402'     | ''          | ''   | '20160525'
 '0.047UF'  | '25V'   | '10%'     | 'C0402'     | 'X7R'     | 'CH3474K1B08'(!)   = ''              | ''                 | ''       | 'CH3474K1B08'     |'C0402'| '(C0402-0201)'                                                       | '0.047UF'  | '25V'         | '10%'    | 'DISCRETE' | 'CAP CHIP 0.047U 25V(10% X7R 0402)MUR_AEC'                     | 'CHIP0402'     | ''          | ''   | '20160525'
 '0.047UF'  | '25V'   | '10%'     | 'C0402'     | 'EMPTY'   | 'CH3474K1B08'(!)   = ''              | ''                 | ''       | 'CH3474K1B08'     |'C0402'| '(C0402-0201)'                                                       | 'NA'       | '25V'         | '10%'    | 'IO'       | 'CAP CHIP 0.047U 25V(10% X7R 0402)MUR_AEC'                     | 'CHIP0402'     | ''          | ''   | '20160525'
 '0.1UF'    | '10V'   | '10%'     | 'C0402'     | 'X7R'     | 'CH4102K1B12'(!)   = ''              | ''                 | ''       | 'CH4102K1B12'     |'C0402'| '(C0402-0201)'                                                       | '0.1UF'    | '10V'         | '10%'    | 'DISCRETE' | 'CAP CHIP 0.1U 10V(10%,X7R,0402)MUR_AEC'                       | 'CHIP0402'     | ''          | ''   | '20160525'
 '0.1UF'    | '10V'   | '10%'     | 'C0402'     | 'EMPTY'   | 'CH4102K1B12'(!)   = ''              | ''                 | ''       | 'CH4102K1B12'     |'C0402'| '(C0402-0201)'                                                       | 'NA'       | '10V'         | '10%'    | 'IO'       | 'CAP CHIP 0.1U 10V(10%,X7R,0402)MUR_AEC'                       | 'CHIP0402'     | ''          | ''   | '20160525'
 '0.1UF'    | '25V'   | '10%'     | 'C0402'     | 'X7R'     | 'CH4104K1B07'(!)   = ''              | ''                 | ''       | 'CH4104K1B07'     |'C0402'| '(C0402-0201)'                                                       | '0.1UF'    | '25V'         | '10%'    | 'DISCRETE' | 'CAP CHIP 0.1U 25V(10%,X7R,0402)MUR_AEC'                       | 'CHIP0402'     | ''          | ''   | '20160525'
 '0.1UF'    | '25V'   | '10%'     | 'C0402'     | 'EMPTY'   | 'CH4104K1B07'(!)   = ''              | ''                 | ''       | 'CH4104K1B07'     |'C0402'| '(C0402-0201)'                                                       | 'NA'       | '25V'         | '10%'    | 'IO'       | 'CAP CHIP 0.1U 25V(10%,X7R,0402)MUR_AEC'                       | 'CHIP0402'     | ''          | ''   | '20160525'
 '0.1UF'    | '25V'   | '10%'     | 'C0603'     | 'X7R'     | 'CH4104K1915'(!)   = 'End of Design' | 'Comp-Approve'     | ''       | 'CH4104K1915'     |'C0603'| '(SMC0603AW)'                                                        | '0.1UF'    | '25V'         | '10%'    | 'DISCRETE' | 'CAP CHIP 0.1U 25V(10%,X7R,0603)MUR_AEC'                       | 'CHIP0603'     | ''          | ''   | '20160525'
 '0.1UF'    | '25V'   | '10%'     | 'C0603'     | 'EMPTY'   | 'CH4104K1915'(!)   = 'End of Design' | 'Comp-Approve'     | ''       | 'CH4104K1915'     |'C0603'| '(SMC0603AW)'                                                        | 'NA'       | '25V'         | '10%'    | 'IO'       | 'CAP CHIP 0.1U 25V(10%,X7R,0603)MUR_AEC'                       | 'CHIP0603'     | ''          | ''   | '20160525'
 '0.47UF'   | '10V'   | '10%'     | 'C0402'     | 'X7S'     | 'CH4472K6B01'(!)   = ''              | ''                 | ''       | 'CH4472K6B01'     |'C0402'| '(C0402-0201)'                                                       | '0.47UF'   | '10V'         | '10%'    | 'DISCRETE' | 'CAP CHIP 0.47U 10V(10%,X7S,0402)MUR_AEC'                      | 'CHIP0402'     | ''          | ''   | '20160525'
 '0.47UF'   | '10V'   | '10%'     | 'C0402'     | 'EMPTY'   | 'CH4472K6B01'(!)   = ''              | ''                 | ''       | 'CH4472K6B01'     |'C0402'| '(C0402-0201)'                                                       | 'NA'       | '10V'         | '10%'    | 'IO'       | 'CAP CHIP 0.47U 10V(10%,X7S,0402)MUR_AEC'                      | 'CHIP0402'     | ''          | ''   | '20160525'
 '1000PF'   | '50V'   | '10%'     | 'C0402'     | 'X7R'     | 'CH2106K1B25'(!)   = ''              | ''                 | ''       | 'CH2106K1B25'     |'C0402'| '(C0402-0201)'                                                       | '1000PF'   | '50V'         | '10%'    | 'DISCRETE' | 'CAP CHIP 1000P 50V(10%,X7R,0402)MUR_AEC'                      | 'CHIP0402'     | ''          | ''   | '20160525'
 '1000PF'   | '50V'   | '10%'     | 'C0402'     | 'EMPTY'   | 'CH2106K1B25'(!)   = ''              | ''                 | ''       | 'CH2106K1B25'     |'C0402'| '(C0402-0201)'                                                       | 'NA'       | '50V'         | '10%'    | 'IO'       | 'CAP CHIP 1000P 50V(10%,X7R,0402)MUR_AEC'                      | 'CHIP0402'     | ''          | ''   | '20160525'
 '1000PF'   | '50V'   | '5%'      | 'C0402'     | 'X7R'     | 'CH2106J1B07'(!)   = ''              | ''                 | ''       | 'CH2106J1B07'     |'C0402'| '(C0402-0201)'                                                       | '1000PF'   | '50V'         | '5%'     | 'DISCRETE' | 'CAP CHIP 1000P 50V(5%,X7R,0402)MUR_AEC'                       | 'CHIP0402'     | ''          | ''   | '20160525'
 '1000PF'   | '50V'   | '5%'      | 'C0402'     | 'EMPTY'   | 'CH2106J1B07'(!)   = ''              | ''                 | ''       | 'CH2106J1B07'     |'C0402'| '(C0402-0201)'                                                       | 'NA'       | '50V'         | '5%'     | 'IO'       | 'CAP CHIP 1000P 50V(5%,X7R,0402)MUR_AEC'                       | 'CHIP0402'     | ''          | ''   | '20160525'
 '100PF'    | '50V'   | '5%'      | 'C0402'     | 'NPO'     | 'CH1106J0B19'(!)   = ''              | ''                 | ''       | 'CH1106J0B19'     |'C0402'| '(C0402-0201)'                                                       | '100PF'    | '50V'         | '5%'     | 'DISCRETE' | 'CAP CHIP 100P 50V(5%,NPO,0402)MUR_AEC'                        | 'CHIP0402'     | ''          | ''   | '20160525'
 '100PF'    | '50V'   | '5%'      | 'C0402'     | 'EMPTY'   | 'CH1106J0B19'(!)   = ''              | ''                 | ''       | 'CH1106J0B19'     |'C0402'| '(C0402-0201)'                                                       | 'NA'       | '50V'         | '5%'     | 'IO'       | 'CAP CHIP 100P 50V(5%,NPO,0402)MUR_AEC'                        | 'CHIP0402'     | ''          | ''   | '20160525'
 '10PF'     | '50V'   | '2%'      | 'C0402'     | 'NPO'     | 'CH0106G0B05'(!)   = ''              | ''                 | ''       | 'CH0106G0B05'     |'C0402'| '(C0402-0201)'                                                       | '10PF'     | '50V'         | '2%'     | 'DISCRETE' | 'CAP CHIP 10P 50V(2%,NPO,0402)MUR_AEC'                         | 'CHIP0402'     | ''          | ''   | '20160525'
 '10PF'     | '50V'   | '2%'      | 'C0402'     | 'EMPTY'   | 'CH0106G0B05'(!)   = ''              | ''                 | ''       | 'CH0106G0B05'     |'C0402'| '(C0402-0201)'                                                       | 'NA'       | '50V'         | '2%'     | 'IO'       | 'CAP CHIP 10P 50V(2%,NPO,0402)MUR_AEC'                         | 'CHIP0402'     | ''          | ''   | '20160525'
 '10UF'     | '10V'   | '20%'     | 'C0603'     | 'X6S'     | 'CH6102ME905'(!)   = ''              | ''                 | ''       | 'CH6102ME905'     |'C0603'| '(SMC0603AW)'                                                        | '10UF'     | '10V'         | '20%'    | 'DISCRETE' | 'CAP CHIP 10U 10V(20%,X6S,0603)MUR_AEC'                        | 'CHIP0603'     | ''          | ''   | '20160525'
 '10UF'     | '10V'   | '20%'     | 'C0603'     | 'EMPTY'   | 'CH6102ME905'(!)   = ''              | ''                 | ''       | 'CH6102ME905'     |'C0603'| '(SMC0603AW)'                                                        | 'NA'       | '10V'         | '20%'    | 'IO'       | 'CAP CHIP 10U 10V(20%,X6S,0603)MUR_AEC'                        | 'CHIP0603'     | ''          | ''   | '20160525'
 '10UF'     | '4V'    | '20%'     | 'C0603'     | 'X6S'     | 'CH610KME909'(!)   = ''              | ''                 | ''       | 'CH610KME909'     |'C0603'| '(SMC0603AW)'                                                        | '10UF'     | '4V'          | '20%'    | 'DISCRETE' | 'CAP CHIP 10U 4V(20%,X6S,0603)MUR_AEC'                         | 'CHIP0603'     | ''          | ''   | '20160525'
 '10UF'     | '4V'    | '20%'     | 'C0603'     | 'EMPTY'   | 'CH610KME909'(!)   = ''              | ''                 | ''       | 'CH610KME909'     |'C0603'| '(SMC0603AW)'                                                        | 'NA'       | '4V'          | '20%'    | 'IO'       | 'CAP CHIP 10U 4V(20%,X6S,0603)MUR_AEC'                         | 'CHIP0603'     | ''          | ''   | '20160525'
 '15PF'     | '50V'   | '5%'      | 'C0402'     | 'NPO'     | 'CH0156J0B12'(!)   = ''              | ''                 | ''       | 'CH0156J0B12'     |'C0402'| '(C0402-0201)'                                                       | '15PF'     | '50V'         | '5%'     | 'DISCRETE' | 'CAP CHIP 15P 50V(5%,NPO,0402)MUR_AEC'                         | 'CHIP0402'     | ''          | ''   | '20160525'
 '15PF'     | '50V'   | '5%'      | 'C0402'     | 'EMPTY'   | 'CH0156J0B12'(!)   = ''              | ''                 | ''       | 'CH0156J0B12'     |'C0402'| '(C0402-0201)'                                                       | 'NA'       | '50V'         | '5%'     | 'IO'       | 'CAP CHIP 15P 50V(5%,NPO,0402)MUR_AEC'                         | 'CHIP0402'     | ''          | ''   | '20160525'
 '18PF'     | '50V'   | '5%'      | 'C0402'     | 'NPO'     | 'CH0186J0B09'(!)   = ''              | ''                 | ''       | 'CH0186J0B09'     |'C0402'| '(C0402-0201)'                                                       | '15PF'     | '50V'         | '5%'     | 'DISCRETE' | 'CAP CHIP 18P 50V(5%,NPO,0402)MUR_AEC'                         | 'CHIP0402'     | ''          | ''   | '20160526'
 '18PF'     | '50V'   | '5%'      | 'C0402'     | 'EMPTY'   | 'CH0186J0B09'(!)   = ''              | ''                 | ''       | 'CH0186J0B09'     |'C0402'| '(C0402-0201)'                                                       | 'NA'       | '50V'         | '5%'     | 'IO'       | 'CAP CHIP 18P 50V(5%,NPO,0402)MUR_AEC'                         | 'CHIP0402'     | ''          | ''   | '20160526'
 '1UF'      | '16V'   | '10%'     | 'C0603'     | 'X7R'     | 'CH5103K1914'(!)   = 'End of Design' | 'Comp-Approve'     | ''       | 'CH5103K1914'     |'C0603'| '(SMC0603AW)'                                                        | '15PF'     | '16V'         | '10%'    | 'DISCRETE' | 'CAP CHIP 1U 16V(10%,X7R,0603)MUR_AEC'                         | 'CHIP0603'     | ''          | ''   | '20160526'
 '1UF'      | '16V'   | '10%'     | 'C0603'     | 'EMPTY'   | 'CH5103K1914'(!)   = 'End of Design' | 'Comp-Approve'     | ''       | 'CH5103K1914'     |'C0603'| '(SMC0603AW)'                                                        | 'NA'       | '16V'         | '10%'    | 'IO'       | 'CAP CHIP 1U 16V(10%,X7R,0603)MUR_AEC'                         | 'CHIP0603'     | ''          | ''   | '20160526'
 '1UF'      | '16V'   | '10%'     | 'C0402'     | 'X6S'     | 'CH5103KEB06'(!)   = ''              | ''                 | ''       | 'CH5103KEB06'     |'C0402'| '(C0402-0201)'                                                       | '15PF'     | '16V'         | '10%'    | 'DISCRETE' | 'CAP CHIP 1U 16V(10%,X6S,0402)MUR_AEC'                         | 'CHIP0402'     | ''          | ''   | '20160526'
 '1UF'      | '16V'   | '10%'     | 'C0402'     | 'EMPTY'   | 'CH5103KEB06'(!)   = ''              | ''                 | ''       | 'CH5103KEB06'     |'C0402'| '(C0402-0201)'                                                       | 'NA'       | '16V'         | '10%'    | 'IO'       | 'CAP CHIP 1U 16V(10%,X6S,0402)MUR_AEC'                         | 'CHIP0402'     | ''          | ''   | '20160526'
 '1UF'      | '25V'   | '10%'     | 'C0402'     | 'X6S'     | 'CH5104KEB06'(!)   = ''              | ''                 | ''       | 'CH5104KEB06'     |'C0402'| '(C0402-0201)'                                                       | '15PF'     | '25V'         | '10%'    | 'DISCRETE' | 'CAP CHIP 1U 25V(10%,X6S,0402)MUR_AEC'                         | 'CHIP0402'     | ''          | ''   | '20160526'
 '1UF'      | '25V'   | '10%'     | 'C0402'     | 'EMPTY'   | 'CH5104KEB06'(!)   = ''              | ''                 | ''       | 'CH5104KEB06'     |'C0402'| '(C0402-0201)'                                                       | 'NA'       | '25V'         | '10%'    | 'IO'       | 'CAP CHIP 1U 25V(10%,X6S,0402)MUR_AEC'                         | 'CHIP0402'     | ''          | ''   | '20160526'
 '2200PF'   | '50V'   | '10%'     | 'C0402'     | 'X7R'     | 'CH2226K1B14'(!)   = ''              | ''                 | ''       | 'CH2226K1B14'     |'C0402'| '(C0402-0201)'                                                       | '2200PF'   | '50V'         | '10%'    | 'DISCRETE' | 'CAP CHIP 2200P 50V(10%,X7R,0402)MUR_AEC'                      | 'CHIP0402'     | ''          | ''   | '20160526'
 '2200PF'   | '50V'   | '10%'     | 'C0402'     | 'EMPTY'   | 'CH2226K1B14'(!)   = ''              | ''                 | ''       | 'CH2226K1B14'     |'C0402'| '(C0402-0201)'                                                       | 'NA'       | '50V'         | '10%'    | 'IO'       | 'CAP CHIP 2200P 50V(10%,X7R,0402)MUR_AEC'                      | 'CHIP0402'     | ''          | ''   | '20160526'
 '22PF'     | '50V'   | '5%'      | 'C0402'     | 'NPO'     | 'CH0226J0B23'(!)   = ''              | ''                 | ''       | 'CH0226J0B23'     |'C0402'| '(C0402-0201)'                                                       | '22PF'     | '50V'         | '5%'     | 'DISCRETE' | 'CAP CHIP 22P 50V(5%,NPO,0402)MUR_AEC'                         | 'CHIP0402'     | ''          | ''   | '20160526'
 '22PF'     | '50V'   | '5%'      | 'C0402'     | 'EMPTY'   | 'CH0226J0B23'(!)   = ''              | ''                 | ''       | 'CH0226J0B23'     |'C0402'| '(C0402-0201)'                                                       | 'NA'       | '50V'         | '5%'     | 'IO'       | 'CAP CHIP 22P 50V(5%,NPO,0402)MUR_AEC'                         | 'CHIP0402'     | ''          | ''   | '20160526'
 '3300PF'   | '50V'   | '10%'     | 'C0402'     | 'X7R'     | 'CH2336K1B11'(!)   = ''              | ''                 | ''       | 'CH2336K1B11'     |'C0402'| '(C0402-0201)'                                                       | '3300PF'   | '50V'         | '10%'    | 'DISCRETE' | 'CAP CHIP 3300P 50V(10%,X7R,0402)MUR_AEC'                      | 'CHIP0402'     | ''          | ''   | '20160526'
 '3300PF'   | '50V'   | '10%'     | 'C0402'     | 'EMPTY'   | 'CH2336K1B11'(!)   = ''              | ''                 | ''       | 'CH2336K1B11'     |'C0402'| '(C0402-0201)'                                                       | 'NA'       | '50V'         | '10%'    | 'IO'       | 'CAP CHIP 3300P 50V(10%,X7R,0402)MUR_AEC'                      | 'CHIP0402'     | ''          | ''   | '20160526'
 '4.7UF'    | '6.3V'  | '10%'     | 'C0603'     | 'X6S'     | 'CH5471KE907'(!)   = 'End of Design' | 'Comp-Approve'     | ''       | 'CH5471KE907'     |'C0603'| '(SMC0603AW)'                                                        | '4.7UF'    | '6.3V'        | '10%'    | 'DISCRETE' | 'CAP CHIP 4.7U 6.3V(10%,X6S,0603)MUR_AEC'                      | 'CHIP0603'     | ''          | ''   | '20160526'
 '4.7UF'    | '6.3V'  | '10%'     | 'C0603'     | 'EMPTY'   | 'CH5471KE907'(!)   = 'End of Design' | 'Comp-Approve'     | ''       | 'CH5471KE907'     |'C0603'| '(SMC0603AW)'                                                        | 'NA'       | '6.3V'        | '10%'    | 'IO'       | 'CAP CHIP 4.7U 6.3V(10%,X6S,0603)MUR_AEC'                      | 'CHIP0603'     | ''          | ''   | '20160526'
 '4700PF'   | '25V'   | '10%'     | 'C0402'     | 'X7R'     | 'CH2474K1B11'(!)   = ''              | ''                 | ''       | 'CH2474K1B11'     |'C0402'| '(C0402-0201)'                                                       | '4700PF'   | '25V'         | '10%'    | 'DISCRETE' | 'CAP CHIP 4700P 25V(10%,X7R,0402)MUR_AEC'                      | 'CHIP0402'     | ''          | ''   | '20160526'
 '4700PF'   | '25V'   | '10%'     | 'C0402'     | 'EMPTY'   | 'CH2474K1B11'(!)   = ''              | ''                 | ''       | 'CH2474K1B11'     |'C0402'| '(C0402-0201)'                                                       | 'NA'       | '25V'         | '10%'    | 'IO'       | 'CAP CHIP 4700P 25V(10%,X7R,0402)MUR_AEC'                      | 'CHIP0402'     | ''          | ''   | '20160526'
 '470PF'    | '50V'   | '10%'     | 'C0402'     | 'X7R'     | 'CH1476K1B15'(!)   = ''              | ''                 | ''       | 'CH1476K1B15'     |'C0402'| '(C0402-0201)'                                                       | '470PF'    | '50V'         | '10%'    | 'DISCRETE' | 'CAP CHIP 470P 50V(10%,X7R,0402)MUR_AEC'                       | 'CHIP0402'     | ''          | ''   | '20160526'
 '470PF'    | '50V'   | '10%'     | 'C0402'     | 'EMPTY'   | 'CH1476K1B15'(!)   = ''              | ''                 | ''       | 'CH1476K1B15'     |'C0402'| '(C0402-0201)'                                                       | 'NA'       | '50V'         | '10%'    | 'IO'       | 'CAP CHIP 470P 50V(10%,X7R,0402)MUR_AEC'                       | 'CHIP0402'     | ''          | ''   | '20160526'
 '47PF'     | '50V'   | '5%'      | 'C0402'     | 'C0G'     | 'CH0476J0B15'(!)   = ''              | ''                 | ''       | 'CH0476J0B15'     |'C0402'| '(C0402-0201)'                                                       | '47PF'     | '50V'         | '5%'     | 'DISCRETE' | 'CAP CHIP 47P 50V(5%,C0G,0402)MUR_AEC'                         | 'CHIP0402'     | ''          | ''   | '20160526'
 '47PF'     | '50V'   | '5%'      | 'C0402'     | 'EMPTY'   | 'CH0476J0B15'(!)   = ''              | ''                 | ''       | 'CH0476J0B15'     |'C0402'| '(C0402-0201)'                                                       | 'NA'       | '50V'         | '5%'     | 'IO'       | 'CAP CHIP 47P 50V(5%,C0G,0402)MUR_AEC'                         | 'CHIP0402'     | ''          | ''   | '20160526'
 '27PF'     | '50V'   | '5%'      | 'C0402'     | 'C0G'     | 'CH0276J0B08'(!)   = ''              | ''                 | ''       | 'CH0276J0B08'     |'C0402'| '(C0402-0201)'                                                       | '27PF'     | '50V'         | '5%'     | 'DISCRETE' | 'CAP CHIP 27P 50V(5%,C0G,0402)MUR_AEC'                         | 'CHIP0402'     | ''          | ''   | '20160530'
 '27PF'     | '50V'   | '5%'      | 'C0402'     | 'EMPTY'   | 'CH0276J0B08'(!)   = ''              | ''                 | ''       | 'CH0276J0B08'     |'C0402'| '(C0402-0201)'                                                       | 'NA'       | '50V'         | '5%'     | 'IO'       | 'CAP CHIP 27P 50V(5%,C0G,0402)MUR_AEC'                         | 'CHIP0402'     | ''          | ''   | '20160530'
 '1UF'      | '10V'   | '10%'     | 'C0402'     | 'X7S'     | 'CH5102K6B02'(!)   = ''              | ''                 | ''       | 'CH5102K6B02'     |'C0402'| '(C0402-0201)'                                                       | '1UF'      | '10V'         | '10%'    | 'DISCRETE' | 'CAP CHIP 1U 10V(10%,X7S,0402)MUR_AEC'                         | 'CHIP0402'     | ''          | ''   | '20160530'
 '1UF'      | '10V'   | '10%'     | 'C0402'     | 'EMPTY'   | 'CH5102K6B02'(!)   = ''              | ''                 | ''       | 'CH5102K6B02'     |'C0402'| '(C0402-0201)'                                                       | 'NA'       | '10V'         | '10%'    | 'IO'       | 'CAP CHIP 1U 10V(10%,X7S,0402)MUR_AEC'                         | 'CHIP0402'     | ''          | ''   | '20160530'
 '4.7UF'    | '16V'   | '10%'     | 'C0603'     | 'X6S'     | 'CH5473KE901'(!)   = ''              | ''                 | ''       | 'CH5473KE901'     |'C0603'| '(SMC0603AW)'                                                        | '4.7UF'    | '16V'         | '10%'    | 'DISCRETE' | 'CAP CHIP 4.7U 16V(10%,X6S,0603)MUR_AEC'                       | 'CHIP0603'     | ''          | ''   | '20160530'
 '4.7UF'    | '16V'   | '10%'     | 'C0603'     | 'EMPTY'   | 'CH5473KE901'(!)   = ''              | ''                 | ''       | 'CH5473KE901'     |'C0603'| '(SMC0603AW)'                                                        | 'NA'       | '16V'         | '10%'    | 'IO'       | 'CAP CHIP 4.7U 16V(10%,X6S,0603)MUR_AEC'                       | 'CHIP0603'     | ''          | ''   | '20160530'
 '33PF'     | '50V'   | '5%'      | 'C0402'     | 'C0G'     | 'CH0336J0B14'(!)   = ''              | ''                 | ''       | 'CH0336J0B14'     |'C0402'| '(C0402-0201)'                                                       | '33PF'     | '50V'         | '5%'     | 'DISCRETE' | 'CAP CHIP 33P 50V(5%,C0G,0402)MUR_AEC'                         | 'CHIP0402'     | ''          | ''   | '20160530'
 '33PF'     | '50V'   | '5%'      | 'C0402'     | 'EMPTY'   | 'CH0336J0B14'(!)   = ''              | ''                 | ''       | 'CH0336J0B14'     |'C0402'| '(C0402-0201)'                                                       | 'NA'       | '50V'         | '5%'     | 'IO'       | 'CAP CHIP 33P 50V(5%,C0G,0402)MUR_AEC'                         | 'CHIP0402'     | ''          | ''   | '20160530'
 '0.01UF'   | '50V'   | '10%'     | 'C0603'     | 'X7R'     | 'CH3106K1915'(!)   = 'End of Design' | 'Comp-Approve'     | ''       | 'CH3106K1915'     |'C0603'| '(SMC0603AW)'                                                        | '0.01UF'   | '50V'         | '10%'    | 'DISCRETE' | 'CAP CHIP 0.01U 50V(10%,X7R,0603)MUR_AEC'                      | 'CHIP0603'     | ''          | ''   | '20160530'
 '0.01UF'   | '50V'   | '10%'     | 'C0603'     | 'EMPTY'   | 'CH3106K1915'(!)   = 'End of Design' | 'Comp-Approve'     | ''       | 'CH3106K1915'     |'C0603'| '(SMC0603AW)'                                                        | 'NA'       | '50V'         | '10%'    | 'IO'       | 'CAP CHIP 0.01U 50V(10%,X7R,0603)MUR_AEC'                      | 'CHIP0603'     | ''          | ''   | '20160530'
 '10UF'     | '16V'   | '10%'     | 'C1206'     | 'X7R'     | 'CH6103K1203'(!)   = ''              | ''                 | ''       | 'CH6103K1203'     |'C1206_H76'| '(SMC1206AW)'                                                        | '10UF'     | '16V'         | '10%'    | 'DISCRETE' | 'CAP CHIP 10U 16V(10%,X7R,1206)MUR_AEC'                        | 'CHIP1206'     | ''          | ''   | '20160531'
 '10UF'     | '16V'   | '10%'     | 'C1206'     | 'EMPTY'   | 'CH6103K1203'(!)   = ''              | ''                 | ''       | 'CH6103K1203'     |'C1206_H76'| '(SMC1206AW)'                                                        | 'NA'       | '16V'         | '10%'    | 'IO'       | 'CAP CHIP 10U 16V(10%,X7R,1206)MUR_AEC'                        | 'CHIP1206'     | ''          | ''   | '20160531'
 '10UF'     | '16V'   | '10%'     | 'C0805'     | 'X7S'     | 'CH6103K6A01'(!)   = ''              | ''                 | ''       | 'CH6103K6A01'     |'C0805_H57'| '(SMC0805AW)'                                                        | '10UF'     | '16V'         | '10%'    | 'DISCRETE' | 'CAP CHIP 10U 16V(10%,X7S,0805)MUR_AEC'                        | 'CHIP0805'     | ''          | ''   | '20160531'
 '10UF'     | '16V'   | '10%'     | 'C0805'     | 'EMPTY'   | 'CH6103K6A01'(!)   = ''              | ''                 | ''       | 'CH6103K6A01'     |'C0805_H57'| '(SMC0805AW)'                                                        | 'NA'       | '16V'         | '10%'    | 'IO'       | 'CAP CHIP 10U 16V(10%,X7S,0805)MUR_AEC'                        | 'CHIP0805'     | ''          | ''   | '20160531'
 '10UF'     | '25V'   | '10%'     | 'C1206'     | 'X7S'     | 'CH6104K6201'(!)   = 'End of Design' | 'Comp-Approve'     | ''       | 'CH6104K6201'     |'C1206_H76'| '(SMC1206AW)'                                                        | '10UF'     | '25V'         | '10%'    | 'DISCRETE' | 'CAP CHIP 10U 25V(10%,X7S,1206)MUR_AEC'                        | 'CHIP1206'     | ''          | ''   | '20160531'
 '10UF'     | '25V'   | '10%'     | 'C1206'     | 'EMPTY'   | 'CH6104K6201'(!)   = 'End of Design' | 'Comp-Approve'     | ''       | 'CH6104K6201'     |'C1206_H76'| '(SMC1206AW)'                                                        | 'NA'       | '25V'         | '10%'    | 'IO'       | 'CAP CHIP 10U 25V(10%,X7S,1206)MUR_AEC'                        | 'CHIP1206'     | ''          | ''   | '20160531'
 '10UF'     | '6.3V'  | '10%'     | 'C0805'     | 'X7R'     | 'CH6101K1A02'(!)   = ''              | ''                 | ''       | 'CH6101K1A02'     |'C0805_H57'| '(SMC0805AW)'                                                        | '10UF'     | '6.3V'        | '10%'    | 'DISCRETE' | 'CAP CHIP 10U 6.3V(10%,X7R,0805)MUR_AEC'                       | 'CHIP0805'     | ''          | ''   | '20160531'
 '10UF'     | '6.3V'  | '10%'     | 'C0805'     | 'EMPTY'   | 'CH6101K1A02'(!)   = ''              | ''                 | ''       | 'CH6101K1A02'     |'C0805_H57'| '(SMC0805AW)'                                                        | 'NA'       | '6.3V'        | '10%'    | 'IO'       | 'CAP CHIP 10U 6.3V(10%,X7R,0805)MUR_AEC'                       | 'CHIP0805'     | ''          | ''   | '20160531'
 '2.2UF'    | '10V'   | '10%'     | 'C0805'     | 'X7R'     | 'CH5222K1A02'(!)   = 'End of Design' | 'Comp-Approve'     | ''       | 'CH5222K1A02'     |'C0805_H57'| '(SMC0805AW)'                                                        | '2.2UF'    | '10V'         | '10%'    | 'DISCRETE' | 'CAP CHIP 2.2U 10V(10%,X7R,0805)MUR_AEC'                       | 'CHIP0805'     | ''          | ''   | '20160531'
 '2.2UF'    | '10V'   | '10%'     | 'C0805'     | 'EMPTY'   | 'CH5222K1A02'(!)   = 'End of Design' | 'Comp-Approve'     | ''       | 'CH5222K1A02'     |'C0805_H57'| '(SMC0805AW)'                                                        | 'NA'       | '10V'         | '10%'    | 'IO'       | 'CAP CHIP 2.2U 10V(10%,X7R,0805)MUR_AEC'                       | 'CHIP0805'     | ''          | ''   | '20160531'
 '22UF'     | '10V'   | '20%'     | 'C0805'     | 'X6S'     | 'CH6222MEA04'(!)   = ''              | ''                 | ''       | 'CH6222MEA04'     |'C0805_H57'| '(SMC0805AW)'                                                        | '22UF'     | '10V'         | '20%'    | 'DISCRETE' | 'CAP CHIP 22U 10V(20%,X6S,0805)MUR_AEC'                        | 'CHIP0805'     | ''          | ''   | '20160531'
 '22UF'     | '10V'   | '20%'     | 'C0805'     | 'EMPTY'   | 'CH6222MEA04'(!)   = ''              | ''                 | ''       | 'CH6222MEA04'     |'C0805_H57'| '(SMC0805AW)'                                                        | 'NA'       | '10V'         | '20%'    | 'IO'       | 'CAP CHIP 22U 10V(20%,X6S,0805)MUR_AEC'                        | 'CHIP0805'     | ''          | ''   | '20160531'
 '22UF'     | '25V'   | '10%'     | 'C1206'     | 'X5R'     | 'CH6224K9204'(!)   = ''              | ''                 | ''       | 'CH6224K9204'     |'C1206_H76'| '(SMC1206AW)'                                                        | '22UF'     | '25V'         | '10%'    | 'DISCRETE' | 'CAP CHIP 22U 25V(10%,X5R,1206)MUR_AEC'                        | 'CHIP1206'     | ''          | ''   | '20160531'
 '22UF'     | '25V'   | '10%'     | 'C1206'     | 'EMPTY'   | 'CH6224K9204'(!)   = ''              | ''                 | ''       | 'CH6224K9204'     |'C1206_H76'| '(SMC1206AW)'                                                        | 'NA'       | '25V'         | '10%'    | 'IO'       | 'CAP CHIP 22U 25V(10%,X5R,1206)MUR_AEC'                        | 'CHIP1206'     | ''          | ''   | '20160531'
 '4.7UF'    | '16V'   | '10%'     | 'C0805'     | 'X7R'     | 'CH5473K1A05'(!)   = 'End of Design' | 'Comp-Approve'     | ''       | 'CH5473K1A05'     |'C0805_H57'| '(SMC0805AW)'                                                        | '4.7UF'    | '16V'         | '10%'    | 'DISCRETE' | 'CAP CHIP 4.7UF 16V(10%,X7R,0805)MUR_AEC'                      | 'CHIP0805'     | ''          | ''   | '20160531'
 '4.7UF'    | '16V'   | '10%'     | 'C0805'     | 'EMPTY'   | 'CH5473K1A05'(!)   = 'End of Design' | 'Comp-Approve'     | ''       | 'CH5473K1A05'     |'C0805_H57'| '(SMC0805AW)'                                                        | 'NA'       | '16V'         | '10%'    | 'IO'       | 'CAP CHIP 4.7UF 16V(10%,X7R,0805)MUR_AEC'                      | 'CHIP0805'     | ''          | ''   | '20160531'
 '0.022UF'  | '25V'   | '10%'     | 'C0402'     | 'X7R'     | 'CH3224K1B06'(!)   = ''              | ''                 | ''       | 'CH3224K1B06'     |'C0402'| '(C0402-0201)'                                                       | '0.022UF'  | '25V'         | '10%'    | 'DISCRETE' | 'CAP CHIP 0.022U 25V(10%,X7R,0402)MUR_AEC'                     | 'CHIP0402'     | ''          | ''   | '20160602'
 '0.022UF'  | '25V'   | '10%'     | 'C0402'     | 'EMPTY'   | 'CH3224K1B06'(!)   = ''              | ''                 | ''       | 'CH3224K1B06'     |'C0402'| '(C0402-0201)'                                                       | 'NA'       | '25V'         | '10%'    | 'IO'       | 'CAP CHIP 0.022U 25V(10%,X7R,0402)MUR_AEC'                     | 'CHIP0402'     | ''          | ''   | '20160602'
 '47UF'     | '4V'    | '20%'     | 'C0805'     | 'X6S'     | 'CH647KMEA04'(!)   = ''              | ''                 | ''       | 'CH647KMEA04'     |'C0805_H57'| '(C0805_H57_M,C0805_BHS)'                                            | '47UF'     | '4V'          | '20%'    | 'DISCRETE' | 'CAP CHIP 47U 4V(+-20%,X6S,0805)MUR'                           | 'CHIP0805'     | ''          | ''   | '20160616'
 '47UF'     | '4V'    | '20%'     | 'C0805'     | 'EMPTY'   | 'CH647KMEA04'(!)   = ''              | ''                 | ''       | 'CH647KMEA04'     |'C0805_H57'| '(C0805_H57_M,C0805_BHS)'                                            | 'NA'       | '4V'          | '20%'    | 'IO'       | 'CAP CHIP 47U 4V(+-20%,X6S,0805)MUR'                           | 'CHIP0805'     | ''          | ''   | '20160616'
 '1UF'      | '16V'   | '10%'     | 'C0603'     | 'X7R'     | 'CH5103K1909'(!)   = 'End of Design' | 'Comp-Approve'     | ''       | 'CH5103K1909'     |'C0603'| '(SMC0603AW,C0603_M)'                                                | '1UF'      | '16V'         | '10%'    | 'DISCRETE' | 'CAP CHIP 1U 16V(+-10%,X7R,0603)MUR'                           | 'CHIP0603'     | ''          | ''   | '20160616'
 '1UF'      | '16V'   | '10%'     | 'C0603'     | 'EMPTY'   | 'CH5103K1909'(!)   = 'End of Design' | 'Comp-Approve'     | ''       | 'CH5103K1909'     |'C0603'| '(SMC0603AW,C0603_M)'                                                | 'NA'       | '16V'         | '10%'    | 'IO'       | 'CAP CHIP 1U 16V(+-10%,X7R,0603)MUR'                           | 'CHIP0603'     | ''          | ''   | '20160616'
 '0.1UF'    | '16V'   | '10%'     | 'C0402'     | 'X7R'     | 'CH4103K1B14'(!)   = 'End of Design' | 'Comp-Approve'     | ''       | 'CH4103K1B14'     |'C0402'| '(C0402_OCTAGONXA,C0402_M,C0402-0201,C0402_OCTAGONXA_BOUND22)'       | '0.1UF'    | '16V'         | '10%'    | 'DISCRETE' | 'CAP CHIP 0.1U 16V(10%,X7R,0402)MUR'                           | 'CHIP0402'     | ''          | ''   | '20160616'
 '0.1UF'    | '16V'   | '10%'     | 'C0402'     | 'EMPTY'   | 'CH4103K1B14'(!)   = 'End of Design' | 'Comp-Approve'     | ''       | 'CH4103K1B14'     |'C0402'| '(C0402_OCTAGONXA,C0402_M,C0402-0201,C0402_OCTAGONXA_BOUND22)'       | 'NA'       | '16V'         | '10%'    | 'IO'       | 'CAP CHIP 0.1U 16V(10%,X7R,0402)MUR'                           | 'CHIP0402'     | ''          | ''   | '20160616'
 '47UF'     | '4V'    | '20%'     | 'C0805'     | 'X6S'     | 'CH647KMEA08'(!)   = ''              | ''                 | ''       | 'CH647KMEA08'     |'C0805_H57'| '(SMC0805AW)'                                                        | '47UF'     | '4V'          | '20%'    | 'DISCRETE' | 'CAP CHIP 47U 4V(20%,X6S,0805)MUR_AEC'                         | 'CHIP0805'     | ''          | ''   | '20160624'
 '47UF'     | '4V'    | '20%'     | 'C0805'     | 'EMPTY'   | 'CH647KMEA08'(!)   = ''              | ''                 | ''       | 'CH647KMEA08'     |'C0805_H57'| '(SMC0805AW)'                                                        | 'NA'       | '4V'          | '20%'    | 'IO'       | 'CAP CHIP 47U 4V(20%,X6S,0805)MUR_AEC'                         | 'CHIP0805'     | ''          | ''   | '20160624'
 '22UF'     | '6.3V'  | '20%'     | 'C0805'     | 'X7T'     | 'CH6221MJA02'(!)   = ''              | ''                 | ''       | 'CH6221MJA02'     |'C0805_H57'| '(SMC0805AW)'                                                        | '22UF'     | '6.3V'        | '20%'    | 'DISCRETE' | 'CAP CHIP 22U 6.3V(20%,X7T,0805)MUR_AEC'                       | 'CHIP0805'     | ''          | ''   | '20160624'
 '22UF'     | '6.3V'  | '20%'     | 'C0805'     | 'EMPTY'   | 'CH6221MJA02'(!)   = ''              | ''                 | ''       | 'CH6221MJA02'     |'C0805_H57'| '(SMC0805AW)'                                                        | 'NA'       | '6.3V'        | '20%'    | 'IO'       | 'CAP CHIP 22U 6.3V(20%,X7T,0805)MUR_AEC'                       | 'CHIP0805'     | ''          | ''   | '20160624'
 '22UF'     | '25V'   | '10%'     | 'C1206'     | 'X6S'     | 'CH6224KE200'(!)   = 'End of Design' | 'Comp-Approve'     | ''       | 'CH6224KE200'     |'C1206_H76'| '(SMC1206AW)'                                                        | '22UF'     | '25V'         | '10%'    | 'DISCRETE' | 'CAP CHIP 22U 25V(+-10%,X6S,1206)'                             | 'CHIP1206'     | ''          | ''   | '20160624'
 '22UF'     | '25V'   | '10%'     | 'C1206'     | 'EMPTY'   | 'CH6224KE200'(!)   = 'End of Design' | 'Comp-Approve'     | ''       | 'CH6224KE200'     |'C1206_H76'| '(SMC1206AW)'                                                        | 'NA'       | '25V'         | '10%'    | 'IO'       | 'CAP CHIP 22U 25V(+-10%,X6S,1206)'                             | 'CHIP1206'     | ''          | ''   | '20160624'
 '6.8PF'    | '50V'   | '0.5PF'   | 'C0402'     | 'C0G'     | 'CH-686D0B02'(!)   = ''              | ''                 | ''       | 'CH-686D0B02'     |'C0402'| '(C0402-0201)'                                                       | '6.8PF'    | '50V'         | '0.5PF'  | 'DISCRETE' | 'CAP CHIP 6.8P 50V(0.5PF,C0G,0402)MUR_AEC'                     | 'CHIP0402'     | ''          | ''   | '20160803'
 '6.8PF'    | '50V'   | '0.5PF'   | 'C0402'     | 'EMPTY'   | 'CH-686D0B02'(!)   = ''              | ''                 | ''       | 'CH-686D0B02'     |'C0402'| '(C0402-0201)'                                                       | 'NA'       | '50V'         | '0.5PF'  | 'IO'       | 'CAP CHIP 6.8P 50V(0.5PF,C0G,0402)MUR_AEC'                     | 'CHIP0402'     | ''          | ''   | '20160803'
 '5.6PF'    | '50V'   | '0.5PF'   | 'C0402'     | 'C0G'     | 'CH-566D0B02'(!)   = ''              | 'End of Life'      | ''       | 'CH-566D0B02'     |'C0402_EOL'| '(C0402-0201)'                                                       | '5.6PF'    | '50V'         | '0.5PF'  | 'DISCRETE' | 'CAP CHIP 5.6P 50V(0.5PF,C0G,0402)MUR_AEC'                     | 'CHIP0402'     | ''          | ''   | '20160803'
 '5.6PF'    | '50V'   | '0.5PF'   | 'C0402'     | 'EMPTY'   | 'CH-566D0B02'(!)   = ''              | 'End of Life'      | ''       | 'CH-566D0B02'     |'C0402_EOL'| '(C0402-0201)'                                                       | 'NA'       | '50V'         | '0.5PF'  | 'IO'       | 'CAP CHIP 5.6P 50V(0.5PF,C0G,0402)MUR_AEC'                     | 'CHIP0402'     | ''          | ''   | '20160803'
 '4.7PF'    | '50V'   | '0.25P'   | 'C0402'     | 'C0G'     | 'CH-476C0B02'(!)   = ''              | 'End of Life'      | ''       | 'CH-476C0B02'     |'C0402_EOL'| '(C0402-0201)'                                                       | '4.7PF'    | '50V'         | '0.25P'  | 'DISCRETE' | 'CAP CHIP 4.7P 50V(0.25P,C0G 0402)MUR_AEC'                     | 'CHIP0402'     | ''          | ''   | '20160803'
 '4.7PF'    | '50V'   | '0.25P'   | 'C0402'     | 'EMPTY'   | 'CH-476C0B02'(!)   = ''              | 'End of Life'      | ''       | 'CH-476C0B02'     |'C0402_EOL'| '(C0402-0201)'                                                       | 'NA'       | '50V'         | '0.25P'  | 'IO'       | 'CAP CHIP 4.7P 50V(0.25P,C0G 0402)MUR_AEC'                     | 'CHIP0402'     | ''          | ''   | '20160803'
 '4.7PF'    | '50V'   | '0.05P'   | 'C0402'     | 'C0G'     | 'CH-476T0B01'(!)   = ''              | ''                 | ''       | 'CH-476T0B01'     |'C0402'| '(C0402-0201)'                                                       | '4.7PF'    | '50V'         | '0.05P'  | 'DISCRETE' | 'CAP CHIP 4.7P 50V(0.05P,C0G,0402)MUR_AEC'                     | 'CHIP0402'     | ''          | ''   | '20160810'
 '4.7PF'    | '50V'   | '0.05P'   | 'C0402'     | 'EMPTY'   | 'CH-476T0B01'(!)   = ''              | ''                 | ''       | 'CH-476T0B01'     |'C0402'| '(C0402-0201)'                                                       | 'NA'       | '50V'         | '0.05P'  | 'IO'       | 'CAP CHIP 4.7P 50V(0.05P,C0G,0402)MUR_AEC'                     | 'CHIP0402'     | ''          | ''   | '20160810'
 '5.6P'     | '50V'   | '0.1P'    | 'C0402'     | 'C0G'     | 'CH-566B0B02'(!)   = ''              | ''                 | ''       | 'CH-566B0B02'     |'C0402'| '(C0402-0201)'                                                       | '5.6P'     | '50V'         | '0.1P'   | 'DISCRETE' | 'CAP CHIP 5.6P 50V(0.1P,C0G,0402)MUR_AEC'                      | 'CHIP0402'     | ''          | ''   | '20160810'
 '5.6P'     | '50V'   | '0.1P'    | 'C0402'     | 'EMPTY'   | 'CH-566B0B02'(!)   = ''              | ''                 | ''       | 'CH-566B0B02'     |'C0402'| '(C0402-0201)'                                                       | 'NA'       | '50V'         | '0.1P'   | 'IO'       | 'CAP CHIP 5.6P 50V(0.1P,C0G,0402)MUR_AEC'                      | 'CHIP0402'     | ''          | ''   | '20160810'
 '22UF'     | '4V'    | '20%'     | 'C0402'     | 'X5R'     | 'SP_CH622KM9B02_1'(!) = 'End of Design' | 'Comp-Approve'     | ''       | 'CH622KM9B02'     |'C0402_SMDC25_SM30'| '(SMC0402AW)'                                                        | '22UF'     | '4V'          | '20%'    | 'DISCRETE' | 'CAP CHIP 22UF 4V (+-20%, X5R,0402)_AMD FOOTPRINT SMDC25_SM30' | 'CHIP0402'     | ''          | ''   | '20160815'
 '22UF'     | '4V'    | '20%'     | 'C0402'     | 'EMPTY'   | 'SP_CH622KM9B02_1'(!) = 'End of Design' | 'Comp-Approve'     | ''       | 'CH622KM9B02'     |'C0402_SMDC25_SM30'| '(SMC0402AW)'                                                        | 'NA'       | '4V'          | '20%'    | 'IO'       | 'CAP CHIP 22UF 4V (+-20%, X5R,0402)_AMD FOOTPRINT SMDC25_SM30' | 'CHIP0402'     | ''          | ''   | '20160815'
 '47UF'     | '2.5V'  | '20%'     | 'C0603'     | 'X6S'     | 'CH647LME901'(!)   = 'End of Design' | 'Comp-Approve'     | ''       | 'CH647LME901'     |'C0603'| '(SMC0603AW)'                                                        | '47UF'     | '2.5V'        | '20%'    | 'DISCRETE' | 'CAP CHIP 47U 2.5V(+-20%,X6S,0603)'                            | 'CHIP0603'     | ''          | ''   | '20160823'
 '47UF'     | '2.5V'  | '20%'     | 'C0603'     | 'EMPTY'   | 'CH647LME901'(!)   = 'End of Design' | 'Comp-Approve'     | ''       | 'CH647LME901'     |'C0603'| '(SMC0603AW)'                                                        | 'NA'       | '2.5V'        | '20%'    | 'IO'       | 'CAP CHIP 47U 2.5V(+-20%,X6S,0603)'                            | 'CHIP0603'     | ''          | ''   | '20160823'
 '0.1UF'    | '16V'   | '10%'     | 'C0402'     | 'X7R'     | 'SP_CH4103K1B08_3'(!) = ''              | ''                 | ''       | 'CH4103K1B08'     |'C0402_SMDC25_SM30'| '(SMC0402AW)'                                                        | '0.1UF'    | '16V'         | '10%'    | 'DISCRETE' | 'CAP CHIP 0.1U 16V(10%.X7R.0402)_AMD FOOTPRINT SMDC25_SM30'    | 'CHIP0402'     | ''          | ''   | '20160829'
 '0.1UF'    | '16V'   | '10%'     | 'C0402'     | 'EMPTY'   | 'SP_CH4103K1B08_3'(!) = ''              | ''                 | ''       | 'CH4103K1B08'     |'C0402_SMDC25_SM30'| '(SMC0402AW)'                                                        | 'NA'       | '16V'         | '10%'    | 'IO'       | 'CAP CHIP 0.1U 16V(10%.X7R.0402)_AMD FOOTPRINT SMDC25_SM30'    | 'CHIP0402'     | ''          | ''   | '20160829'
 '0.68UF'   | '16V'   | '10%'     | 'C0603'     | 'X7R'     | 'CH4683K1901'(!)   = ''              | ''                 | ''       | 'CH4683K1901'     |'C0603'| '(SMC0603AW)'                                                        | '0.68UF'   | '16V'         | '10%'    | 'DISCRETE' | 'CAP CHIP 0.68U 16V(+-10%,X7R,0603)WTC'                        | 'CHIP0603'     | ''          | ''   | '20160830'
 '0.68UF'   | '16V'   | '10%'     | 'C0603'     | 'EMPTY'   | 'CH4683K1901'(!)   = ''              | ''                 | ''       | 'CH4683K1901'     |'C0603'| '(SMC0603AW)'                                                        | 'NA'       | '16V'         | '10%'    | 'IO'       | 'CAP CHIP 0.68U 16V(+-10%,X7R,0603)WTC'                        | 'CHIP0603'     | ''          | ''   | '20160830'
 '4.7UF'    | '25V'   | '10%'     | 'C0603'     | 'X6S'     | 'CH5474KE906'(!)   = ''              | ''                 | ''       | 'CH5474KE906'     |'C0603'| '(SMC0603AW)'                                                        | '4.7UF'    | '25V'         | '10%'    | 'DISCRETE' | 'CAP CHIP 4.7UF 25V(+-10%,X6S,0603)'                           | 'CHIP0603'     | ''          | ''   | '20160830'
 '4.7UF'    | '25V'   | '10%'     | 'C0603'     | 'EMPTY'   | 'CH5474KE906'(!)   = ''              | ''                 | ''       | 'CH5474KE906'     |'C0603'| '(SMC0603AW)'                                                        | 'NA'       | '25V'         | '10%'    | 'IO'       | 'CAP CHIP 4.7UF 25V(+-10%,X6S,0603)'                           | 'CHIP0603'     | ''          | ''   | '20160830'
 '33PF'     | '50V'   | '1%'      | 'C0402'     | 'C0G'     | 'CH0336F0B00'(!)   = ''              | ''                 | ''       | 'CH0336F0B00'     |'C0402'| '(C0402-0201)'                                                       | '33PF'     | '50V'         | '1%'     | 'DISCRETE' | 'CAP CHIP 33P 50V(+-1%,C0G,0402)'                              | 'CHIP0402'     | ''          | ''   | '20160906'
 '33PF'     | '50V'   | '1%'      | 'C0402'     | 'EMPTY'   | 'CH0336F0B00'(!)   = ''              | ''                 | ''       | 'CH0336F0B00'     |'C0402'| '(C0402-0201)'                                                       | 'NA'       | '50V'         | '1%'     | 'IO'       | 'CAP CHIP 33P 50V(+-1%,C0G,0402)'                              | 'CHIP0402'     | ''          | ''   | '20160906'
 '22UF'     | '6.3V'  | '20%'     | 'C0402'     | 'X5R'     | 'CH6221M9B01'(!)   = 'End of Design' | 'Comp-Approve'     | ''       | 'CH6221M9B01'     |'C0402'| '(C0402_OCTAGONXA,C0402-0201)'                                       | '22UF'     | '6.3V'        | '20%'    | 'DISCRETE' | 'CAP CHIP 22U 6.3V(+-20%,X5R,0402)'                            | 'CHIP0402'     | ''          | ''   | '20160906'
 '22UF'     | '6.3V'  | '20%'     | 'C0402'     | 'EMPTY'   | 'CH6221M9B01'(!)   = 'End of Design' | 'Comp-Approve'     | ''       | 'CH6221M9B01'     |'C0402'| '(C0402_OCTAGONXA,C0402-0201)'                                       | 'NA'       | '6.3V'        | '20%'    | 'IO'       | 'CAP CHIP 22U 6.3V(+-20%,X5R,0402)'                            | 'CHIP0402'     | ''          | ''   | '20160906'
 '22UF'     | '6.3V'  | '20%'     | 'C0402'     | 'X5R'     | 'SP_CH6221M9B01'(!) = ''              | ''                 | ''       | 'SP_CH6221M9B01'  |'C0402_SMDC25_SM30'| '(SMC0402AW)'                                                        | '22UF'     | '6.3V'        | '20%'    | 'DISCRETE' | 'CAP CHIP 22U 6.3V(+-20%,X5R,0402)_AMD FOOTPRINT SMDC25_SM30'  | 'CHIP0402'     | ''          | ''   | '20160906'
 '22UF'     | '6.3V'  | '20%'     | 'C0402'     | 'EMPTY'   | 'SP_CH6221M9B01'(!) = ''              | ''                 | ''       | 'SP_CH6221M9B01'  |'C0402_SMDC25_SM30'| '(SMC0402AW)'                                                        | 'NA'       | '6.3V'        | '20%'    | 'IO'       | 'CAP CHIP 22U 6.3V(+-20%,X5R,0402)_AMD FOOTPRINT SMDC25_SM30'  | 'CHIP0402'     | ''          | ''   | '20160906'
 '10UF'     | '4V'    | '20%'     | 'C0402'     | 'X5R'     | 'CH610KM9B00'(!)   = 'End of Design' | 'Comp-Approve'     | ''       | 'CH610KM9B00'     |'C0402'| '(C0402-0201)'                                                       | '10UF'     | '4V'          | '20%'    | 'DISCRETE' | 'CAP CHIP 10UF 4V(+-20%,X5R,0402)'                             | 'CHIP0402'     | ''          | ''   | '20161017'
 '10UF'     | '4V'    | '20%'     | 'C0402'     | 'EMPTY'   | 'CH610KM9B00'(!)   = 'End of Design' | 'Comp-Approve'     | ''       | 'CH610KM9B00'     |'C0402'| '(C0402-0201)'                                                       | 'NA'       | '4V'          | '20%'    | 'IO'       | 'CAP CHIP 10UF 4V(+-20%,X5R,0402)'                             | 'CHIP0402'     | ''          | ''   | '20161017'
 '10UF'     | '2.5V'  | '20%'     | 'C0402'     | 'X6S'     | 'CH610LMEB00'(!)   = ''              | ''                 | ''       | 'CH610LMEB00'     |'C0402'| '(C0402-0201)'                                                       | '10UF'     | '2.5V'        | '20%'    | 'DISCRETE' | 'CAP CHIP 10U 2.5V(+-20%,X6S,0402)MUR_AEC'                     | 'CHIP0402'     | ''          | ''   | '20161017'
 '10UF'     | '2.5V'  | '20%'     | 'C0402'     | 'EMPTY'   | 'CH610LMEB00'(!)   = ''              | ''                 | ''       | 'CH610LMEB00'     |'C0402'| '(C0402-0201)'                                                       | 'NA'       | '2.5V'        | '20%'    | 'IO'       | 'CAP CHIP 10U 2.5V(+-20%,X6S,0402)MUR_AEC'                     | 'CHIP0402'     | ''          | ''   | '20161017'
 '0.01UF'   | '16V'   | '10%'     | 'C0402'     | 'X7R'     | 'CH3103K1B24'(!)   = 'End of Design' | 'Comp-Release Qty' | ''       | 'CH3103K1B24'     |'C0402'| '(C0402-0201)'                                                       | '0.01UF'   | '16V'         | '10%'    | 'DISCRETE' | 'CAP CHIP 0.01U 16V(10%,X7R,0402)MUR_AEC'                      | 'CHIP0402'     | ''          | ''   | '20161017'
 '0.01UF'   | '16V'   | '10%'     | 'C0402'     | 'EMPTY'   | 'CH3103K1B24'(!)   = 'End of Design' | 'Comp-Release Qty' | ''       | 'CH3103K1B24'     |'C0402'| '(C0402-0201)'                                                       | 'NA'       | '16V'         | '10%'    | 'IO'       | 'CAP CHIP 0.01U 16V(10%,X7R,0402)MUR_AEC'                      | 'CHIP0402'     | ''          | ''   | '20161017'
 '6.8P'     | '50V'   | '0.05P'   | 'C0402'     | 'C0G'     | 'CH-686T0B01'(!)   = ''              | ''                 | ''       | 'CH-686T0B01'     |'C0402'| '(C0402-0201)'                                                       | '6.8P'     | '50V'         | '6.8P'   | 'DISCRETE' | 'CAP CHIP 6.8P 50V(0.05P,C0G,0402)MUR_AEC'                     | 'CHIP0402'     | ''          | ''   | '20161227'
 '6.8P'     | '50V'   | '0.05P'   | 'C0402'     | 'EMPTY'   | 'CH-686T0B01'(!)   = ''              | ''                 | ''       | 'CH-686T0B01'     |'C0402'| '(C0402-0201)'                                                       | 'NA'       | '50V'         | '6.8P'   | 'IO'       | 'CAP CHIP 6.8P 50V(0.05P,C0G,0402)MUR_AEC'                     | 'CHIP0402'     | ''          | ''   | '20161227'
 '2.2UF'    | '6.3V'  | '20%'     | 'C0402'     | 'X6S'     | 'CH5221MEB00'(!)   = ''              | ''                 | ''       | 'CH5221MEB00'     |'C0402'| '(C0402_OCTAGONXA,C0402-0201)'                                       | '2.2UF'    | '6.3V'        | '20%'    | 'DISCRETE' | 'CAP CHIP 2.2U 6.3V(+-20%,X6S,0402)'                           | 'CHIP0402'     | ''          | ''   | '20170330'
 '2.2UF'    | '6.3V'  | '20%'     | 'C0402'     | 'EMPTY'   | 'CH5221MEB00'(!)   = ''              | ''                 | ''       | 'CH5221MEB00'     |'C0402'| '(C0402_OCTAGONXA,C0402-0201)'                                       | 'NA'       | '6.3V'        | '20%'    | 'IO'       | 'CAP CHIP 2.2U 6.3V(+-20%,X6S,0402)'                           | 'CHIP0402'     | ''          | ''   | '20170330'
 '10UF'     | '6.3V'  | '20%'     | 'C0402'     | 'X6S'     | 'CH6101MEB01'(!)   = ''              | ''                 | ''       | 'CH6101MEB01'     |'C0402'| '(C0402_OCTAGONXA,C0402-0201)'                                       | '10UF'     | '6.3V'        | '20%'    | 'DISCRETE' | 'CAP CHIP 10UF 6.3V(+-20%,X6S,0402)'                           | 'CHIP0402'     | ''          | ''   | '20170330'
 '10UF'     | '6.3V'  | '20%'     | 'C0402'     | 'EMPTY'   | 'CH6101MEB01'(!)   = ''              | ''                 | ''       | 'CH6101MEB01'     |'C0402'| '(C0402_OCTAGONXA,C0402-0201)'                                       | 'NA'       | '6.3V'        | '20%'    | 'IO'       | 'CAP CHIP 10UF 6.3V(+-20%,X6S,0402)'                           | 'CHIP0402'     | ''          | ''   | '20170330'
 '47UF'     | '10V'   | '20%'     | 'C0805'     | 'X5R'     | 'CH6472M9A00'(!)   = 'End of Design' | 'Comp-Approve'     | ''       | 'CH6472M9A00'     |'C0805_H61'| '(SMC0805AW)'                                                        | '47UF'     | '10V'         | '20%'    | 'DISCRETE' | 'CAP CHIP 47U 10V(+-20%,X5R,0805)H1.25'                        | 'CHIP0805'     | ''          | ''   | '20170331'
 '47UF'     | '10V'   | '20%'     | 'C0805'     | 'EMPTY'   | 'CH6472M9A00'(!)   = 'End of Design' | 'Comp-Approve'     | ''       | 'CH6472M9A00'     |'C0805_H61'| '(SMC0805AW)'                                                        | 'NA'       | '10V'         | '20%'    | 'IO'       | 'CAP CHIP 47U 10V(+-20%,X5R,0805)H1.25'                        | 'CHIP0805'     | ''          | ''   | '20170331'
 '1000PF'   | '16V'   | '10%'     | 'C0201'     | 'X7R'     | 'CH2103K1E10'(!)   = ''              | ''                 | ''       | 'CH2103K1E10'     |'C0201'| '(SMC0201AW)'                                                        | '1000PF'   | '16V'         | '10%'    | 'DISCRETE' | 'CAP CHIP 1000P 16V(10%,X7R,0201)SAM'                          | 'CHIP0201'     | ''          | ''   | '20170427'
 '1000PF'   | '16V'   | '10%'     | 'C0201'     | 'EMPTY'   | 'CH2103K1E10'(!)   = ''              | ''                 | ''       | 'CH2103K1E10'     |'C0201'| '(SMC0201AW)'                                                        | 'NA'       | '16V'         | '10%'    | 'IO'       | 'CAP CHIP 1000P 16V(10%,X7R,0201)SAM'                          | 'CHIP0201'     | ''          | ''   | '20170427'
 '1000PF'   | '16V'   | '10%'     | 'C0201'     | 'X7R'     | 'CH2103K1E11'(!)   = ''              | ''                 | ''       | 'CH2103K1E11'     |'C0201'| '(SMC0201AW)'                                                        | '1000PF'   | '16V'         | '10%'    | 'DISCRETE' | 'CAP CHIP 1000P 16V(10%,X7R,0201)WTC'                          | 'CHIP0201'     | ''          | ''   | '20170427'
 '1000PF'   | '16V'   | '10%'     | 'C0201'     | 'EMPTY'   | 'CH2103K1E11'(!)   = ''              | ''                 | ''       | 'CH2103K1E11'     |'C0201'| '(SMC0201AW)'                                                        | 'NA'       | '16V'         | '10%'    | 'IO'       | 'CAP CHIP 1000P 16V(10%,X7R,0201)WTC'                          | 'CHIP0201'     | ''          | ''   | '20170427'
 '1UF'      | '4V'    | '20%'     | 'C0201'     | 'X6S'     | 'CH510KMEE04'(!)   = ''              | ''                 | ''       | 'CH510KMEE04'     |'C0201'| '(SMC0201AW)'                                                        | '1UF'      | '4V'          | '20%'    | 'DISCRETE' | 'CAP CHIP 1U 4V(+-20%,X6S,0201)TAY'                            | 'CHIP0201'     | ''          | ''   | '20170427'
 '1UF'      | '4V'    | '20%'     | 'C0201'     | 'EMPTY'   | 'CH510KMEE04'(!)   = ''              | ''                 | ''       | 'CH510KMEE04'     |'C0201'| '(SMC0201AW)'                                                        | 'NA'       | '4V'          | '20%'    | 'IO'       | 'CAP CHIP 1U 4V(+-20%,X6S,0201)TAY'                            | 'CHIP0201'     | ''          | ''   | '20170427'
 '1UF'      | '4V'    | '20%'     | 'C0201'     | 'X6S'     | 'CH510KMEE03'(!)   = ''              | ''                 | ''       | 'CH510KMEE03'     |'C0201'| '(SMC0201AW)'                                                        | '1UF'      | '4V'          | '20%'    | 'DISCRETE' | 'CAP CHIP 1U 4V(+-20%,X6S,0201)MUR'                            | 'CHIP0201'     | ''          | ''   | '20170427'
 '1UF'      | '4V'    | '20%'     | 'C0201'     | 'EMPTY'   | 'CH510KMEE03'(!)   = ''              | ''                 | ''       | 'CH510KMEE03'     |'C0201'| '(SMC0201AW)'                                                        | 'NA'       | '4V'          | '20%'    | 'IO'       | 'CAP CHIP 1U 4V(+-20%,X6S,0201)MUR'                            | 'CHIP0201'     | ''          | ''   | '20170427'
 '0.1UF'    | '6.3V'  | '10%'     | 'C0201'     | 'X6S'     | 'CH4101KEE03'(!)   = ''              | ''                 | ''       | 'CH4101KEE03'     |'C0201'| '(SMC0201AW)'                                                        | '0.1UF'    | '6.3V'        | '10%'    | 'DISCRETE' | 'CAP CHIP 0.1UF 6.3V(10%,X6S,0201)TAY'                         | 'CHIP0201'     | ''          | ''   | '20170427'
 '0.1UF'    | '6.3V'  | '10%'     | 'C0201'     | 'EMPTY'   | 'CH4101KEE03'(!)   = ''              | ''                 | ''       | 'CH4101KEE03'     |'C0201'| '(SMC0201AW)'                                                        | 'NA'       | '6.3V'        | '10%'    | 'IO'       | 'CAP CHIP 0.1UF 6.3V(10%,X6S,0201)TAY'                         | 'CHIP0201'     | ''          | ''   | '20170427'
 '0.1UF'    | '6.3V'  | '10%'     | 'C0201'     | 'X6S'     | 'CH4101KEE02'(!)   = ''              | ''                 | ''       | 'CH4101KEE02'     |'C0201'| '(SMC0201AW)'                                                        | '0.1UF'    | '6.3V'        | '10%'    | 'DISCRETE' | 'CAP CHIP 0.1UF 6.3V(10%,X6S,0201)SAM'                         | 'CHIP0201'     | ''          | ''   | '20170427'
 '0.1UF'    | '6.3V'  | '10%'     | 'C0201'     | 'EMPTY'   | 'CH4101KEE02'(!)   = ''              | ''                 | ''       | 'CH4101KEE02'     |'C0201'| '(SMC0201AW)'                                                        | 'NA'       | '6.3V'        | '10%'    | 'IO'       | 'CAP CHIP 0.1UF 6.3V(10%,X6S,0201)SAM'                         | 'CHIP0201'     | ''          | ''   | '20170427'
 '0.01UF'   | '16V'   | '10%'     | 'C0201'     | 'X7R'     | 'CH3103K1E02'(!)   = ''              | ''                 | ''       | 'CH3103K1E02'     |'C0201'| '(SMC0201AW)'                                                        | '0.01UF'   | '16V'         | '10%'    | 'DISCRETE' | 'CAP CHIP 0.01U 16V(+-10%,X7R,0201)YGO'                        | 'CHIP0201'     | ''          | ''   | '20170427'
 '0.01UF'   | '16V'   | '10%'     | 'C0201'     | 'EMPTY'   | 'CH3103K1E02'(!)   = ''              | ''                 | ''       | 'CH3103K1E02'     |'C0201'| '(SMC0201AW)'                                                        | 'NA'       | '16V'         | '10%'    | 'IO'       | 'CAP CHIP 0.01U 16V(+-10%,X7R,0201)YGO'                        | 'CHIP0201'     | ''          | ''   | '20170427'
 '2200PF'   | '50V'   | '10%'     | 'C0402'     | 'X7R'     | 'CH2226K1B15'(!)   = ''              | ''                 | ''       | 'CH2226K1B15'     |'C0402'| '(C0402-0201)'                                                       | '2200PF'   | '50V'         | '10%'    | 'DISCRETE' | 'CAP CHIP 2200P 50V(+-10%,X7R,0402)SAM'                        | 'CHIP0402'     | ''          | ''   | '20170427'
 '2200PF'   | '50V'   | '10%'     | 'C0402'     | 'EMPTY'   | 'CH2226K1B15'(!)   = ''              | ''                 | ''       | 'CH2226K1B15'     |'C0402'| '(C0402-0201)'                                                       | 'NA'       | '50V'         | '10%'    | 'IO'       | 'CAP CHIP 2200P 50V(+-10%,X7R,0402)SAM'                        | 'CHIP0402'     | ''          | ''   | '20170427'
 '100PF'    | '50V'   | '5%'      | 'C0402'     | 'NPO'     | 'CH1106J0B23'(!)   = ''              | ''                 | ''       | 'CH1106J0B23'     |'C0402'| '(C0402-0201)'                                                       | '100PF'    | '50V'         | '5%'     | 'DISCRETE' | 'CAP CHIP 100P 50V(+-5%,NPO,0402)YGO'                          | 'CHIP0402'     | ''          | ''   | '20170427'
 '100PF'    | '50V'   | '5%'      | 'C0402'     | 'EMPTY'   | 'CH1106J0B23'(!)   = ''              | ''                 | ''       | 'CH1106J0B23'     |'C0402'| '(C0402-0201)'                                                       | 'NA'       | '50V'         | '5%'     | 'IO'       | 'CAP CHIP 100P 50V(+-5%,NPO,0402)YGO'                          | 'CHIP0402'     | ''          | ''   | '20170427'
 '100PF'    | '50V'   | '5%'      | 'C0402'     | 'NPO'     | 'CH1106J0B22'(!)   = ''              | ''                 | ''       | 'CH1106J0B22'     |'C0402'| '(C0402-0201)'                                                       | '100PF'    | '50V'         | '5%'     | 'DISCRETE' | 'CAP CHIP 100P 50V(+-5%,NPO,0402)WTC'                          | 'CHIP0402'     | ''          | ''   | '20170427'
 '100PF'    | '50V'   | '5%'      | 'C0402'     | 'EMPTY'   | 'CH1106J0B22'(!)   = ''              | ''                 | ''       | 'CH1106J0B22'     |'C0402'| '(C0402-0201)'                                                       | 'NA'       | '50V'         | '5%'     | 'IO'       | 'CAP CHIP 100P 50V(+-5%,NPO,0402)WTC'                          | 'CHIP0402'     | ''          | ''   | '20170427'
 '1000PF'   | '50V'   | '5%'      | 'C0402'     | 'X7R'     | 'CH2106J1B08'(!)   = ''              | ''                 | ''       | 'CH2106J1B08'     |'C0402'| '(C0402-0201)'                                                       | '1000PF'   | '50V'         | '5%'     | 'DISCRETE' | 'CAP CHIP 1000P 50V(+-5%,X7R,0402)WTC'                         | 'CHIP0402'     | ''          | ''   | '20170427'
 '1000PF'   | '50V'   | '5%'      | 'C0402'     | 'EMPTY'   | 'CH2106J1B08'(!)   = ''              | ''                 | ''       | 'CH2106J1B08'     |'C0402'| '(C0402-0201)'                                                       | 'NA'       | '50V'         | '5%'     | 'IO'       | 'CAP CHIP 1000P 50V(+-5%,X7R,0402)WTC'                         | 'CHIP0402'     | ''          | ''   | '20170427'
 '1000PF'   | '50V'   | '5%'      | 'C0402'     | 'X7R'     | 'CH2106J1B05'(!)   = ''              | ''                 | ''       | 'CH2106J1B05'     |'C0402'| '(C0402-0201)'                                                       | '1000PF'   | '50V'         | '5%'     | 'DISCRETE' | 'CAP CHIP 1000P 50V(+-5%,X7R,0402)SAM'                         | 'CHIP0402'     | ''          | ''   | '20170427'
 '1000PF'   | '50V'   | '5%'      | 'C0402'     | 'EMPTY'   | 'CH2106J1B05'(!)   = ''              | ''                 | ''       | 'CH2106J1B05'     |'C0402'| '(C0402-0201)'                                                       | 'NA'       | '50V'         | '5%'     | 'IO'       | 'CAP CHIP 1000P 50V(+-5%,X7R,0402)SAM'                         | 'CHIP0402'     | ''          | ''   | '20170427'
 '0.01UF'   | '50V'   | '10%'     | 'C0402'     | 'X7R'     | 'CH3106K1B11'(!)   = ''              | ''                 | ''       | 'CH3106K1B11'     |'C0402'| '(C0402-0201)'                                                       | '0.01UF'   | '50V'         | '10%'    | 'DISCRETE' | 'CAP CHIP 0.01U 50V(+-10%,X7R,0402)WTC'                        | 'CHIP0402'     | ''          | ''   | '20170427'
 '0.01UF'   | '50V'   | '10%'     | 'C0402'     | 'EMPTY'   | 'CH3106K1B11'(!)   = ''              | ''                 | ''       | 'CH3106K1B11'     |'C0402'| '(C0402-0201)'                                                       | 'NA'       | '50V'         | '10%'    | 'IO'       | 'CAP CHIP 0.01U 50V(+-10%,X7R,0402)WTC'                        | 'CHIP0402'     | ''          | ''   | '20170427'
 '0.01UF'   | '50V'   | '10%'     | 'C0402'     | 'X7R'     | 'CH3106K1B06'(!)   = ''              | ''                 | ''       | 'CH3106K1B06'     |'C0402'| '(C0402-0201)'                                                       | '0.01UF'   | '50V'         | '10%'    | 'DISCRETE' | 'CAP CHIP 0.01U 50V(+-10%,X7R,0402)SAM'                        | 'CHIP0402'     | ''          | ''   | '20170427'
 '0.01UF'   | '50V'   | '10%'     | 'C0402'     | 'EMPTY'   | 'CH3106K1B06'(!)   = ''              | ''                 | ''       | 'CH3106K1B06'     |'C0402'| '(C0402-0201)'                                                       | 'NA'       | '50V'         | '10%'    | 'IO'       | 'CAP CHIP 0.01U 50V(+-10%,X7R,0402)SAM'                        | 'CHIP0402'     | ''          | ''   | '20170427'
 '0.047UF'  | '25V'   | '10%'     | 'C0402'     | 'X7R'     | 'CH3474K1B09'(!)   = ''              | ''                 | ''       | 'CH3474K1B09'     |'C0402'| '(C0402-0201)'                                                       | '0.047UF'  | '25V'         | '10%'    | 'DISCRETE' | 'CAP CHIP 0.047U 25V(+-10%,X7R,0402)WTC'                       | 'CHIP0402'     | ''          | ''   | '20170427'
 '0.047UF'  | '25V'   | '10%'     | 'C0402'     | 'EMPTY'   | 'CH3474K1B09'(!)   = ''              | ''                 | ''       | 'CH3474K1B09'     |'C0402'| '(C0402-0201)'                                                       | 'NA'       | '25V'         | '10%'    | 'IO'       | 'CAP CHIP 0.047U 25V(+-10%,X7R,0402)WTC'                       | 'CHIP0402'     | ''          | ''   | '20170427'
 '0.1UF'    | '25V'   | '10%'     | 'C0402'     | 'X7R'     | 'CH4104K9B08'(!)   = 'End of Design' | 'Comp-Approve'     | ''       | 'CH4104K9B08'     |'C0402'| '(C0402-0201)'                                                       | '0.1UF'    | '25V'         | '10%'    | 'DISCRETE' | 'CAP CHIP 0.1U 25V(+-10%,X7R,0402)SAM'                         | 'CHIP0402'     | ''          | ''   | '20170427'
 '0.1UF'    | '25V'   | '10%'     | 'C0402'     | 'EMPTY'   | 'CH4104K9B08'(!)   = 'End of Design' | 'Comp-Approve'     | ''       | 'CH4104K9B08'     |'C0402'| '(C0402-0201)'                                                       | 'NA'       | '25V'         | '10%'    | 'IO'       | 'CAP CHIP 0.1U 25V(+-10%,X7R,0402)SAM'                         | 'CHIP0402'     | ''          | ''   | '20170427'
 '0.1UF'    | '25V'   | '10%'     | 'C0402'     | 'X7R'     | 'CH4104K1B09'(!)   = ''              | ''                 | ''       | 'CH4104K1B09'     |'C0402'| '(C0402-0201)'                                                       | '0.1UF'    | '25V'         | '10%'    | 'DISCRETE' | 'CAP CHIP 0.1U 25V(+-10%,X7R,0402)WTC'                         | 'CHIP0402'     | ''          | ''   | '20170427'
 '0.1UF'    | '25V'   | '10%'     | 'C0402'     | 'EMPTY'   | 'CH4104K1B09'(!)   = ''              | ''                 | ''       | 'CH4104K1B09'     |'C0402'| '(C0402-0201)'                                                       | 'NA'       | '25V'         | '10%'    | 'IO'       | 'CAP CHIP 0.1U 25V(+-10%,X7R,0402)WTC'                         | 'CHIP0402'     | ''          | ''   | '20170427'
 '1UF'      | '6.3V'  | '10%'     | 'C0402'     | 'X5R'     | 'CH5101K9B23'(!)   = ''              | ''                 | ''       | 'CH5101K9B23'     |'C0402'| '(C0402-0201)'                                                       | '1UF'      | '6.3V'        | '10%'    | 'DISCRETE' | 'CAP CHIP 1U 6.3V(+-10%,X5R,0402)SAM'                          | 'CHIP0402'     | ''          | ''   | '20170427'
 '1UF'      | '6.3V'  | '10%'     | 'C0402'     | 'EMPTY'   | 'CH5101K9B23'(!)   = ''              | ''                 | ''       | 'CH5101K9B23'     |'C0402'| '(C0402-0201)'                                                       | 'NA'       | '6.3V'        | '10%'    | 'IO'       | 'CAP CHIP 1U 6.3V(+-10%,X5R,0402)SAM'                          | 'CHIP0402'     | ''          | ''   | '20170427'
 '1UF'      | '6.3V'  | '10%'     | 'C0402'     | 'X5R'     | 'CH5101K9B17'(!)   = ''              | ''                 | ''       | 'CH5101K9B17'     |'C0402'| '(C0402-0201)'                                                       | '1UF'      | '6.3V'        | '10%'    | 'DISCRETE' | 'CAP CHIP 1U 6.3V(+-10%,X5R,0402)WTC'                          | 'CHIP0402'     | ''          | ''   | '20170427'
 '1UF'      | '6.3V'  | '10%'     | 'C0402'     | 'EMPTY'   | 'CH5101K9B17'(!)   = ''              | ''                 | ''       | 'CH5101K9B17'     |'C0402'| '(C0402-0201)'                                                       | 'NA'       | '6.3V'        | '10%'    | 'IO'       | 'CAP CHIP 1U 6.3V(+-10%,X5R,0402)WTC'                          | 'CHIP0402'     | ''          | ''   | '20170427'
 '1UF'      | '6.3V'  | '10%'     | 'C0402'     | 'X6S'     | 'CH5101KEB03'(!)   = ''              | ''                 | ''       | 'CH5101KEB03'     |'C0402'| '(C0402-0201)'                                                       | '1UF'      | '6.3V'        | '10%'    | 'DISCRETE' | 'CAP CHIP 1U 6.3V(+-10%,X6S,0402)SAM'                          | 'CHIP0402'     | ''          | ''   | '20170427'
 '1UF'      | '6.3V'  | '10%'     | 'C0402'     | 'EMPTY'   | 'CH5101KEB03'(!)   = ''              | ''                 | ''       | 'CH5101KEB03'     |'C0402'| '(C0402-0201)'                                                       | 'NA'       | '6.3V'        | '10%'    | 'IO'       | 'CAP CHIP 1U 6.3V(+-10%,X6S,0402)SAM'                          | 'CHIP0402'     | ''          | ''   | '20170427'
 '1UF'      | '6.3V'  | '10%'     | 'C0402'     | 'X6S'     | 'CH5101KEB02'(!)   = 'End of Design' | 'Comp-Approve'     | ''       | 'CH5101KEB02'     |'C0402'| '(C0402_OCTAGONXA,C0402-0201)'                                       | '1UF'      | '6.3V'        | '10%'    | 'DISCRETE' | 'CAP CHIP 1U 6.3V(+-10%,X6S,0402)MUR'                          | 'CHIP0402'     | ''          | ''   | '20170427'
 '1UF'      | '6.3V'  | '10%'     | 'C0402'     | 'EMPTY'   | 'CH5101KEB02'(!)   = 'End of Design' | 'Comp-Approve'     | ''       | 'CH5101KEB02'     |'C0402'| '(C0402_OCTAGONXA,C0402-0201)'                                       | 'NA'       | '6.3V'        | '10%'    | 'IO'       | 'CAP CHIP 1U 6.3V(+-10%,X6S,0402)MUR'                          | 'CHIP0402'     | ''          | ''   | '20170427'
 '1UF'      | '25V'   | '10%'     | 'C0402'     | 'X6S'     | 'CH5104KEB07'(!)   = 'End of Design' | 'Comp-Approve'     | ''       | 'CH5104KEB07'     |'C0402'| '(C0402-0201)'                                                       | '1UF'      | '25V'         | '10%'    | 'DISCRETE' | 'CAP CHIP 1UF 25V(+-10%,X6S,0402)WTC'                          | 'CHIP0402'     | ''          | ''   | '20170427'
 '1UF'      | '25V'   | '10%'     | 'C0402'     | 'EMPTY'   | 'CH5104KEB07'(!)   = 'End of Design' | 'Comp-Approve'     | ''       | 'CH5104KEB07'     |'C0402'| '(C0402-0201)'                                                       | 'NA'       | '25V'         | '10%'    | 'IO'       | 'CAP CHIP 1UF 25V(+-10%,X6S,0402)WTC'                          | 'CHIP0402'     | ''          | ''   | '20170427'
 '10UF'     | '16V'   | '20%'     | 'C0603'     | 'X6S'     | 'CH6103ME905'(!)   = ''              | ''                 | ''       | 'CH6103ME905'     |'C0603'| '(SMC0603AW)'                                                        | '10UF'     | '16V'         | '20%'    | 'DISCRETE' | 'CAP CHIP 10U 16V(+-20%,X6S,0603)WTC'                          | 'CHIP0603'     | ''          | ''   | '20170426'
 '10UF'     | '16V'   | '20%'     | 'C0603'     | 'EMPTY'   | 'CH6103ME905'(!)   = ''              | ''                 | ''       | 'CH6103ME905'     |'C0603'| '(SMC0603AW)'                                                        | 'NA'       | '16V'         | '20%'    | 'IO'       | 'CAP CHIP 10U 16V(+-20%,X6S,0603)WTC'                          | 'CHIP0603'     | ''          | ''   | '20170426'
 '10UF'     | '16V'   | '20%'     | 'C0603'     | 'X6S'     | 'CH6103ME904'(!)   = ''              | ''                 | ''       | 'CH6103ME904'     |'C0603'| '(SMC0603AW)'                                                        | '10UF'     | '16V'         | '20%'    | 'DISCRETE' | 'CAP CHIP 10UF 16V(+-20%,X6S,0603)MUR'                         | 'CHIP0603'     | ''          | ''   | '20170426'
 '10UF'     | '16V'   | '20%'     | 'C0603'     | 'EMPTY'   | 'CH6103ME904'(!)   = ''              | ''                 | ''       | 'CH6103ME904'     |'C0603'| '(SMC0603AW)'                                                        | 'NA'       | '16V'         | '20%'    | 'IO'       | 'CAP CHIP 10UF 16V(+-20%,X6S,0603)MUR'                         | 'CHIP0603'     | ''          | ''   | '20170426'
 '10UF'     | '6.3V'  | '20%'     | 'C0603'     | 'X6S'     | 'CH6101ME904'(!)   = ''              | ''                 | ''       | 'CH6101ME904'     |'C0603'| '(SMC0603AW)'                                                        | '10UF'     | '6.3V'        | '20%'    | 'DISCRETE' | 'CAP CHIP 10U 6.3V(+-20%,X6S,0603)SAM'                         | 'CHIP0603'     | ''          | ''   | '20170426'
 '10UF'     | '6.3V'  | '20%'     | 'C0603'     | 'EMPTY'   | 'CH6101ME904'(!)   = ''              | ''                 | ''       | 'CH6101ME904'     |'C0603'| '(SMC0603AW)'                                                        | 'NA'       | '6.3V'        | '20%'    | 'IO'       | 'CAP CHIP 10U 6.3V(+-20%,X6S,0603)SAM'                         | 'CHIP0603'     | ''          | ''   | '20170426'
 '4.7UF'    | '6.3V'  | '10%'     | 'C0603'     | 'X6S'     | 'CH5471KE904'(!)   = 'End of Design' | 'Comp-Approve'     | ''       | 'CH5471KE904'     |'C0603'| '(SMC0603AW)'                                                        | '4.7UF'    | '6.3V'        | '10%'    | 'DISCRETE' | 'CAP CHIP 4.7U 6.3V(+-10%,X6S,0603)SAM'                        | 'CHIP0603'     | ''          | ''   | '20170426'
 '4.7UF'    | '6.3V'  | '10%'     | 'C0603'     | 'EMPTY'   | 'CH5471KE904'(!)   = 'End of Design' | 'Comp-Approve'     | ''       | 'CH5471KE904'     |'C0603'| '(SMC0603AW)'                                                        | 'NA'       | '6.3V'        | '10%'    | 'IO'       | 'CAP CHIP 4.7U 6.3V(+-10%,X6S,0603)SAM'                        | 'CHIP0603'     | ''          | ''   | '20170426'
 '0.033UF'  | '50V'   | '10%'     | 'C0603'     | 'X7R'     | 'CH3336K1906'(!)   = 'End of Design' | 'Comp-Approve'     | ''       | 'CH3336K1906'     |'C0603'| '(SMC0603AW)'                                                        | '0.033UF'  | '50V'         | '10%'    | 'DISCRETE' | 'CAP CHIP 0.033U 50V(+-10%,X7R,0603)WTC'                       | 'CHIP0603'     | ''          | ''   | '20170426'
 '0.033UF'  | '50V'   | '10%'     | 'C0603'     | 'EMPTY'   | 'CH3336K1906'(!)   = 'End of Design' | 'Comp-Approve'     | ''       | 'CH3336K1906'     |'C0603'| '(SMC0603AW)'                                                        | 'NA'       | '50V'         | '10%'    | 'IO'       | 'CAP CHIP 0.033U 50V(+-10%,X7R,0603)WTC'                       | 'CHIP0603'     | ''          | ''   | '20170426'
 '22UF'     | '6.3V'  | '20%'     | 'C0603'     | 'X6S'     | 'CH6221ME902'(!)   = 'End of Design' | 'Comp-Approve'     | ''       | 'CH6221ME902'     |'C0603'| '(SMC0603AW)'                                                        | '22UF'     | '6.3V'        | '20%'    | 'DISCRETE' | 'CAP CHIP 22U 6.3V(+-20%,X6S,0603)WTC'                         | 'CHIP0603'     | ''          | ''   | '20170426'
 '22UF'     | '6.3V'  | '20%'     | 'C0603'     | 'EMPTY'   | 'CH6221ME902'(!)   = 'End of Design' | 'Comp-Approve'     | ''       | 'CH6221ME902'     |'C0603'| '(SMC0603AW)'                                                        | 'NA'       | '6.3V'        | '20%'    | 'IO'       | 'CAP CHIP 22U 6.3V(+-20%,X6S,0603)WTC'                         | 'CHIP0603'     | ''          | ''   | '20170426'
 '22UF'     | '6.3V'  | '20%'     | 'C0603'     | 'X6S'     | 'CH6221ME901'(!)   = ''              | ''                 | ''       | 'CH6221ME901'     |'C0603'| '(SMC0603AW)'                                                        | '22UF'     | '6.3V'        | '20%'    | 'DISCRETE' | 'CAP CHIP 22U 6.3V(+-20%,X6S,0603)MUR'                         | 'CHIP0603'     | ''          | ''   | '20170426'
 '22UF'     | '6.3V'  | '20%'     | 'C0603'     | 'EMPTY'   | 'CH6221ME901'(!)   = ''              | ''                 | ''       | 'CH6221ME901'     |'C0603'| '(SMC0603AW)'                                                        | 'NA'       | '6.3V'        | '20%'    | 'IO'       | 'CAP CHIP 22U 6.3V(+-20%,X6S,0603)MUR'                         | 'CHIP0603'     | ''          | ''   | '20170426'
 '10UF'     | '6.3V'  | '20%'     | 'C0603'     | 'X5R'     | 'CH6101M9921'(!)   = ''              | ''                 | ''       | 'CH6101M9921'     |'C0603'| '(SMC0603AW)'                                                        | '10UF'     | '6.3V'        | '20%'    | 'DISCRETE' | 'CAP CHIP 10U 6.3V(+-20%,X5R,0603)SAM'                         | 'CHIP0603'     | ''          | ''   | '20170427'
 '10UF'     | '6.3V'  | '20%'     | 'C0603'     | 'EMPTY'   | 'CH6101M9921'(!)   = ''              | ''                 | ''       | 'CH6101M9921'     |'C0603'| '(SMC0603AW)'                                                        | 'NA'       | '6.3V'        | '20%'    | 'IO'       | 'CAP CHIP 10U 6.3V(+-20%,X5R,0603)SAM'                         | 'CHIP0603'     | ''          | ''   | '20170427'
 '10UF'     | '6.3V'  | '20%'     | 'C0603'     | 'X5R'     | 'CH6101M9914'(!)   = 'End of Design' | 'Comp-Approve'     | ''       | 'CH6101M9914'     |'C0603'| '(SMC0603AW)'                                                        | '10UF'     | '6.3V'        | '20%'    | 'DISCRETE' | 'CAP CHIP 10U 6.3V(+-20%,X5R,0603)YGO'                         | 'CHIP0603'     | ''          | ''   | '20170427'
 '10UF'     | '6.3V'  | '20%'     | 'C0603'     | 'EMPTY'   | 'CH6101M9914'(!)   = 'End of Design' | 'Comp-Approve'     | ''       | 'CH6101M9914'     |'C0603'| '(SMC0603AW)'                                                        | 'NA'       | '6.3V'        | '20%'    | 'IO'       | 'CAP CHIP 10U 6.3V(+-20%,X5R,0603)YGO'                         | 'CHIP0603'     | ''          | ''   | '20170427'
 '22PF'     | '50V'   | '5%'      | 'C0402'     | 'NPO'     | 'CH0226J0B22'(!)   = ''              | ''                 | ''       | 'CH0226J0B22'     |'C0402'| '(C0402-0201)'                                                       | '22PF'     | '50V'         | '5%'     | 'DISCRETE' | 'CAP CHIP 22P 50V(+-5%,NPO,0402)SAM'                           | 'CHIP0402'     | ''          | ''   | '20170427'
 '22PF'     | '50V'   | '5%'      | 'C0402'     | 'EMPTY'   | 'CH0226J0B22'(!)   = ''              | ''                 | ''       | 'CH0226J0B22'     |'C0402'| '(C0402-0201)'                                                       | 'NA'       | '50V'         | '5%'     | 'IO'       | 'CAP CHIP 22P 50V(+-5%,NPO,0402)SAM'                           | 'CHIP0402'     | ''          | ''   | '20170427'
 '0.1UF'    | '16V'   | '10%'     | 'C0402'     | 'X7R'     | 'CH4103K1B19'(!)   = 'End of Design' | 'Comp-Approve'     | ''       | 'CH4103K1B19'     |'C0402'| '(C0402-0201)'                                                       | '0.1UF'    | '16V'         | '10%'    | 'DISCRETE' | 'CAP CHIP 0.1U 16V(10%,X7R,0402)SAM'                           | 'CHIP0402'     | ''          | ''   | '20170427'
 '0.1UF'    | '16V'   | '10%'     | 'C0402'     | 'EMPTY'   | 'CH4103K1B19'(!)   = 'End of Design' | 'Comp-Approve'     | ''       | 'CH4103K1B19'     |'C0402'| '(C0402-0201)'                                                       | 'NA'       | '16V'         | '10%'    | 'IO'       | 'CAP CHIP 0.1U 16V(10%,X7R,0402)SAM'                           | 'CHIP0402'     | ''          | ''   | '20170427'
 '10UF'     | '10V'   | '20%'     | 'C0402'     | 'X5R'     | 'CH6102M9B11'(!)   = ''              | ''                 | ''       | 'CH6102M9B11'     |'C0402'| '(C0402-0201)'                                                       | '10UF'     | '10V'         | '20%'    | 'DISCRETE' | 'CAP CHIP 10U 10V(+-20%, X5R,0402)YGO'                         | 'CHIP0402'     | ''          | ''   | '20170427'
 '10UF'     | '10V'   | '20%'     | 'C0402'     | 'EMPTY'   | 'CH6102M9B11'(!)   = ''              | ''                 | ''       | 'CH6102M9B11'     |'C0402'| '(C0402-0201)'                                                       | 'NA'       | '10V'         | '20%'    | 'IO'       | 'CAP CHIP 10U 10V(+-20%, X5R,0402)YGO'                         | 'CHIP0402'     | ''          | ''   | '20170427'
 '10PF'     | '50V'   | '5%'      | 'C0402'     | 'C0G'     | 'CH0106J0B17'(!)   = ''              | ''                 | ''       | 'CH0106J0B17'     |'C0402'| '(C0402-0201)'                                                       | '10PF'     | '50V'         | '5%'     | 'DISCRETE' | 'CAP CHIP 10P 50V(+-5%,C0G,0402)MUR'                           | 'CHIP0402'     | ''          | ''   | '20170427'
 '10PF'     | '50V'   | '5%'      | 'C0402'     | 'EMPTY'   | 'CH0106J0B17'(!)   = ''              | ''                 | ''       | 'CH0106J0B17'     |'C0402'| '(C0402-0201)'                                                       | 'NA'       | '50V'         | '5%'     | 'IO'       | 'CAP CHIP 10P 50V(+-5%,C0G,0402)MUR'                           | 'CHIP0402'     | ''          | ''   | '20170427'
 '10PF'     | '50V'   | '5%'      | 'C0402'     | 'C0G'     | 'CH0106J0B18'(!)   = ''              | ''                 | ''       | 'CH0106J0B18'     |'C0402'| '(C0402-0201)'                                                       | '10PF'     | '50V'         | '5%'     | 'DISCRETE' | 'CAP CHIP 10P 50V(+-5%,C0G,0402)YGO'                           | 'CHIP0402'     | ''          | ''   | '20170427'
 '10PF'     | '50V'   | '5%'      | 'C0402'     | 'EMPTY'   | 'CH0106J0B18'(!)   = ''              | ''                 | ''       | 'CH0106J0B18'     |'C0402'| '(C0402-0201)'                                                       | 'NA'       | '50V'         | '5%'     | 'IO'       | 'CAP CHIP 10P 50V(+-5%,C0G,0402)YGO'                           | 'CHIP0402'     | ''          | ''   | '20170427'
 '12PF'     | '50V'   | '5%'      | 'C0402'     | 'C0G'     | 'CH0126J0B15'(!)   = ''              | ''                 | ''       | 'CH0126J0B15'     |'C0402'| '(C0402-0201)'                                                       | '12PF'     | '50V'         | '5%'     | 'DISCRETE' | 'CAP CHIP 12P 50V(+-5%,C0G,0402)WTC'                           | 'CHIP0402'     | ''          | ''   | '20170427'
 '12PF'     | '50V'   | '5%'      | 'C0402'     | 'EMPTY'   | 'CH0126J0B15'(!)   = ''              | ''                 | ''       | 'CH0126J0B15'     |'C0402'| '(C0402-0201)'                                                       | 'NA'       | '50V'         | '5%'     | 'IO'       | 'CAP CHIP 12P 50V(+-5%,C0G,0402)WTC'                           | 'CHIP0402'     | ''          | ''   | '20170427'
 '12PF'     | '50V'   | '5%'      | 'C0402'     | 'NP0'     | 'CH0126J0B10'(!)   = ''              | ''                 | ''       | 'CH0126J0B10'     |'C0402'| '(C0402-0201)'                                                       | '12PF'     | '50V'         | '5%'     | 'DISCRETE' | 'CAP CHIP 12P 50V(+-5%,NP0,0402)TAY'                           | 'CHIP0402'     | ''          | ''   | '20170427'
 '12PF'     | '50V'   | '5%'      | 'C0402'     | 'EMPTY'   | 'CH0126J0B10'(!)   = ''              | ''                 | ''       | 'CH0126J0B10'     |'C0402'| '(C0402-0201)'                                                       | 'NA'       | '50V'         | '5%'     | 'IO'       | 'CAP CHIP 12P 50V(+-5%,NP0,0402)TAY'                           | 'CHIP0402'     | ''          | ''   | '20170427'
 '2200PF'   | '50V'   | '10%'     | 'C0402'     | 'X7R'     | 'CH2226K1B12'(!)   = ''              | ''                 | ''       | 'CH2226K1B12'     |'C0402'| '(C0402-0201)'                                                       | '2200PF'   | '50V'         | '10%'    | 'DISCRETE' | 'CAP CHIP 2200P 50V(+-10%,X7R,0402)TAY'                        | 'CHIP0402'     | ''          | ''   | '20170427'
 '2200PF'   | '50V'   | '10%'     | 'C0402'     | 'EMPTY'   | 'CH2226K1B12'(!)   = ''              | ''                 | ''       | 'CH2226K1B12'     |'C0402'| '(C0402-0201)'                                                       | 'NA'       | '50V'         | '10%'    | 'IO'       | 'CAP CHIP 2200P 50V(+-10%,X7R,0402)TAY'                        | 'CHIP0402'     | ''          | ''   | '20170427'
 '0.22UF'   | '16V'   | '10%'     | 'C0402'     | 'X7R'     | 'CH4223K1B05'(!)   = 'End of Design' | 'Comp-Approve'     | ''       | 'CH4223K1B05'     |'C0402'| '(C0402-0201)'                                                       | '0.22UF'   | '16V'         | '10%'    | 'DISCRETE' | 'CAP CHIP 0.22U 16V(10%,X7R,0402)SAM'                          | 'CHIP0402'     | ''          | ''   | '20170427'
 '0.22UF'   | '16V'   | '10%'     | 'C0402'     | 'EMPTY'   | 'CH4223K1B05'(!)   = 'End of Design' | 'Comp-Approve'     | ''       | 'CH4223K1B05'     |'C0402'| '(C0402-0201)'                                                       | 'NA'       | '16V'         | '10%'    | 'IO'       | 'CAP CHIP 0.22U 16V(10%,X7R,0402)SAM'                          | 'CHIP0402'     | ''          | ''   | '20170427'
 '4.7UF'    | '6.3V'  | '20%'     | 'C0402'     | 'X6S'     | 'CH5471MEB04'(!)   = ''              | ''                 | ''       | 'CH5471MEB04'     |'C0402'| '(C0402-0201)'                                                       | '4.7UF'    | '6.3V'        | '20%'    | 'DISCRETE' | 'CAP CHIP 4.7UF 6.3V(+-20%,X6S,0402)TAY'                       | 'CHIP0402'     | ''          | ''   | '20170427'
 '4.7UF'    | '6.3V'  | '20%'     | 'C0402'     | 'EMPTY'   | 'CH5471MEB04'(!)   = ''              | ''                 | ''       | 'CH5471MEB04'     |'C0402'| '(C0402-0201)'                                                       | 'NA'       | '6.3V'        | '20%'    | 'IO'       | 'CAP CHIP 4.7UF 6.3V(+-20%,X6S,0402)TAY'                       | 'CHIP0402'     | ''          | ''   | '20170427'
 '1UF'      | '6.3V'  | '10%'     | 'C0402'     | 'X7R'     | 'CH5101K1B06'(!)   = ''              | ''                 | ''       | 'CH5101K1B06'     |'C0402'| '(C0402-0201)'                                                       | '1UF'      | '6.3V'        | '10%'    | 'DISCRETE' | 'CAP CHIP 1U,6.3V(+-10%,X7R,0402)SAM'                          | 'CHIP0402'     | ''          | ''   | '20170427'
 '1UF'      | '6.3V'  | '10%'     | 'C0402'     | 'EMPTY'   | 'CH5101K1B06'(!)   = ''              | ''                 | ''       | 'CH5101K1B06'     |'C0402'| '(C0402-0201)'                                                       | 'NA'       | '6.3V'        | '10%'    | 'IO'       | 'CAP CHIP 1U,6.3V(+-10%,X7R,0402)SAM'                          | 'CHIP0402'     | ''          | ''   | '20170427'
 '1500PF'   | '50V'   | '10%'     | 'C0402'     | 'X7R'     | 'CH2156K1B09'(!)   = ''              | ''                 | ''       | 'CH2156K1B09'     |'C0402'| '(C0402-0201)'                                                       | '1500PF'   | '50V'         | '10%'    | 'DISCRETE' | 'CAP CHIP 1500PF 50V(+-10%,X7R,0402)SAM'                       | 'CHIP0402'     | ''          | ''   | '20170427'
 '1500PF'   | '50V'   | '10%'     | 'C0402'     | 'EMPTY'   | 'CH2156K1B09'(!)   = ''              | ''                 | ''       | 'CH2156K1B09'     |'C0402'| '(C0402-0201)'                                                       | 'NA'       | '50V'         | '10%'    | 'IO'       | 'CAP CHIP 1500PF 50V(+-10%,X7R,0402)SAM'                       | 'CHIP0402'     | ''          | ''   | '20170427'
 '1500PF'   | '50V'   | '10%'     | 'C0402'     | 'X7R'     | 'CH2156K1B10'(!)   = ''              | ''                 | ''       | 'CH2156K1B10'     |'C0402'| '(C0402-0201)'                                                       | '1500PF'   | '50V'         | '10%'    | 'DISCRETE' | 'CAP CHIP 1500PF 50V(+-10%,X7R,0402)WTC'                       | 'CHIP0402'     | ''          | ''   | '20170427'
 '1500PF'   | '50V'   | '10%'     | 'C0402'     | 'EMPTY'   | 'CH2156K1B10'(!)   = ''              | ''                 | ''       | 'CH2156K1B10'     |'C0402'| '(C0402-0201)'                                                       | 'NA'       | '50V'         | '10%'    | 'IO'       | 'CAP CHIP 1500PF 50V(+-10%,X7R,0402)WTC'                       | 'CHIP0402'     | ''          | ''   | '20170427'
 '1200PF'   | '50V'   | '10%'     | 'C0402'     | 'X7R'     | 'CH2126K1B03'(!)   = 'End of Design' | 'End of Life'      | ''       | 'CH2126K1B03'     |'C0402_EOL'| '(C0402-0201)'                                                       | '1200PF'   | '50V'         | '10%'    | 'DISCRETE' | 'CAP CHIP 1200P 50V(+-10%,X7R,0402)SAM'                        | 'CHIP0402'     | ''          | ''   | '20170427'
 '1200PF'   | '50V'   | '10%'     | 'C0402'     | 'EMPTY'   | 'CH2126K1B03'(!)   = 'End of Design' | 'End of Life'      | ''       | 'CH2126K1B03'     |'C0402_EOL'| '(C0402-0201)'                                                       | 'NA'       | '50V'         | '10%'    | 'IO'       | 'CAP CHIP 1200P 50V(+-10%,X7R,0402)SAM'                        | 'CHIP0402'     | ''          | ''   | '20170427'
 '1200PF'   | '50V'   | '10%'     | 'C0402'     | 'X7R'     | 'CH2126K1B04'(!)   = ''              | ''                 | ''       | 'CH2126K1B04'     |'C0402'| '(C0402-0201)'                                                       | '1200PF'   | '50V'         | '10%'    | 'DISCRETE' | 'CAP CHIP 1200P 50V(+-10%,X7R,0402)WTC'                        | 'CHIP0402'     | ''          | ''   | '20170427'
 '1200PF'   | '50V'   | '10%'     | 'C0402'     | 'EMPTY'   | 'CH2126K1B04'(!)   = ''              | ''                 | ''       | 'CH2126K1B04'     |'C0402'| '(C0402-0201)'                                                       | 'NA'       | '50V'         | '10%'    | 'IO'       | 'CAP CHIP 1200P 50V(+-10%,X7R,0402)WTC'                        | 'CHIP0402'     | ''          | ''   | '20170427'
 '10UF'     | '10V'   | '20%'     | 'C0402'     | 'X5R'     | 'CH6102M9B12'(!)   = ''              | ''                 | ''       | 'CH6102M9B12'     |'C0402'| '(C0402-0201)'                                                       | '10UF'     | '10V'         | '20%'    | 'DISCRETE' | 'CAP CHIP 10U 10V(+-20%, X5R,0402)SAM'                         | 'CHIP0402'     | ''          | ''   | '20170427'
 '10UF'     | '10V'   | '20%'     | 'C0402'     | 'EMPTY'   | 'CH6102M9B12'(!)   = ''              | ''                 | ''       | 'CH6102M9B12'     |'C0402'| '(C0402-0201)'                                                       | 'NA'       | '10V'         | '20%'    | 'IO'       | 'CAP CHIP 10U 10V(+-20%, X5R,0402)SAM'                         | 'CHIP0402'     | ''          | ''   | '20170427'
 '0.01UF'   | '16V'   | '10%'     | 'C0402'     | 'X7R'     | 'CH3103K1B26'(!)   = ''              | ''                 | ''       | 'CH3103K1B26'     |'C0402'| '(C0402-0201)'                                                       | '0.01UF'   | '16V'         | '10%'    | 'DISCRETE' | 'CAP CHIP 0.01U 16V(10%,X7R,0402)YGO'                          | 'CHIP0402'     | ''          | ''   | '20170427'
 '0.01UF'   | '16V'   | '10%'     | 'C0402'     | 'EMPTY'   | 'CH3103K1B26'(!)   = ''              | ''                 | ''       | 'CH3103K1B26'     |'C0402'| '(C0402-0201)'                                                       | 'NA'       | '16V'         | '10%'    | 'IO'       | 'CAP CHIP 0.01U 16V(10%,X7R,0402)YGO'                          | 'CHIP0402'     | ''          | ''   | '20170427'
 '0.01UF'   | '16V'   | '10%'     | 'C0402'     | 'X7R'     | 'CH3103K1B25'(!)   = ''              | ''                 | ''       | 'CH3103K1B25'     |'C0402'| '(C0402-0201)'                                                       | '0.01UF'   | '16V'         | '10%'    | 'DISCRETE' | 'CAP CHIP 0.01U 16V(10%,X7R,0402)WTC'                          | 'CHIP0402'     | ''          | ''   | '20170427'
 '0.01UF'   | '16V'   | '10%'     | 'C0402'     | 'EMPTY'   | 'CH3103K1B25'(!)   = ''              | ''                 | ''       | 'CH3103K1B25'     |'C0402'| '(C0402-0201)'                                                       | 'NA'       | '16V'         | '10%'    | 'IO'       | 'CAP CHIP 0.01U 16V(10%,X7R,0402)WTC'                          | 'CHIP0402'     | ''          | ''   | '20170427'
 '1UF'      | '16V'   | '10%'     | 'C0402'     | 'X5R'     | 'CH5103K9B06'(!)   = ''              | ''                 | ''       | 'CH5103K9B06'     |'C0402'| '(C0402-0201)'                                                       | '1UF'      | '16V'         | '10%'    | 'DISCRETE' | 'CAP CHIP 1U 16V(10%,X5R,0402)SAM'                             | 'CHIP0402'     | ''          | ''   | '20170427'
 '1UF'      | '16V'   | '10%'     | 'C0402'     | 'EMPTY'   | 'CH5103K9B06'(!)   = ''              | ''                 | ''       | 'CH5103K9B06'     |'C0402'| '(C0402-0201)'                                                       | 'NA'       | '16V'         | '10%'    | 'IO'       | 'CAP CHIP 1U 16V(10%,X5R,0402)SAM'                             | 'CHIP0402'     | ''          | ''   | '20170427'
 '1UF'      | '16V'   | '10%'     | 'C0402'     | 'X5R'     | 'CH5103K9B09'(!)   = ''              | ''                 | ''       | 'CH5103K9B09'     |'C0402'| '(C0402-0201)'                                                       | '1UF'      | '16V'         | '10%'    | 'DISCRETE' | 'CAP CHIP 1UF 16V(10%,X5R,0402)WTC'                            | 'CHIP0402'     | ''          | ''   | '20170427'
 '1UF'      | '16V'   | '10%'     | 'C0402'     | 'EMPTY'   | 'CH5103K9B09'(!)   = ''              | ''                 | ''       | 'CH5103K9B09'     |'C0402'| '(C0402-0201)'                                                       | 'NA'       | '16V'         | '10%'    | 'IO'       | 'CAP CHIP 1UF 16V(10%,X5R,0402)WTC'                            | 'CHIP0402'     | ''          | ''   | '20170427'
 '10UF'     | '25V'   | '10%'     | 'C0805'     | 'X6S'     | 'CH6104KEA06'(!)   = 'End of Design' | 'Comp-Approve'     | ''       | 'CH6104KEA06'     |'C0805_H57'| '(SMC0805AW)'                                                        | '10UF'     | '25V'         | '10%'    | 'DISCRETE' | 'CAP CHIP 10U 25V(+-10%,X6S,0805)WTC'                          | 'CHIP0805'     | ''          | ''   | '20170502'
 '10UF'     | '25V'   | '10%'     | 'C0805'     | 'EMPTY'   | 'CH6104KEA06'(!)   = 'End of Design' | 'Comp-Approve'     | ''       | 'CH6104KEA06'     |'C0805_H57'| '(SMC0805AW)'                                                        | 'NA'       | '25V'         | '10%'    | 'IO'       | 'CAP CHIP 10U 25V(+-10%,X6S,0805)WTC'                          | 'CHIP0805'     | ''          | ''   | '20170502'
 '22UF'     | '6.3V'  | '20%'     | 'C0805'     | 'X5R'     | 'CH6221M9A34'(!)   = ''              | ''                 | ''       | 'CH6221M9A34'     |'C0805_H57'| '(SMC0805AW)'                                                        | '22UF'     | '6.3V'        | '20%'    | 'DISCRETE' | 'CAP CHIP 22U 6.3V(+-20%,X5R,0805)WTC'                         | 'CHIP0805'     | ''          | ''   | '20170502'
 '22UF'     | '6.3V'  | '20%'     | 'C0805'     | 'EMPTY'   | 'CH6221M9A34'(!)   = ''              | ''                 | ''       | 'CH6221M9A34'     |'C0805_H57'| '(SMC0805AW)'                                                        | 'NA'       | '6.3V'        | '20%'    | 'IO'       | 'CAP CHIP 22U 6.3V(+-20%,X5R,0805)WTC'                         | 'CHIP0805'     | ''          | ''   | '20170502'
 '22UF'     | '6.3V'  | '20%'     | 'C0805'     | 'X6S'     | 'CH6221MEA06'(!)   = ''              | ''                 | ''       | 'CH6221MEA06'     |'C0805_H57'| '(SMC0805AW)'                                                        | '22UF'     | '6.3V'        | '20%'    | 'DISCRETE' | 'CAP CHIP 22U 6.3V(+-20%,X6S,0805)SAM'                         | 'CHIP0805'     | ''          | ''   | '20170502'
 '22UF'     | '6.3V'  | '20%'     | 'C0805'     | 'EMPTY'   | 'CH6221MEA06'(!)   = ''              | ''                 | ''       | 'CH6221MEA06'     |'C0805_H57'| '(SMC0805AW)'                                                        | 'NA'       | '6.3V'        | '20%'    | 'IO'       | 'CAP CHIP 22U 6.3V(+-20%,X6S,0805)SAM'                         | 'CHIP0805'     | ''          | ''   | '20170502'
 '10UF'     | '25V'   | '10%'     | 'C1206'     | 'X7R'     | 'CH6104K1212'(!)   = 'End of Design' | 'Comp-Approve'     | ''       | 'CH6104K1212'     |'C1206_H76'| '(SMC1206AW)'                                                        | '10UF'     | '25V'         | '10%'    | 'DISCRETE' | 'CAP CHIP 10U 25V(+-10%,X7R,1206)WTC'                          | 'CHIP1206'     | ''          | ''   | '20170502'
 '10UF'     | '25V'   | '10%'     | 'C1206'     | 'EMPTY'   | 'CH6104K1212'(!)   = 'End of Design' | 'Comp-Approve'     | ''       | 'CH6104K1212'     |'C1206_H76'| '(SMC1206AW)'                                                        | 'NA'       | '25V'         | '10%'    | 'IO'       | 'CAP CHIP 10U 25V(+-10%,X7R,1206)WTC'                          | 'CHIP1206'     | ''          | ''   | '20170502'
 '22UF'     | '25V'   | '10%'     | 'C1206'     | 'X6S'     | 'CH6224KE202'(!)   = 'End of Design' | 'Comp-Approve'     | ''       | 'CH6224KE202'     |'C1206_H76'| '(SMC1206AW)'                                                        | '22UF'     | '25V'         | '10%'    | 'DISCRETE' | 'CAP CHIP 22U 25V(+-10%,X6S,1206)SAM'                          | 'CHIP1206'     | ''          | ''   | '20170502'
 '22UF'     | '25V'   | '10%'     | 'C1206'     | 'EMPTY'   | 'CH6224KE202'(!)   = 'End of Design' | 'Comp-Approve'     | ''       | 'CH6224KE202'     |'C1206_H76'| '(SMC1206AW)'                                                        | 'NA'       | '25V'         | '10%'    | 'IO'       | 'CAP CHIP 22U 25V(+-10%,X6S,1206)SAM'                          | 'CHIP1206'     | ''          | ''   | '20170502'
 '22UF'     | '10V'   | '20%'     | 'C0805'     | 'X6S'     | 'CH6222MEA02'(!)   = ''              | ''                 | ''       | 'CH6222MEA02'     |'C0805_H57'| '(SMC0805AW)'                                                        | '22UF'     | '10V'         | '20%'    | 'DISCRETE' | 'CAP CHIP 22U 10V(+-20%,X6S,0805)TAY'                          | 'CHIP0805'     | ''          | ''   | '20170503'
 '22UF'     | '10V'   | '20%'     | 'C0805'     | 'EMPTY'   | 'CH6222MEA02'(!)   = ''              | ''                 | ''       | 'CH6222MEA02'     |'C0805_H57'| '(SMC0805AW)'                                                        | 'NA'       | '10V'         | '20%'    | 'IO'       | 'CAP CHIP 22U 10V(+-20%,X6S,0805)TAY'                          | 'CHIP0805'     | ''          | ''   | '20170503'
 '10UF'     | '6.3V'  | '20%'     | 'C0805'     | 'X6S'     | 'CH6101MEA01'(!)   = ''              | 'End of Life'      | ''       | 'CH6101MEA01'     |'C0805_H57_EOL'| '(SMC0805AW)'                                                        | '10UF'     | '6.3V'        | '20%'    | 'DISCRETE' | 'CAP CHIP 10UF 6.3V(+-20%,X6S,0805)TAY'                        | 'CHIP0805'     | ''          | ''   | '20170503'
 '10UF'     | '6.3V'  | '20%'     | 'C0805'     | 'EMPTY'   | 'CH6101MEA01'(!)   = ''              | 'End of Life'      | ''       | 'CH6101MEA01'     |'C0805_H57_EOL'| '(SMC0805AW)'                                                        | 'NA'       | '6.3V'        | '20%'    | 'IO'       | 'CAP CHIP 10UF 6.3V(+-20%,X6S,0805)TAY'                        | 'CHIP0805'     | ''          | ''   | '20170503'
 '22UF'     | '6.3V'  | '20%'     | 'C0805'     | 'X5R'     | 'CH6221M9A27'(!)   = ''              | ''                 | ''       | 'CH6221M9A27'     |'C0805_H57'| '(SMC0805AW)'                                                        | '22UF'     | '6.3V'        | '20%'    | 'DISCRETE' | 'CAP CHIP 22U 6.3V(+-20%,X5R,0805)TAY'                         | 'CHIP0805'     | ''          | ''   | '20170503'
 '22UF'     | '6.3V'  | '20%'     | 'C0805'     | 'EMPTY'   | 'CH6221M9A27'(!)   = ''              | ''                 | ''       | 'CH6221M9A27'     |'C0805_H57'| '(SMC0805AW)'                                                        | 'NA'       | '6.3V'        | '20%'    | 'IO'       | 'CAP CHIP 22U 6.3V(+-20%,X5R,0805)TAY'                         | 'CHIP0805'     | ''          | ''   | '20170503'
 '10UF'     | '6.3V'  | '10%'     | 'C0805'     | 'X6S'     | 'CH6101KEA02'(!)   = 'End of Design' | 'Comp-Approve'     | ''       | 'CH6101KEA02'     |'C0805_H57'| '(SMC0805AW)'                                                        | '10UF'     | '6.3V'        | '10%'    | 'DISCRETE' | 'CAP CHIP 10UF,6.3V (+-10%,X6S,0805)MUR'                       | 'CHIP0805'     | ''          | ''   | '20170503'
 '10UF'     | '6.3V'  | '10%'     | 'C0805'     | 'EMPTY'   | 'CH6101KEA02'(!)   = 'End of Design' | 'Comp-Approve'     | ''       | 'CH6101KEA02'     |'C0805_H57'| '(SMC0805AW)'                                                        | 'NA'       | '6.3V'        | '10%'    | 'IO'       | 'CAP CHIP 10UF,6.3V (+-10%,X6S,0805)MUR'                       | 'CHIP0805'     | ''          | ''   | '20170503'
 '10UF'     | '6.3V'  | '20%'     | 'C0805'     | 'X6S'     | 'CH6101MEA02'(!)   = ''              | ''                 | ''       | 'CH6101MEA02'     |'C0805_H57'| '(SMC0805AW)'                                                        | '10UF'     | '6.3V'        | '20%'    | 'DISCRETE' | 'CAP CHIP 10UF 6.3V(+-20%,X6S,0805)MUR'                        | 'CHIP0805'     | ''          | ''   | '20170503'
 '10UF'     | '6.3V'  | '20%'     | 'C0805'     | 'EMPTY'   | 'CH6101MEA02'(!)   = ''              | ''                 | ''       | 'CH6101MEA02'     |'C0805_H57'| '(SMC0805AW)'                                                        | 'NA'       | '6.3V'        | '20%'    | 'IO'       | 'CAP CHIP 10UF 6.3V(+-20%,X6S,0805)MUR'                        | 'CHIP0805'     | ''          | ''   | '20170503'
 '22UF'     | '25V'   | '10%'     | 'C1206'     | 'X6S'     | 'CH6224KE201'(!)   = 'End of Design' | 'Comp-Approve'     | ''       | 'CH6224KE201'     |'C1206_H76'| '(SMC1206AW)'                                                        | '22UF'     | '25V'         | '10%'    | 'DISCRETE' | 'CAP CHIP 22U 25V(+-10%,X6S,1206)MUR'                          | 'CHIP1206'     | ''          | ''   | '20170503'
 '22UF'     | '25V'   | '10%'     | 'C1206'     | 'EMPTY'   | 'CH6224KE201'(!)   = 'End of Design' | 'Comp-Approve'     | ''       | 'CH6224KE201'     |'C1206_H76'| '(SMC1206AW)'                                                        | 'NA'       | '25V'         | '10%'    | 'IO'       | 'CAP CHIP 22U 25V(+-10%,X6S,1206)MUR'                          | 'CHIP1206'     | ''          | ''   | '20170503'
 '1UF'      | '25V'   | '10%'     | 'C0402'     | 'X6S'     | 'CH5104KEB03'(!)   = ''              | ''                 | ''       | 'CH5104KEB03'     |'C0402'| '(C0402_OCTAGONXA,C0402-0201,C0402_OCTAGONXA_BOUND22)'               | '1UF'      | '25V'         | '10%'    | 'DISCRETE' | 'CAP CHIP 1UF 25V(+-10%,X6S,0402)MUR'                          | 'CHIP0402'     | ''          | ''   | '20170509'
 '1UF'      | '25V'   | '10%'     | 'C0402'     | 'EMPTY'   | 'CH5104KEB03'(!)   = ''              | ''                 | ''       | 'CH5104KEB03'     |'C0402'| '(C0402_OCTAGONXA,C0402-0201,C0402_OCTAGONXA_BOUND22)'               | 'NA'       | '25V'         | '10%'    | 'IO'       | 'CAP CHIP 1UF 25V(+-10%,X6S,0402)MUR'                          | 'CHIP0402'     | ''          | ''   | '20170509'
 '16PF'     | '25V'   | '5%'      | 'C0402'     | 'NP0'     | 'CH0164J0B00'(!)   = ''              | ''                 | ''       | 'CH0164J0B00'     |'C0402'| '(C0402-0201)'                                                       | '16PF'     | '25V'         | '5%'     | 'DISCRETE' | 'CAP CHIP 16P 25V(+-5%,NP0,0402)'                              | 'CHIP0402'     | ''          | ''   | '20170509'
 '16PF'     | '25V'   | '5%'      | 'C0402'     | 'EMPTY'   | 'CH0164J0B00'(!)   = ''              | ''                 | ''       | 'CH0164J0B00'     |'C0402'| '(C0402-0201)'                                                       | 'NA'       | '25V'         | '5%'     | 'IO'       | 'CAP CHIP 16P 25V(+-5%,NP0,0402)'                              | 'CHIP0402'     | ''          | ''   | '20170509'
 '0.1UF'    | '16V'   | '10%'     | 'C0402'     | 'X7R'     | 'CH4103K1B13'(!)   = 'End of Design' | 'Comp-Approve'     | ''       | 'CH4103K1B13'     |'C0402'| '(C0402_OCTAGONXA,C0402_SMDC25_SM30,C0402-0201)'                     | '0.1UF'    | '16V'         | '10%'    | 'DISCRETE' | 'CAP CHIP 0.1U 16V(10%,X7R,0402)MUR'                           | 'CHIP0402'     | ''          | ''   | '20170524'
 '0.1UF'    | '16V'   | '10%'     | 'C0402'     | 'EMPTY'   | 'CH4103K1B13'(!)   = 'End of Design' | 'Comp-Approve'     | ''       | 'CH4103K1B13'     |'C0402'| '(C0402_OCTAGONXA,C0402_SMDC25_SM30,C0402-0201)'                     | 'NA'       | '16V'         | '10%'    | 'IO'       | 'CAP CHIP 0.1U 16V(10%,X7R,0402)MUR'                           | 'CHIP0402'     | ''          | ''   | '20170524'
 '22UF'     | '4V'    | '20%'     | 'C0402'     | 'X6S'     | 'CH622KMEB00'(!)   = 'End of Design' | 'Comp-Approve'     | ''       | 'CH622KMEB00'     |'C0402'| '(C0402_SMDC25_SM30,C0402-0201)'                                     | '22UF'     | '4V'          | '20%'    | 'DISCRETE' | 'CAP CHIP 22UF 4V(+-20%,X6S,0402)TAY'                          | 'CHIP0402'     | ''          | ''   | '20170524'
 '22UF'     | '4V'    | '20%'     | 'C0402'     | 'EMPTY'   | 'CH622KMEB00'(!)   = 'End of Design' | 'Comp-Approve'     | ''       | 'CH622KMEB00'     |'C0402'| '(C0402_SMDC25_SM30,C0402-0201)'                                     | 'NA'       | '4V'          | '20%'    | 'IO'       | 'CAP CHIP 22UF 4V(+-20%,X6S,0402)TAY'                          | 'CHIP0402'     | ''          | ''   | '20170524'
 '4.7PF'    | '50V'   | '0.25PF'  | 'C0402'     | 'C0G'     | 'CH-476C0B05'(!)   = 'End of Design' | 'Comp-Approve'     | ''       | 'CH-476C0B05'     |'C0402'| '(C0402-0201)'                                                       | '4.7PF'    | '50V'         | '0.25PF' | 'DISCRETE' | 'CAP CHIP 4.7P 50V(+-0.25P,C0G,0402)SAM'                       | 'CHIP0402'     | ''          | ''   | '20170526'
 '4.7PF'    | '50V'   | '0.25PF'  | 'C0402'     | 'EMPTY'   | 'CH-476C0B05'(!)   = 'End of Design' | 'Comp-Approve'     | ''       | 'CH-476C0B05'     |'C0402'| '(C0402-0201)'                                                       | 'NA'       | '50V'         | '0.25PF' | 'IO'       | 'CAP CHIP 4.7P 50V(+-0.25P,C0G,0402)SAM'                       | 'CHIP0402'     | ''          | ''   | '20170526'
 '4.7PF'    | '50V'   | '0.25PF'  | 'C0402'     | 'C0G'     | 'CH-476C0B04'(!)   = ''              | ''                 | ''       | 'CH-476C0B04'     |'C0402'| '(C0402-0201)'                                                       | '4.7PF'    | '50V'         | '0.25PF' | 'DISCRETE' | 'CAP CHIP 4.7P 50V(+-0.25P,C0G,0402)WTC'                       | 'CHIP0402'     | ''          | ''   | '20170526'
 '4.7PF'    | '50V'   | '0.25PF'  | 'C0402'     | 'EMPTY'   | 'CH-476C0B04'(!)   = ''              | ''                 | ''       | 'CH-476C0B04'     |'C0402'| '(C0402-0201)'                                                       | 'NA'       | '50V'         | '0.25PF' | 'IO'       | 'CAP CHIP 4.7P 50V(+-0.25P,C0G,0402)WTC'                       | 'CHIP0402'     | ''          | ''   | '20170526'
 '4.7PF'    | '50V'   | '0.25PF'  | 'C0402'     | 'C0G'     | 'CH-476C0B03'(!)   = ''              | ''                 | ''       | 'CH-476C0B03'     |'C0402'| '(C0402-0201)'                                                       | '4.7PF'    | '50V'         | '0.25PF' | 'DISCRETE' | 'CAP CHIP 4.7P 50V(+-0.25P,C0G,0402)MUR'                       | 'CHIP0402'     | ''          | ''   | '20170526'
 '4.7PF'    | '50V'   | '0.25PF'  | 'C0402'     | 'EMPTY'   | 'CH-476C0B03'(!)   = ''              | ''                 | ''       | 'CH-476C0B03'     |'C0402'| '(C0402-0201)'                                                       | 'NA'       | '50V'         | '0.25PF' | 'IO'       | 'CAP CHIP 4.7P 50V(+-0.25P,C0G,0402)MUR'                       | 'CHIP0402'     | ''          | ''   | '20170526'
 '22UF'     | '6.3V'  | '20%'     | 'C0402'     | 'X5R'     | 'CH6221M9B05'(!)   = ''              | ''                 | ''       | 'CH6221M9B05'     |'C0402'| '(C0402-0201)'                                                       | '22UF'     | '6.3V'        | '20%'    | 'DISCRETE' | 'CAP CHIP 22UF 6.3V(+-20%,X5R,0402)MUR'                        | 'CHIP0402'     | ''          | ''   | '20170626'
 '22UF'     | '6.3V'  | '20%'     | 'C0402'     | 'EMPTY'   | 'CH6221M9B05'(!)   = ''              | ''                 | ''       | 'CH6221M9B05'     |'C0402'| '(C0402-0201)'                                                       | 'NA'       | '6.3V'        | '20%'    | 'IO'       | 'CAP CHIP 22UF 6.3V(+-20%,X5R,0402)MUR'                        | 'CHIP0402'     | ''          | ''   | '20170626'
 '1UF'      | '10V'   | '10%'     | 'C0402'     | 'X6S'     | 'CH5102KEB02'(!)   = ''              | ''                 | ''       | 'CH5102KEB02'     |'C0402'| '(C0402-0201)'                                                       | '1UF'      | '10V'         | '10%'    | 'DISCRETE' | 'CAP CHIP 1UF 10V(+-10%,X6S,0402)MUR'                          | 'CHIP0402'     | ''          | ''   | '20170626'
 '1UF'      | '10V'   | '10%'     | 'C0402'     | 'EMPTY'   | 'CH5102KEB02'(!)   = ''              | ''                 | ''       | 'CH5102KEB02'     |'C0402'| '(C0402-0201)'                                                       | 'NA'       | '10V'         | '10%'    | 'IO'       | 'CAP CHIP 1UF 10V(+-10%,X6S,0402)MUR'                          | 'CHIP0402'     | ''          | ''   | '20170626'
 '6800PF'   | '100V'  | '10%'     | 'C0603'     | 'X7R'     | 'CH2688K1900'(!)   = ''              | ''                 | ''       | 'CH2688K1900'     |'C0603'| '(SMC0603AW)'                                                        | '6800PF'   | '100V'        | '10%'    | 'DISCRETE' | 'CAP CHIP 6800P 100V(+-10%,X7R,0603)MUR'                       | 'CHIP0603'     | ''          | ''   | '20170704'
 '6800PF'   | '100V'  | '10%'     | 'C0603'     | 'EMPTY'   | 'CH2688K1900'(!)   = ''              | ''                 | ''       | 'CH2688K1900'     |'C0603'| '(SMC0603AW)'                                                        | 'NA'       | '100V'        | '10%'    | 'IO'       | 'CAP CHIP 6800P 100V(+-10%,X7R,0603)MUR'                       | 'CHIP0603'     | ''          | ''   | '20170704'
 '0.47UF'   | '100V'  | '10%'     | 'C0805'     | 'X7R'     | 'CH4478K1A01'(!)   = 'End of Design' | 'Comp-Approve'     | ''       | 'CH4478K1A01'     |'C0805_H61'| '(SMC0805AW)'                                                        | '0.47UF'   | '100V'        | '10%'    | 'DISCRETE' | 'CAP CHIP 0.47U 100V(+-10%,X7R,0805)MUR'                       | 'CHIP0805'     | ''          | ''   | '20170705'
 '0.47UF'   | '100V'  | '10%'     | 'C0805'     | 'EMPTY'   | 'CH4478K1A01'(!)   = 'End of Design' | 'Comp-Approve'     | ''       | 'CH4478K1A01'     |'C0805_H61'| '(SMC0805AW)'                                                        | 'NA'       | '100V'        | '10%'    | 'IO'       | 'CAP CHIP 0.47U 100V(+-10%,X7R,0805)MUR'                       | 'CHIP0805'     | ''          | ''   | '20170705'
 '4.7UF'    | '100V'  | '10%'     | 'C1206'     | 'X7R'     | 'CH5478K1200'(!)   = ''              | ''                 | ''       | 'CH5478K1200'     |'C1206XB'| '(SMC1206AW)'                                                        | '4.7UF'    | '100V'        | '10%'    | 'DISCRETE' | 'CAP CHIP 4.7UF 100V(+-10%,X7R,1206)MUR'                       | 'CHIP1206'     | ''          | ''   | '20170705'
 '4.7UF'    | '100V'  | '10%'     | 'C1206'     | 'EMPTY'   | 'CH5478K1200'(!)   = ''              | ''                 | ''       | 'CH5478K1200'     |'C1206XB'| '(SMC1206AW)'                                                        | 'NA'       | '100V'        | '10%'    | 'IO'       | 'CAP CHIP 4.7UF 100V(+-10%,X7R,1206)MUR'                       | 'CHIP1206'     | ''          | ''   | '20170705'
 '68PF'     | '50V'   | '5%'      | 'C0402'     | 'COG'     | 'CH06806JB01'(!)   = ''              | ''                 | ''       | 'CH06806JB01'     |'C0402'| '(C0402-0201)'                                                       | '68PF'     | '50V'         | '5%'     | 'DISCRETE' | 'CAP CHIP 68P 50V(+-5%.COG.0402)'                              | 'CHIP0402'     | ''          | ''   | '20170725'
 '68PF'     | '50V'   | '5%'      | 'C0402'     | 'EMPTY'   | 'CH06806JB01'(!)   = ''              | ''                 | ''       | 'CH06806JB01'     |'C0402'| '(C0402-0201)'                                                       | 'NA'       | '50V'         | '5%'     | 'IO'       | 'CAP CHIP 68P 50V(+-5%.COG.0402)'                              | 'CHIP0402'     | ''          | ''   | '20170725'
 '22UF'     | '10V'   | '20%'     | 'C0603'     | 'X5R'     | 'CH6222M9901'(!)   = ''              | ''                 | ''       | 'CH6222M9901'     |'C0603'| '(SMC0603AW)'                                                        | '22UF'     | '10V'         | '20%'    | 'DISCRETE' | 'CAP CHIP 22UF 10V(+-20%,X5R,0603)'                            | 'CHIP0603'     | ''          | ''   | '20170801'
 '22UF'     | '10V'   | '20%'     | 'C0603'     | 'EMPTY'   | 'CH6222M9901'(!)   = ''              | ''                 | ''       | 'CH6222M9901'     |'C0603'| '(SMC0603AW)'                                                        | 'NA'       | '10V'         | '20%'    | 'IO'       | 'CAP CHIP 22UF 10V(+-20%,X5R,0603)'                            | 'CHIP0603'     | ''          | ''   | '20170801'
 '0.047UF'  | '100V'  | '10%'     | 'C0805'     | 'X7R'     | 'CH3478K1A01'(!)   = ''              | ''                 | ''       | 'CH3478K1A01'     |'C0805_H57'| '(SMC0805AW)'                                                        | '0.047UF'  | '100V'        | '10%'    | 'DISCRETE' | 'CAP CHIP 0.047UF 100V(+-10%,X7R,0805)MUR'                     | 'CHIP0805'     | ''          | ''   | '20170809'
 '0.047UF'  | '100V'  | '10%'     | 'C0805'     | 'EMPTY'   | 'CH3478K1A01'(!)   = ''              | ''                 | ''       | 'CH3478K1A01'     |'C0805_H57'| '(SMC0805AW)'                                                        | 'NA'       | '100V'        | '10%'    | 'IO'       | 'CAP CHIP 0.047UF 100V(+-10%,X7R,0805)MUR'                     | 'CHIP0805'     | ''          | ''   | '20170809'
 '0.0082UF' | '50V'   | '5%'      | 'C0603'     | 'C0G'     | 'CH2826J0900'(!)   = 'End of Design' | 'Comp-Approve'     | ''       | 'CH2826J0900'     |'C0603'| '(SMC0603AW)'                                                        | '0.0082UF' | '50V'         | '5%'     | 'DISCRETE' | 'CAP CHIP 0.0082U 50V(+-5%,C0G,0603)'                          | 'CHIP0603'     | ''          | ''   | '20170817'
 '0.0082UF' | '50V'   | '5%'      | 'C0603'     | 'EMPTY'   | 'CH2826J0900'(!)   = 'End of Design' | 'Comp-Approve'     | ''       | 'CH2826J0900'     |'C0603'| '(SMC0603AW)'                                                        | 'NA'       | '50V'         | '5%'     | 'IO'       | 'CAP CHIP 0.0082U 50V(+-5%,C0G,0603)'                          | 'CHIP0603'     | ''          | ''   | '20170817'
 '0.47UF'   | '16V'   | '10%'     | 'C0402'     | 'X7R'     | 'CH4473K1B01'(!)   = 'End of Design' | 'Comp-Approve'     | ''       | 'CH4473K1B01'     |'C0402'| '(C0402-0201)'                                                       | '0.47UF'   | '16V'         | '10%'    | 'DISCRETE' | 'CAP CHIP 0.47U 16V(+-10%,X7R,0402)MUR'                        | 'CHIP0402'     | ''          | ''   | '20170817'
 '0.47UF'   | '16V'   | '10%'     | 'C0402'     | 'EMPTY'   | 'CH4473K1B01'(!)   = 'End of Design' | 'Comp-Approve'     | ''       | 'CH4473K1B01'     |'C0402'| '(C0402-0201)'                                                       | 'NA'       | '16V'         | '10%'    | 'IO'       | 'CAP CHIP 0.47U 16V(+-10%,X7R,0402)MUR'                        | 'CHIP0402'     | ''          | ''   | '20170817'
 '820PF'    | '100V'  | '5%'      | 'C0603'     | 'C0G'     | 'CH1828J0900'(!)   = 'End of Design' | 'Comp-Release Qty' | ''       | 'CH1828J0900'     |'C0603'| '(SMC0603AW)'                                                        | '820PF'    | '100V'        | '5%'     | 'DISCRETE' | 'CAP CHIP 820P 100V(+-5%,C0G,0603)'                            | 'CHIP0603'     | ''          | ''   | '20170821'
 '820PF'    | '100V'  | '5%'      | 'C0603'     | 'EMPTY'   | 'CH1828J0900'(!)   = 'End of Design' | 'Comp-Release Qty' | ''       | 'CH1828J0900'     |'C0603'| '(SMC0603AW)'                                                        | 'NA'       | '100V'        | '5%'     | 'IO'       | 'CAP CHIP 820P 100V(+-5%,C0G,0603)'                            | 'CHIP0603'     | ''          | ''   | '20170821'
 '33NF'     | '25V'   | '10%'     | 'C0402'     | 'X7R'     | 'CH3334K1B02'(!)   = ''              | ''                 | ''       | 'CH3334K1B02'     |'C0402'| '(C0402-0201)'                                                       | '33NF'     | '25V'         | '10%'    | 'DISCRETE' | 'CAP CHIP 33NF 25V(+-10%,X7R,0402)MUR'                         | 'CHIP0402'     | ''          | ''   | '20170904'
 '33NF'     | '25V'   | '10%'     | 'C0402'     | 'EMPTY'   | 'CH3334K1B02'(!)   = ''              | ''                 | ''       | 'CH3334K1B02'     |'C0402'| '(C0402-0201)'                                                       | 'NA'       | '25V'         | '10%'    | 'IO'       | 'CAP CHIP 33NF 25V(+-10%,X7R,0402)MUR'                         | 'CHIP0402'     | ''          | ''   | '20170904'
 '0.039UF'  | '50V'   | '10%'     | 'C0603'     | 'X7R'     | 'CH3396K1900'(!)   = ''              | ''                 | ''       | 'CH3396K1900'     |'C0603'| '(SMC0603AW)'                                                        | '0.039UF'  | '50V'         | '10%'    | 'DISCRETE' | 'CAP CHIP 0.039U 50V(+-10%,X7R,0603)'                          | 'CHIP0603'     | ''          | ''   | '20170918'
 '0.039UF'  | '50V'   | '10%'     | 'C0603'     | 'EMPTY'   | 'CH3396K1900'(!)   = ''              | ''                 | ''       | 'CH3396K1900'     |'C0603'| '(SMC0603AW)'                                                        | 'NA'       | '50V'         | '10%'    | 'IO'       | 'CAP CHIP 0.039U 50V(+-10%,X7R,0603)'                          | 'CHIP0603'     | ''          | ''   | '20170918'
 '100NF'    | '50V'   | '10%'     | 'C0402'     | 'X7R'     | 'CH4106K1B01'(!)   = ''              | ''                 | ''       | 'CH4106K1B01'     |'C0402'| '(C0402_OCTAGONXA,C0402-0201)'                                       | '100NF'    | '50V'         | '10%'    | 'DISCRETE' | 'CAP CHIP 100NF 50V(+-10%,X7R,0402)'                           | 'CHIP0402'     | ''          | ''   | '20171109'
 '100NF'    | '50V'   | '10%'     | 'C0402'     | 'EMPTY'   | 'CH4106K1B01'(!)   = ''              | ''                 | ''       | 'CH4106K1B01'     |'C0402'| '(C0402_OCTAGONXA,C0402-0201)'                                       | 'NA'       | '50V'         | '10%'    | 'IO'       | 'CAP CHIP 100NF 50V(+-10%,X7R,0402)'                           | 'CHIP0402'     | ''          | ''   | '20171109'
 '0.22UF'   | '25V'   | '10%'     | 'C0402'     | 'X7R'     | 'CH4224K1B01'(!)   = 'End of Design' | 'Comp-Release Qty' | ''       | 'CH4224K1B01'     |'C0402'| '(C0402_OCTAGONXA,C0402-0201)'                                       | '0.22UF'   | '25V'         | '10%'    | 'DISCRETE' | 'CAP CHIP 0.22U 25V(10%,X7R,0402)'                             | 'CHIP0402'     | ''          | ''   | '20171109'
 '0.22UF'   | '25V'   | '10%'     | 'C0402'     | 'EMPTY'   | 'CH4224K1B01'(!)   = 'End of Design' | 'Comp-Release Qty' | ''       | 'CH4224K1B01'     |'C0402'| '(C0402_OCTAGONXA,C0402-0201)'                                       | 'NA'       | '25V'         | '10%'    | 'IO'       | 'CAP CHIP 0.22U 25V(10%,X7R,0402)'                             | 'CHIP0402'     | ''          | ''   | '20171109'
 '1UF'      | '16V'   | '10%'     | '0603'      | 'X7R'     | 'TMP_QCH5103K1900'(!) = 'End of Design' | 'Comp-Approve'     | ''       | 'CH5103K1900'     |'C0603'| '(SMC0603AW)'                                                        | '1UF'      | '16V'         | '10%'    | 'DISCRETE' | 'CHIP0603'                                                     | 'CHIP0603'     | ''          | ''   | ''        
 '1UF'      | '16V'   | '10%'     | '0603'      | 'EMPTY'   | 'TMP_QCH5103K1900'(!) = 'End of Design' | 'Comp-Approve'     | ''       | 'CH5103K1900'     |'C0603'| '(SMC0603AW)'                                                        | 'NA'       | '16V'         | '10%'    | 'IO'       | 'CHIP0603'                                                     | 'CHIP0603'     | ''          | ''   | ''        
 '10UF'     | '6.3V'  | '20%'     | '0603'      | 'X5R'     | 'CH6101M9905'(!)   = 'End of Design' | 'Comp-Release Qty' | ''       | 'CH6101M9905'     |'C0603'| '(SMC0603AW)'                                                        | '10UF'     | '6.3V'        | '20%'    | 'DISCRETE' | 'CAP CHIP 10U 6.3V(+-20%,X5R,0603)'                            | 'CHIP0603'     | ''          | ''   | '2010701' 
 '10UF'     | '6.3V'  | '20%'     | '0603'      | 'EMPTY'   | 'CH6101M9905'(!)   = 'End of Design' | 'Comp-Release Qty' | ''       | 'CH6101M9905'     |'C0603'| '(SMC0603AW)'                                                        | 'NA'       | '6.3V'        | '20%'    | 'IO'       | 'CAP CHIP 10U 6.3V(+-20%,X5R,0603)'                            | 'CHIP0603'     | ''          | ''   | '2010701' 
 '10UF  '   | '16V '  | '10%'     | '0805'      | 'X5R'     | 'CH6103K9A00'(!)   = 'End of Design' | 'Comp-Approve'     | ''       | 'CH6103K9A00'     |'C0805_H61'| '(SMC0805AW)'                                                        | '10UF   '  | '16V'         | '10%'    | 'DISCRETE' | 'CAP CHIP 10U 16V(10%,X5R,0805)H1.25'                          | 'CHIP0805'     | ''          | ''   | '20100827'
 '10UF  '   | '16V '  | '10%'     | '0805'      | 'EMPTY'   | 'CH6103K9A00'(!)   = 'End of Design' | 'Comp-Approve'     | ''       | 'CH6103K9A00'     |'C0805_H61'| '(SMC0805AW)'                                                        | 'NA'       | '16V'         | '10%'    | 'IO'       | 'CAP CHIP 10U 16V(10%,X5R,0805)H1.25'                          | 'CHIP0805'     | ''          | ''   | '20100827'
 '22UF'     | '6.3V'  | '20%'     | '0805'      | 'X6S'     | 'CH6221MEA01'(!)   = 'End of Design' | 'Comp-Approve'     | ''       | 'CH6221MEA01'     |'C0805_H57'| '(SMC0805AW)'                                                        | '22UF'     | '6.3V'        | '20%'    | 'DISCRETE' | 'CAP CHIP 22U 6.3V(+-20%,X6S,0805)H1.25'                       | 'CHIP0805'     | ''          | ''   | '20101116'
 '22UF'     | '6.3V'  | '20%'     | '0805'      | 'EMPTY'   | 'CH6221MEA01'(!)   = 'End of Design' | 'Comp-Approve'     | ''       | 'CH6221MEA01'     |'C0805_H57'| '(SMC0805AW)'                                                        | 'NA'       | '6.3V'        | '20%'    | 'IO'       | 'CAP CHIP 22U 6.3V(+-20%,X6S,0805)H1.25'                       | 'CHIP0805'     | ''          | ''   | '20101116'
 '1UF'      | '6.3V'  | '20%'     | 'C0201'     | 'X6S'     | 'CH5101MEE01'(!)   = ''              | ''                 | ''       | 'CH5101MEE01'     |'C0201'| '(SMC0201AW)'                                                        | '1UF'      | '6.3V'        | '20%'    | 'DISCRETE' | 'CAP CHIP 1U 6.3V(+-20%,X6S,0201)'                             | 'CHIP0201'     | ''          | ''   | '20171115'
 '1UF'      | '6.3V'  | '20%'     | 'C0201'     | 'EMPTY'   | 'CH5101MEE01'(!)   = ''              | ''                 | ''       | 'CH5101MEE01'     |'C0201'| '(SMC0201AW)'                                                        | 'NA'       | '6.3V'        | '20%'    | 'IO'       | 'CAP CHIP 1U 6.3V(+-20%,X6S,0201)'                             | 'CHIP0201'     | ''          | ''   | '20171115'
 '0.22UF'   | '6.3V'  | '10%'     | 'C0201'     | 'X6S'     | 'CH4221KEE00'(!)   = ''              | ''                 | ''       | 'CH4221KEE00'     |'C0201'| '(SMC0201AW)'                                                        | '0.22UF'   | '6.3V'        | '10%'    | 'DISCRETE' | 'CAP CHIP 0.22UF 6.3V(+-10%,X6S,0201)'                         | 'CHIP0201'     | ''          | ''   | '20171116'
 '0.22UF'   | '6.3V'  | '10%'     | 'C0201'     | 'EMPTY'   | 'CH4221KEE00'(!)   = ''              | ''                 | ''       | 'CH4221KEE00'     |'C0201'| '(SMC0201AW)'                                                        | 'NA'       | '6.3V'        | '10%'    | 'IO'       | 'CAP CHIP 0.22UF 6.3V(+-10%,X6S,0201)'                         | 'CHIP0201'     | ''          | ''   | '20171116'
 '10UF'     | '4V'    | '20%'     | 'C0805'     | 'X6S'     | 'CH610KMEA03'(!)   = 'End of Design' | 'Comp-Approve'     | ''       | 'CH610KMEA03'     |'C0805_H57'| '(SMC0805AW)'                                                        | '10UF'     | '4V'          | '20%'    | 'DISCRETE' | 'CAP CHIP 10U,4V(+-20%,X6S,0805)MUR'                           | 'CHIP0805'     | ''          | ''   | '20171120'
 '10UF'     | '4V'    | '20%'     | 'C0805'     | 'EMPTY'   | 'CH610KMEA03'(!)   = 'End of Design' | 'Comp-Approve'     | ''       | 'CH610KMEA03'     |'C0805_H57'| '(SMC0805AW)'                                                        | 'NA'       | '4V'          | '20%'    | 'IO'       | 'CAP CHIP 10U,4V(+-20%,X6S,0805)MUR'                           | 'CHIP0805'     | ''          | ''   | '20171120'
 '0.01UF'   | '10V'   | '10%'     | 'C0201'     | 'X7R'     | 'CH3102K1E01'(!)   = ''              | ''                 | ''       | 'CH3102K1E01'     |'C0201'| '(SMC0201AW)'                                                        | '0.01UF'   | '10V'         | '10%'    | 'DISCRETE' | 'CAP CHIP 0.01UF 10V(10%,X7R,0201)'                            | 'CHIP0201'     | ''          | ''   | '20171121'
 '0.01UF'   | '10V'   | '10%'     | 'C0201'     | 'EMPTY'   | 'CH3102K1E01'(!)   = ''              | ''                 | ''       | 'CH3102K1E01'     |'C0201'| '(SMC0201AW)'                                                        | 'NA'       | '10V'         | '10%'    | 'IO'       | 'CAP CHIP 0.01UF 10V(10%,X7R,0201)'                            | 'CHIP0201'     | ''          | ''   | '20171121'
 '4.7UF'    | '25V'   | '10%'     | 'C0603'     | 'X6S'     | 'CH5474KE905'(!)   = 'End of Design' | 'Comp-Approve'     | ''       | 'CH5474KE905'     |'C0603'| '(SMC0603AW)'                                                        | '4.7UF'    | '25V'         | '10%'    | 'DISCRETE' | 'CAP CHIP 4.7U 25V(+-10%,X6S,0603)WTC'                         | 'CHIP0603'     | ''          | ''   | '20171121'
 '4.7UF'    | '25V'   | '10%'     | 'C0603'     | 'EMPTY'   | 'CH5474KE905'(!)   = 'End of Design' | 'Comp-Approve'     | ''       | 'CH5474KE905'     |'C0603'| '(SMC0603AW)'                                                        | 'NA'       | '25V'         | '10%'    | 'IO'       | 'CAP CHIP 4.7U 25V(+-10%,X6S,0603)WTC'                         | 'CHIP0603'     | ''          | ''   | '20171121'
 '1000PF'   | '16V'   | '5%'      | 'C0201'     | 'X7R'     | 'CH2103J1E01'(!)   = ''              | ''                 | ''       | 'CH2103J1E01'     |'C0201'| '(SMC0201AW)'                                                        | '1000PF'   | '16V'         | '5%'     | 'DISCRETE' | 'CAP CHIP 1000P 16V(+-5%,X7R,0201)'                            | 'CHIP0201'     | ''          | ''   | '20171121'
 '1000PF'   | '16V'   | '5%'      | 'C0201'     | 'EMPTY'   | 'CH2103J1E01'(!)   = ''              | ''                 | ''       | 'CH2103J1E01'     |'C0201'| '(SMC0201AW)'                                                        | 'NA'       | '16V'         | '5%'     | 'IO'       | 'CAP CHIP 1000P 16V(+-5%,X7R,0201)'                            | 'CHIP0201'     | ''          | ''   | '20171121'
 '22UF'     | '16V'   | '20%'     | 'C0805'     | 'X6S'     | 'CH6223MEA01'(!)   = ''              | ''                 | ''       | 'CH6223MEA01'     |'C0805_H57'| '(SMC0805AW)'                                                        | '22UF'     | '16V'         | '20%'    | 'DISCRETE' | 'CAP CHIP 22UF 16V(+-20%,X6S,0805)MUR'                         | 'CHIP0805'     | ''          | ''   | '20171127'
 '22UF'     | '16V'   | '20%'     | 'C0805'     | 'EMPTY'   | 'CH6223MEA01'(!)   = ''              | ''                 | ''       | 'CH6223MEA01'     |'C0805_H57'| '(SMC0805AW)'                                                        | 'NA'       | '16V'         | '20%'    | 'IO'       | 'CAP CHIP 22UF 16V(+-20%,X6S,0805)MUR'                         | 'CHIP0805'     | ''          | ''   | '20171127'
 '47UF'     | '6.3V'  | '20%'     | 'C0805'     | 'X5R'     | 'CH6471M9A08'(!)   = ''              | ''                 | ''       | 'CH6471M9A08'     |'C0805_H57'| '(SMC0805AW)'                                                        | '47UF'     | '6.3V'        | '20%'    | 'DISCRETE' | 'CAP CHIP 47U 6.3V(+-20%,X5R,0805)MUR'                         | 'CHIP0805'     | ''          | ''   | '20171206'
 '47UF'     | '6.3V'  | '20%'     | 'C0805'     | 'EMPTY'   | 'CH6471M9A08'(!)   = ''              | ''                 | ''       | 'CH6471M9A08'     |'C0805_H57'| '(SMC0805AW)'                                                        | 'NA'       | '6.3V'        | '20%'    | 'IO'       | 'CAP CHIP 47U 6.3V(+-20%,X5R,0805)MUR'                         | 'CHIP0805'     | ''          | ''   | '20171206'
 '0.1UF'    | '25V'   | '10%'     | 'C0402'     | 'X7R'     | 'CH4104K1B11'(!)   = ''              | ''                 | ''       | 'CH4104K1B11'     |'C0402'| '(C0402-0201)'                                                       | '0.1UF'    | '25V'         | '10%'    | 'DISCRETE' | 'CAP CHIP 0.1U 25V(+-10%,X7R,0402)TAY'                         | 'CHIP0402'     | ''          | ''   | '20171212'
 '0.1UF'    | '25V'   | '10%'     | 'C0402'     | 'EMPTY'   | 'CH4104K1B11'(!)   = ''              | ''                 | ''       | 'CH4104K1B11'     |'C0402'| '(C0402-0201)'                                                       | 'NA'       | '25V'         | '10%'    | 'IO'       | 'CAP CHIP 0.1U 25V(+-10%,X7R,0402)TAY'                         | 'CHIP0402'     | ''          | ''   | '20171212'
 '10UF'     | '16V'   | '20%'     | 'C0603'     | 'X5R'     | 'CH6103M9900'(!)   = ''              | ''                 | ''       | 'CH6103M9900'     |'C0603_H40'| '(SMC0603AW)'                                                        | '10UF'     | '16V'         | '20%'    | 'DISCRETE' | 'CAP CHIP 10U 16V(+-20%,X5R,0603)'                             | 'CHIP0603'     | ''          | ''   | '20171221'
 '10UF'     | '16V'   | '20%'     | 'C0603'     | 'EMPTY'   | 'CH6103M9900'(!)   = ''              | ''                 | ''       | 'CH6103M9900'     |'C0603_H40'| '(SMC0603AW)'                                                        | 'NA'       | '16V'         | '20%'    | 'IO'       | 'CAP CHIP 10U 16V(+-20%,X5R,0603)'                             | 'CHIP0603'     | ''          | ''   | '20171221'
 '0.1UF'    | '25V'   | '10%'     | 'C0402'     | 'X6S'     | 'CH4104KEB00'(!)   = 'End of Design' | 'Comp-Approve'     | ''       | 'CH4104KEB00'     |'C0402'| '(C0402-0201)'                                                       | '0.1UF'    | '25V'         | '10%'    | 'DISCRETE' | 'CAP CHIP 0.1U 25V(+-10%,X6S,0402)'                            | 'CHIP0402'     | ''          | ''   | '20171221'
 '0.1UF'    | '25V'   | '10%'     | 'C0402'     | 'EMPTY'   | 'CH4104KEB00'(!)   = 'End of Design' | 'Comp-Approve'     | ''       | 'CH4104KEB00'     |'C0402'| '(C0402-0201)'                                                       | 'NA'       | '25V'         | '10%'    | 'IO'       | 'CAP CHIP 0.1U 25V(+-10%,X6S,0402)'                            | 'CHIP0402'     | ''          | ''   | '20171221'
 '1UF'      | '6.3V'  | '10%'     | 'C0201'     | 'X5R'     | 'CH5101K9E02'(!)   = 'End of Design' | 'Comp-Release Qty' | ''       | 'CH5101K9E02'     |'C0201'| '(SMC0201AW)'                                                        | '1UF'      | '6.3V'        | '10%'    | 'DISCRETE' | 'CAP CHIP 1U 6.3V(+-10%,X5R,0201)'                             | 'CHIP0201'     | ''          | ''   | '20171221'
 '1UF'      | '6.3V'  | '10%'     | 'C0201'     | 'EMPTY'   | 'CH5101K9E02'(!)   = 'End of Design' | 'Comp-Release Qty' | ''       | 'CH5101K9E02'     |'C0201'| '(SMC0201AW)'                                                        | 'NA'       | '6.3V'        | '10%'    | 'IO'       | 'CAP CHIP 1U 6.3V(+-10%,X5R,0201)'                             | 'CHIP0201'     | ''          | ''   | '20171221'
 '4.7UF'    | '10V'   | '10%'     | 'C0402'     | 'X5R'     | 'CH5472K9B02'(!)   = ''              | ''                 | ''       | 'CH5472K9B02'     |'C0402'| '(C0402-0201)'                                                       | '4.7UF'    | '10V'         | '10%'    | 'DISCRETE' | 'CAP CHIP 4.7U 10V(+-10%,X5R,0402)MUR'                         | 'CHIP0402'     | ''          | ''   | '20171222'
 '4.7UF'    | '10V'   | '10%'     | 'C0402'     | 'EMPTY'   | 'CH5472K9B02'(!)   = ''              | ''                 | ''       | 'CH5472K9B02'     |'C0402'| '(C0402-0201)'                                                       | 'NA'       | '10V'         | '10%'    | 'IO'       | 'CAP CHIP 4.7U 10V(+-10%,X5R,0402)MUR'                         | 'CHIP0402'     | ''          | ''   | '20171222'
 '270PF'    | '25V'   | '5%'      | 'C0402'     | 'NPO'     | 'CH12704JB07'(!)   = ''              | ''                 | ''       | 'CH12704JB07'     |'C0402'| '(C0402-0201)'                                                       | ' 270PF'   | '25V'         | '5%'     | 'DISCRETE' | 'CAP CHIP 270P 25V(+-5%,NPO,0402)'                             | 'CHIP0402'     | ''          | ''   | '20180126'
 '270PF'    | '25V'   | '5%'      | 'C0402'     | 'EMPTY'   | 'CH12704JB07'(!)   = ''              | ''                 | ''       | 'CH12704JB07'     |'C0402'| '(C0402-0201)'                                                       | 'NA'       | '25V'         | '5%'     | 'IO'       | 'CAP CHIP 270P 25V(+-5%,NPO,0402)'                             | 'CHIP0402'     | ''          | ''   | '20180126'
 '22UF'     | '4V'    | '20%'     | 'C0402'     | 'X6S'     | 'CH622KMEB01'(!)   = ''              | ''                 | ''       | 'CH622KMEB01'     |'C0402_H32'| '(C0402_OCTAGONXA,C0402-0201_H32)'                                   | '22UF'     | '4V'          | '20%'    | 'DISCRETE' | 'CAP CHIP 22UF 4V(+-20%,X6S,0402)MUR'                          | 'CHIP0402'     | ''          | ''   | '20180313'
 '22UF'     | '4V'    | '20%'     | 'C0402'     | 'EMPTY'   | 'CH622KMEB01'(!)   = ''              | ''                 | ''       | 'CH622KMEB01'     |'C0402_H32'| '(C0402_OCTAGONXA,C0402-0201_H32)'                                   | 'NA'       | '4V'          | '20%'    | 'IO'       | 'CAP CHIP 22UF 4V(+-20%,X6S,0402)MUR'                          | 'CHIP0402'     | ''          | ''   | '20180313'
 '1UF'      | '10V'   | '20%'     | 'C0201'     | 'X5R'     | 'CH5102M9E01'(!)   = ''              | ''                 | ''       | 'CH5102M9E01'     |'C0201'| '(SMC0201AW)'                                                        | '1UF'      | '10V'         | '20%'    | 'DISCRETE' | 'CAP CHIP 1UF 10V(+-20%,X5R,0201)'                             | 'CHIP0201'     | ''          | ''   | '20180320'
 '1UF'      | '10V'   | '20%'     | 'C0201'     | 'EMPTY'   | 'CH5102M9E01'(!)   = ''              | ''                 | ''       | 'CH5102M9E01'     |'C0201'| '(SMC0201AW)'                                                        | 'NA'       | '10V'         | '20%'    | 'IO'       | 'CAP CHIP 1UF 10V(+-20%,X5R,0201)'                             | 'CHIP0201'     | ''          | ''   | '20180320'
 '1UF'      | '25V'   | '10%'     | 'C0402'     | 'X7S'     | 'CH5104K6B00'(!)   = ''              | ''                 | ''       | 'CH5104K6B00'     |'C0402_H28'| '(C0402-0201_H28)'                                                   | '1UF'      | '25V'         | '10%'    | 'DISCRETE' | 'CAP CHIP 1U 25V (+-10%, X7S, 0402)MUR'                        | 'CHIP0402'     | ''          | ''   | '20180403'
 '1UF'      | '25V'   | '10%'     | 'C0402'     | 'EMPTY'   | 'CH5104K6B00'(!)   = ''              | ''                 | ''       | 'CH5104K6B00'     |'C0402_H28'| '(C0402-0201_H28)'                                                   | 'NA'       | '25V'         | '10%'    | 'IO'       | 'CAP CHIP 1U 25V (+-10%, X7S, 0402)MUR'                        | 'CHIP0402'     | ''          | ''   | '20180403'
 '0.1UF'    | '16V'   | '10%'     | 'C0201'     | 'X6S'     | 'CH4103KEE03'(!)   = ''              | ''                 | ''       | 'CH4103KEE03'     |'C0201'| '(C0201_HOME-PLATE_H22)'                                             | '0.1UF'    | '16V'         | '10%'    | 'DISCRETE' | 'CAP CHIP 0.1UF 16V(+-10%,X6S,0201)MUR'                        | 'CHIP0201'     | ''          | ''   | '20180403'
 '0.1UF'    | '16V'   | '10%'     | 'C0201'     | 'EMPTY'   | 'CH4103KEE03'(!)   = ''              | ''                 | ''       | 'CH4103KEE03'     |'C0201'| '(C0201_HOME-PLATE_H22)'                                             | 'NA'       | '16V'         | '10%'    | 'IO'       | 'CAP CHIP 0.1UF 16V(+-10%,X6S,0201)MUR'                        | 'CHIP0201'     | ''          | ''   | '20180403'
 '0.01U'    | '25V'   | '5%'      | 'C0402'     | 'X7R'     | 'CH3104J1B01'(!)   = ''              | ''                 | ''       | 'CH3104J1B01'     |'C0402'| '(C0402-0201)'                                                       | '0.01UF'   | '25V'         | '5%'     | 'DISCRETE' | 'CAP CHIP 0.01U 25V (+-5%,X7R,0402)MUR'                        | 'CHIP0402'     | ''          | ''   | '20180403'
 '0.01U'    | '25V'   | '5%'      | 'C0402'     | 'EMPTY'   | 'CH3104J1B01'(!)   = ''              | ''                 | ''       | 'CH3104J1B01'     |'C0402'| '(C0402-0201)'                                                       | 'NA'       | '25V'         | '5%'     | 'IO'       | 'CAP CHIP 0.01U 25V (+-5%,X7R,0402)MUR'                        | 'CHIP0402'     | ''          | ''   | '20180403'
 '22UF'     | '4V'    | '20%'     | 'C0402'     | 'X6S'     | 'CH622KMEB02'(!)   = 'End of Design' | 'Comp-Approve'     | ''       | 'CH622KMEB02'     |'C0402_H32'| '(C0402-0201_H32,C0402_OCTAGONXA)'                                   | '22UF'     | '4V'          | '20%'    | 'DISCRETE' | 'CAP CHIP 22UF 4V(+-20%,X6S,0402)'                             | 'CHIP0402'     | ''          | ''   | '20180409'
 '22UF'     | '4V'    | '20%'     | 'C0402'     | 'EMPTY'   | 'CH622KMEB02'(!)   = 'End of Design' | 'Comp-Approve'     | ''       | 'CH622KMEB02'     |'C0402_H32'| '(C0402-0201_H32,C0402_OCTAGONXA)'                                   | 'NA'       | '4V'          | '20%'    | 'IO'       | 'CAP CHIP 22UF 4V(+-20%,X6S,0402)'                             | 'CHIP0402'     | ''          | ''   | '20180409'
 '1000PF'   | '25V'   | '5%'      | 'C0402'     | 'NPO'     | 'CH2104J0B00'(!)   = ''              | ''                 | ''       | 'CH2104J0B00'     |'C0402'| '(C0402-0201)'                                                       | '1000PF'   | '25V'         | '5%'     | 'DISCRETE' | 'CAP CHIP 1000PF 25V (5%,NPO,0402)'                            | 'CHIP0402'     | ''          | ''   | '20180419'
 '1000PF'   | '25V'   | '5%'      | 'C0402'     | 'EMPTY'   | 'CH2104J0B00'(!)   = ''              | ''                 | ''       | 'CH2104J0B00'     |'C0402'| '(C0402-0201)'                                                       | 'NA'       | '25V'         | '5%'     | 'IO'       | 'CAP CHIP 1000PF 25V (5%,NPO,0402)'                            | 'CHIP0402'     | ''          | ''   | '20180419'
 '1.4UF'    | '50V'   | '5%'      | 'C1812'     | 'U2J'     | 'CH5146JF400'(!)   = 'End of Design' | 'P/N Release'      | ''       | 'CH5146JF400'     |'C1812_X3'| '(SMC1812AW)'                                                        | '1.4UF'    | '50V'         | '5%'     | 'DISCRETE' | 'CAP CHIP 1.4UF 50V(5%,U2J,1812)KEM'                           | 'CHIP1812'     | ''          | ''   | '20180423'
 '1.4UF'    | '50V'   | '5%'      | 'C1812'     | 'EMPTY'   | 'CH5146JF400'(!)   = 'End of Design' | 'P/N Release'      | ''       | 'CH5146JF400'     |'C1812_X3'| '(SMC1812AW)'                                                        | 'NA'       | '50V'         | '5%'     | 'IO'       | 'CAP CHIP 1.4UF 50V(5%,U2J,1812)KEM'                           | 'CHIP1812'     | ''          | ''   | '20180423'
 '10UF'     | '100V'  | '10%'     | 'C1210'     | 'X7S'     | 'CH6108K6300'(!)   = ''              | ''                 | ''       | 'CH6108K6300'     |'C1210_GRM32E'| '(SMC1210AW)'                                                        | '10UF'     | '100V'        | '10%'    | 'DISCRETE' | 'CAP CHIP 10UF 100V(+-10%,X7S,1210)MUR'                        | 'CHIP1210'     | ''          | ''   | '20180423'
 '10UF'     | '100V'  | '10%'     | 'C1210'     | 'EMPTY'   | 'CH6108K6300'(!)   = ''              | ''                 | ''       | 'CH6108K6300'     |'C1210_GRM32E'| '(SMC1210AW)'                                                        | 'NA'       | '100V'        | '10%'    | 'IO'       | 'CAP CHIP 10UF 100V(+-10%,X7S,1210)MUR'                        | 'CHIP1210'     | ''          | ''   | '20180423'
 '0.1UF'    | '6.3V'  | '10%'     | 'C0402'     | 'X7R'     | 'CH4101K1B01'(!)   = 'End of Design' | 'Comp-Approve'     | ''       | 'CH4101K1B01'     |'C0402'| '(C0402-0201)'                                                       | '0.1UF'    | '6.3V'        | '10%'    | 'DISCRETE' | 'CAP CHIP 0.1UF 6.3V(+-10%,X7R,0402)MUR'                       | 'CHIP0402'     | ''          | ''   | '20150729'
 '0.1UF'    | '6.3V'  | '10%'     | 'C0402'     | 'EMPTY'   | 'CH4101K1B01'(!)   = 'End of Design' | 'Comp-Approve'     | ''       | 'CH4101K1B01'     |'C0402'| '(C0402-0201)'                                                       | 'NA'       | '6.3V'        | '10%'    | 'IO'       | 'CAP CHIP 0.1UF 6.3V(+-10%,X7R,0402)MUR'                       | 'CHIP0402'     | ''          | ''   | '20150729'
 '0.22UF'   | '25V'   | '10%'     | 'C0402'     | 'X7R'     | 'CH4224K1B03'(!)   = 'End of Design' | 'Comp-Approve'     | ''       | 'CH4224K1B03'     |'C0402'| '(C0402-0201)'                                                       | '0.22UF'   | '25V'         | '10%'    | 'DISCRETE' | 'CAP CHIP 0.22UF 25V(10%,X7R,0402)MUR'                         | 'CHIP0402'     | ''          | ''   | '20180430'
 '0.22UF'   | '25V'   | '10%'     | 'C0402'     | 'EMPTY'   | 'CH4224K1B03'(!)   = 'End of Design' | 'Comp-Approve'     | ''       | 'CH4224K1B03'     |'C0402'| '(C0402-0201)'                                                       | 'NA'       | '25V'         | '10%'    | 'IO'       | 'CAP CHIP 0.22UF 25V(10%,X7R,0402)MUR'                         | 'CHIP0402'     | ''          | ''   | '20180430'
 '68PF'     | '50V'   | '5%'      | 'C0402'     | 'C0G'     | 'CH0686J0B11'(!)   = ''              | ''                 | ''       | 'CH0686J0B11'     |'C0402'| '(C0402-0201)'                                                       | '68PF'     | '50V'         | '5%'     | 'DISCRETE' | 'CAP CHIP 68P 50V(+-5%,C0G,0402)MUR'                           | 'CHIP0402'     | ''          | ''   | '20171026'
 '68PF'     | '50V'   | '5%'      | 'C0402'     | 'EMPTY'   | 'CH0686J0B11'(!)   = ''              | ''                 | ''       | 'CH0686J0B11'     |'C0402'| '(C0402-0201)'                                                       | 'NA'       | '50V'         | '5%'     | 'IO'       | 'CAP CHIP 68P 50V(+-5%,C0G,0402)MUR'                           | 'CHIP0402'     | ''          | ''   | '20171026'
 '1000PF'   | '100V'  | '5%'      | 'C1206'     | 'NPO'     | 'CH2108J0200'(!)   = ''              | ''                 | ''       | 'CH2108J0200'     |'C1206XC'| '(SMC1206AW)'                                                        | '1000PF'   | '100V'        | '5%'     | 'DISCRETE' | 'CAP CHIP 1000PF 100V(+-5%,NPO,1206)'                          | 'CHIP1206'     | ''          | ''   | '20180516'
 '1000PF'   | '100V'  | '5%'      | 'C1206'     | 'EMPTY'   | 'CH2108J0200'(!)   = ''              | ''                 | ''       | 'CH2108J0200'     |'C1206XC'| '(SMC1206AW)'                                                        | 'NA'       | '100V'        | '5%'     | 'IO'       | 'CAP CHIP 1000PF 100V(+-5%,NPO,1206)'                          | 'CHIP1206'     | ''          | ''   | '20180516'
 '1000PF'   | '100V'  | '10%'     | 'C0805'     | 'C0G'     | 'CH2108K0A00'(!)   = ''              | ''                 | ''       | 'CH2108K0A00'     |'C0805_H43'| '(SMC0805AW)'                                                        | '1000PF'   | '100V'        | '10%'    | 'DISCRETE' | 'CAP CHIP 1000PF 100V(+-10%,C0G,0805)KEM'                      | 'CHIP0805'     | ''          | ''   | '20180522'
 '1000PF'   | '100V'  | '10%'     | 'C0805'     | 'EMPTY'   | 'CH2108K0A00'(!)   = ''              | ''                 | ''       | 'CH2108K0A00'     |'C0805_H43'| '(SMC0805AW)'                                                        | 'NA'       | '100V'        | '10%'    | 'IO'       | 'CAP CHIP 1000PF 100V(+-10%,C0G,0805)KEM'                      | 'CHIP0805'     | ''          | ''   | '20180522'
 '1000PF'   | '100V'  | '10%'     | 'C0805'     | 'X7R'     | 'CH2108K1A00'(!)   = ''              | ''                 | ''       | 'CH2108K1A00'     |'C0805'| '(SMC0805AW)'                                                        | '1000PF'   | '100V'        | '10%'    | 'DISCRETE' | 'CAP CHIP 1000PF 100V(+-10%,X7R,0805)YGO'                      | 'CHIP0805'     | ''          | ''   | '20180522'
 '1000PF'   | '100V'  | '10%'     | 'C0805'     | 'EMPTY'   | 'CH2108K1A00'(!)   = ''              | ''                 | ''       | 'CH2108K1A00'     |'C0805'| '(SMC0805AW)'                                                        | 'NA'       | '100V'        | '10%'    | 'IO'       | 'CAP CHIP 1000PF 100V(+-10%,X7R,0805)YGO'                      | 'CHIP0805'     | ''          | ''   | '20180522'
 '1000PF'   | '100V'  | '1%'      | 'C0805'     | 'NPO'     | 'CH2108F0A00'(!)   = ''              | ''                 | ''       | 'CH2108F0A00'     |'C0805'| '(SMC0805AW)'                                                        | '1000PF'   | '100V'        | '1%'     | 'DISCRETE' | 'CAP CHIP 1000PF 100V(+-1%,NPO,0805)YGO'                       | 'CHIP0805'     | ''          | ''   | '20180523'
 '1000PF'   | '100V'  | '1%'      | 'C0805'     | 'EMPTY'   | 'CH2108F0A00'(!)   = ''              | ''                 | ''       | 'CH2108F0A00'     |'C0805'| '(SMC0805AW)'                                                        | 'NA'       | '100V'        | '1%'     | 'IO'       | 'CAP CHIP 1000PF 100V(+-1%,NPO,0805)YGO'                       | 'CHIP0805'     | ''          | ''   | '20180523'
 '5.6PF'    | '50V'   | '0.1PF'   | 'C0402'     | 'NP0'     | 'CH-566B0100'(!)   = ''              | ''                 | ''       | 'CH-566B0100'     |'C0402'| '(C0402-0201)'                                                       | '5.6PF'    | '50V'         | '0.1PF'  | 'DISCRETE' | 'CAP CHIP 5.6PF 50V(+-0.1PF,NP0,0402)'                         | 'CHIP0402'     | ''          | ''   | '20180528'
 '5.6PF'    | '50V'   | '0.1PF'   | 'C0402'     | 'EMPTY'   | 'CH-566B0100'(!)   = ''              | ''                 | ''       | 'CH-566B0100'     |'C0402'| '(C0402-0201)'                                                       | 'NA'       | '50V'         | '0.1PF'  | 'IO'       | 'CAP CHIP 5.6PF 50V(+-0.1PF,NP0,0402)'                         | 'CHIP0402'     | ''          | ''   | '20180528'
 '4.7UF'    | '16V'   | '10%'     | 'C0603'     | 'X6S'     | 'CH5473KE902'(!)   = ''              | ''                 | ''       | 'CH5473KE902'     |'C0603_H40'| '(SMC0603AW)'                                                        | '4.7UF'    | '16V'         | '10%'    | 'DISCRETE' | 'CAP CHIP 4.7UF 16V(+-10%,X6S,0603)'                           | 'CHIP0603'     | ''          | ''   | '20180627'
 '4.7UF'    | '16V'   | '10%'     | 'C0603'     | 'EMPTY'   | 'CH5473KE902'(!)   = ''              | ''                 | ''       | 'CH5473KE902'     |'C0603_H40'| '(SMC0603AW)'                                                        | 'NA'       | '16V'         | '10%'    | 'IO'       | 'CAP CHIP 4.7UF 16V(+-10%,X6S,0603)'                           | 'CHIP0603'     | ''          | ''   | '20180627'
 '10UF'     | '16V'   | '10%'     | 'C0805'     | 'X6S'     | 'CH6103KEA00'(!)   = ''              | ''                 | ''       | 'CH6103KEA00'     |'C0805_H57'| '(SMC0805AW)'                                                        | '10UF'     | '16V'         | '10%'    | 'DISCRETE' | 'CAP CHIP 10UF 16V(+-10%,X6S,0805)'                            | 'CHIP0805'     | ''          | ''   | '20180706'
 '10UF'     | '16V'   | '10%'     | 'C0805'     | 'EMPTY'   | 'CH6103KEA00'(!)   = ''              | ''                 | ''       | 'CH6103KEA00'     |'C0805_H57'| '(SMC0805AW)'                                                        | 'NA'       | '16V'         | '10%'    | 'IO'       | 'CAP CHIP 10UF 16V(+-10%,X6S,0805)'                            | 'CHIP0805'     | ''          | ''   | '20180706'
 '1NF'      | '50V'   | '10%'     | 'C0402'     | 'X7R'     | 'CH2106K1B23'(!)   = ''              | ''                 | ''       | 'CH2106K1B23'     |'C0402'| '(C0402-0201)'                                                       | '1NF'      | '50V'         | '10%'    | 'DISCRETE' | 'CAP CHIP 1N 50V(+-10%,X7R,0402)TAY'                           | 'CHIP0402'     | ''          | ''   | '20180710'
 '1NF'      | '50V'   | '10%'     | 'C0402'     | 'EMPTY'   | 'CH2106K1B23'(!)   = ''              | ''                 | ''       | 'CH2106K1B23'     |'C0402'| '(C0402-0201)'                                                       | 'NA'       | '50V'         | '10%'    | 'IO'       | 'CAP CHIP 1N 50V(+-10%,X7R,0402)TAY'                           | 'CHIP0402'     | ''          | ''   | '20180710'
 '0.01UF'   | '16V'   | '10%'     | 'C0402'     | 'X7R'     | 'CH3103K1B15'(!)   = 'End of Design' | 'Comp-Approve'     | ''       | 'CH3103K1B15'     |'C0402'| '(C0402_OCTAGON,C0402_SMDC25_SM30,C0402-0201)'                       | '0.01UF'   | '16V'         | '10%'    | 'DISCRETE' | 'CAP CHIP 0.01U 16V(10%,X7R,0402)'                             | 'CHIP0402'     | ''          | ''   | '20150911'
 '0.01UF'   | '16V'   | '10%'     | 'C0402'     | 'EMPTY'   | 'CH3103K1B15'(!)   = 'End of Design' | 'Comp-Approve'     | ''       | 'CH3103K1B15'     |'C0402'| '(C0402_OCTAGON,C0402_SMDC25_SM30,C0402-0201)'                       | 'NA'       | '16V'         | '10%'    | 'IO'       | 'CAP CHIP 0.01U 16V(10%,X7R,0402)'                             | 'CHIP0402'     | ''          | ''   | '20150911'
 '0.1UF'    | '100V'  | '10%'     | 'C0805'     | 'X7R'     | 'CH4108K1A06'(!)   = ''              | ''                 | ''       | 'CH4108K1A06'     |'C0805_H43'| '(SMC0805AW)'                                                        | '0.1UF'    | '100V'        | '10%'    | 'DISCRETE' | 'CAP CHIP 0.1UF 100V(+-10%,X7R,0805)WTC'                       | 'CHIP0805'     | ''          | ''   | '20180720'
 '0.1UF'    | '100V'  | '10%'     | 'C0805'     | 'EMPTY'   | 'CH4108K1A06'(!)   = ''              | ''                 | ''       | 'CH4108K1A06'     |'C0805_H43'| '(SMC0805AW)'                                                        | 'NA'       | '100V'        | '10%'    | 'IO'       | 'CAP CHIP 0.1UF 100V(+-10%,X7R,0805)WTC'                       | 'CHIP0805'     | ''          | ''   | '20180720'
 '0.1UF'    | '100V'  | '10%'     | 'C0805'     | 'X7R'     | 'CH4108K1A05'(!)   = ''              | ''                 | ''       | 'CH4108K1A05'     |'C0805_H57'| '(SMC0805AW)'                                                        | '0.1UF'    | '100V'        | '10%'    | 'DISCRETE' | 'CAP CHIP 0.1UF 100V(+-10%,X7R,0805)YGO'                       | 'CHIP0805'     | ''          | ''   | '20180723'
 '0.1UF'    | '100V'  | '10%'     | 'C0805'     | 'EMPTY'   | 'CH4108K1A05'(!)   = ''              | ''                 | ''       | 'CH4108K1A05'     |'C0805_H57'| '(SMC0805AW)'                                                        | 'NA'       | '100V'        | '10%'    | 'IO'       | 'CAP CHIP 0.1UF 100V(+-10%,X7R,0805)YGO'                       | 'CHIP0805'     | ''          | ''   | '20180723'
 '0.01UF'   | '1KV'   | '10%'     | 'C1206'     | 'X7R'     | 'CH310FK1204'(!)   = ''              | ''                 | ''       | 'CH310FK1204'     |'C1206_H66'| '(SMC1206AW)'                                                        | '0.01UF'   | '1KV'         | '10%'    | 'DISCRETE' | 'CAP CHIP 0.01U 1KV(+-10%,X7R,1206)YGO'                        | 'CHIP1206'     | ''          | ''   | '20180724'
 '0.01UF'   | '1KV'   | '10%'     | 'C1206'     | 'EMPTY'   | 'CH310FK1204'(!)   = ''              | ''                 | ''       | 'CH310FK1204'     |'C1206_H66'| '(SMC1206AW)'                                                        | 'NA'       | '1KV'         | '10%'    | 'IO'       | 'CAP CHIP 0.01U 1KV(+-10%,X7R,1206)YGO'                        | 'CHIP1206'     | ''          | ''   | '20180724'
 '0.1UF'    | '100V'  | '10%'     | 'C1206'     | 'X7R'     | 'CH4108K1208'(!)   = ''              | ''                 | ''       | 'CH4108K1208'     |'C1206_H76'| '(SMC1206AW)'                                                        | '0.1UF'    | '100V'        | '10%'    | 'DISCRETE' | 'CAP CHIP 0.1UF 100V(+-10%,X7R,1206)TAY'                       | 'CHIP1206'     | ''          | ''   | '20180731'
 '0.1UF'    | '100V'  | '10%'     | 'C1206'     | 'EMPTY'   | 'CH4108K1208'(!)   = ''              | ''                 | ''       | 'CH4108K1208'     |'C1206_H76'| '(SMC1206AW)'                                                        | 'NA'       | '100V'        | '10%'    | 'IO'       | 'CAP CHIP 0.1UF 100V(+-10%,X7R,1206)TAY'                       | 'CHIP1206'     | ''          | ''   | '20180731'
 '1U'       | '100V'  | '10%'     | 'C1206'     | 'X7R'     | 'CH5108K1204'(!)   = ''              | ''                 | ''       | 'CH5108K1204'     |'C1206_H76'| '(SMC1206AW)'                                                        | '1U'       | '100V'        | '10%'    | 'DISCRETE' | 'CAP CHIP 1U 100V(10%,X7R,1206)SAM'                            | 'CHIP1206'     | ''          | ''   | '20180801'
 '1U'       | '100V'  | '10%'     | 'C1206'     | 'EMPTY'   | 'CH5108K1204'(!)   = ''              | ''                 | ''       | 'CH5108K1204'     |'C1206_H76'| '(SMC1206AW)'                                                        | 'NA'       | '100V'        | '10%'    | 'IO'       | 'CAP CHIP 1U 100V(10%,X7R,1206)SAM'                            | 'CHIP1206'     | ''          | ''   | '20180801'
 '4.7U'     | '100V'  | '10%'     | 'C1206'     | 'X7S'     | 'CH5478K6200'(!)   = ''              | ''                 | ''       | 'CH5478K6200'     |'C1206XB'| '(SMC1206AW)'                                                        | '4.7U'     | '100V'        | '10%'    | 'DISCRETE' | 'CAP CHIP 4.7U 100V(10%,X7S,1206)MUR'                          | 'CHIP1206'     | ''          | ''   | '20180803'
 '4.7U'     | '100V'  | '10%'     | 'C1206'     | 'EMPTY'   | 'CH5478K6200'(!)   = ''              | ''                 | ''       | 'CH5478K6200'     |'C1206XB'| '(SMC1206AW)'                                                        | 'NA'       | '100V'        | '10%'    | 'IO'       | 'CAP CHIP 4.7U 100V(10%,X7S,1206)MUR'                          | 'CHIP1206'     | ''          | ''   | '20180803'
 '4700PF'   | '25V'   | '10%'     | 'C0402'     | 'X7R'     | 'CH2474K1B18'(!)   = ''              | ''                 | ''       | 'CH2474K1B18'     |'C0402'| '(C0402-0201)'                                                       | '4700PF'   | '25V'         | '10%'    | 'DISCRETE' | 'CAP CHIP 4700P 25V(+-10%,X7R,0402)WTC'                        | 'CHIP0402'     | ''          | ''   | '20180904'
 '4700PF'   | '25V'   | '10%'     | 'C0402'     | 'EMPTY'   | 'CH2474K1B18'(!)   = ''              | ''                 | ''       | 'CH2474K1B18'     |'C0402'| '(C0402-0201)'                                                       | 'NA'       | '25V'         | '10%'    | 'IO'       | 'CAP CHIP 4700P 25V(+-10%,X7R,0402)WTC'                        | 'CHIP0402'     | ''          | ''   | '20180904'
 '0.022UF'  | '25V'   | '10%'     | 'C0402'     | 'X7R'     | 'CH3224K1B09'(!)   = ''              | ''                 | ''       | 'CH3224K1B09'     |'C0402'| '(C0402-0201)'                                                       | '0.022UF'  | '25V'         | '10%'    | 'DISCRETE' | 'CAP CHIP 0.022U 25V(+-10%,X7R,0402)WTC'                       | 'CHIP0402'     | ''          | ''   | '20180904'
 '0.022UF'  | '25V'   | '10%'     | 'C0402'     | 'EMPTY'   | 'CH3224K1B09'(!)   = ''              | ''                 | ''       | 'CH3224K1B09'     |'C0402'| '(C0402-0201)'                                                       | 'NA'       | '25V'         | '10%'    | 'IO'       | 'CAP CHIP 0.022U 25V(+-10%,X7R,0402)WTC'                       | 'CHIP0402'     | ''          | ''   | '20180904'
 '0.047UF'  | '50V'   | '10%'     | 'C0402'     | 'X7R'     | 'CH3476K1B04'(!)   = ''              | ''                 | ''       | 'CH3476K1B04'     |'C0402_H28'| '(C0402-0201_H28)'                                                   | '0.047UF'  | '50V'         | '10%'    | 'DISCRETE' | 'CAP CHIP 0.047U 50V(+-10%,X7R,0402)WTC'                       | 'CHIP0402'     | ''          | ''   | '20180904'
 '0.047UF'  | '50V'   | '10%'     | 'C0402'     | 'EMPTY'   | 'CH3476K1B04'(!)   = ''              | ''                 | ''       | 'CH3476K1B04'     |'C0402_H28'| '(C0402-0201_H28)'                                                   | 'NA'       | '50V'         | '10%'    | 'IO'       | 'CAP CHIP 0.047U 50V(+-10%,X7R,0402)WTC'                       | 'CHIP0402'     | ''          | ''   | '20180904'
 '0.039UF'  | '50V'   | '10%'     | 'C0603'     | 'X7R'     | 'CH3396K1904'(!)   = ''              | ''                 | ''       | 'CH3396K1904'     |'C0603'| '(SMC0603AW)'                                                        | '0.039UF'  | '50V'         | '10%'    | 'DISCRETE' | 'CAP CHIP 0.039U 50V(+-10%,X7R,0603)WTC'                       | 'CHIP0603'     | ''          | ''   | '20180904'
 '0.039UF'  | '50V'   | '10%'     | 'C0603'     | 'EMPTY'   | 'CH3396K1904'(!)   = ''              | ''                 | ''       | 'CH3396K1904'     |'C0603'| '(SMC0603AW)'                                                        | 'NA'       | '50V'         | '10%'    | 'IO'       | 'CAP CHIP 0.039U 50V(+-10%,X7R,0603)WTC'                       | 'CHIP0603'     | ''          | ''   | '20180904'
 '0.68UF'   | '16V'   | '10%'     | 'C0603'     | 'X7R'     | 'CH4683K1902'(!)   = ''              | ''                 | ''       | 'CH4683K1902'     |'C0603'| '(SMC0603AW)'                                                        | '0.68UF'   | '16V'         | '10%'    | 'DISCRETE' | 'CAP CHIP 0.68U 16V(+-10%,X7R,0603)SAM'                        | 'CHIP0603'     | ''          | ''   | '20160810'
 '0.68UF'   | '16V'   | '10%'     | 'C0603'     | 'EMPTY'   | 'CH4683K1902'(!)   = ''              | ''                 | ''       | 'CH4683K1902'     |'C0603'| '(SMC0603AW)'                                                        | 'NA'       | '16V'         | '10%'    | 'IO'       | 'CAP CHIP 0.68U 16V(+-10%,X7R,0603)SAM'                        | 'CHIP0603'     | ''          | ''   | '20160810'
 '4700PF'   | '25V'   | '10%'     | 'C0402'     | 'X7R'     | 'CH2474K1B12'(!)   = ''              | ''                 | ''       | 'CH2474K1B12'     |'C0402'| '(C0402-0201)'                                                       | '4700PF'   | '25V'         | '10%'    | 'DISCRETE' | 'CAP CHIP 4700P 25V(+-10%,X7R,0402)SAM'                        | 'CHIP0402'     | ''          | ''   | '20180917'
 '4700PF'   | '25V'   | '10%'     | 'C0402'     | 'EMPTY'   | 'CH2474K1B12'(!)   = ''              | ''                 | ''       | 'CH2474K1B12'     |'C0402'| '(C0402-0201)'                                                       | 'NA'       | '25V'         | '10%'    | 'IO'       | 'CAP CHIP 4700P 25V(+-10%,X7R,0402)SAM'                        | 'CHIP0402'     | ''          | ''   | '20180917'
 '470NF'    | '50V'   | '5%'      | 'C1812'     | 'U2J'     | 'CH4476JF400'(!)   = 'End of Design' | 'Comp-Release Qty' | ''       | 'CH4476JF400'     |'C1812XB'| '(SMC0603AW)'                                                        | '470NF'    | '50V'         | '5%'     | 'DISCRETE' | 'CAP CHIP 470NF 50V(+-5%,U2J,1812)'                            | 'CHIP1812'     | ''          | ''   | '20180927'
 '470NF'    | '50V'   | '5%'      | 'C1812'     | 'EMPTY'   | 'CH4476JF400'(!)   = 'End of Design' | 'Comp-Release Qty' | ''       | 'CH4476JF400'     |'C1812XB'| '(SMC0603AW)'                                                        | 'NA'       | '50V'         | '5%'     | 'IO'       | 'CAP CHIP 470NF 50V(+-5%,U2J,1812)'                            | 'CHIP1812'     | ''          | ''   | '20180927'
 '470NF'    | '50V'   | '5%'      | 'C1812'     | 'U2J'     | 'CH4476JF401'(!)   = 'End of Design' | 'Comp-Approve'     | ''       | 'CH4476JF401'     |'C1812XB'| '(SMC0603AW)'                                                        | '470NF'    | '50V'         | '5%'     | 'DISCRETE' | 'CAP CHIP 470NF 50V(+-5%,U2J,1812)KEM'                         | 'CHIP1812'     | ''          | ''   | '20181008'
 '470NF'    | '50V'   | '5%'      | 'C1812'     | 'EMPTY'   | 'CH4476JF401'(!)   = 'End of Design' | 'Comp-Approve'     | ''       | 'CH4476JF401'     |'C1812XB'| '(SMC0603AW)'                                                        | 'NA'       | '50V'         | '5%'     | 'IO'       | 'CAP CHIP 470NF 50V(+-5%,U2J,1812)KEM'                         | 'CHIP1812'     | ''          | ''   | '20181008'
 '22UF'     | '16V'   | '20%'     | 'C0805'     | 'X5R'     | 'CH6223M9A00'(!)   = ''              | ''                 | ''       | 'CH6223M9A00'     |'C0805_H57'| '(SMC0805AW)'                                                        | '22UF'     | '16V'         | '20%'    | 'DISCRETE' | 'CAP CHIP 22UF 16V( +-20% ,X5R,0805)'                          | 'CHIP0805'     | ''          | ''   | '20181016'
 '22UF'     | '16V'   | '20%'     | 'C0805'     | 'EMPTY'   | 'CH6223M9A00'(!)   = ''              | ''                 | ''       | 'CH6223M9A00'     |'C0805_H57'| '(SMC0805AW)'                                                        | 'NA'       | '16V'         | '20%'    | 'IO'       | 'CAP CHIP 22UF 16V( +-20% ,X5R,0805)'                          | 'CHIP0805'     | ''          | ''   | '20181016'
 '2.2UF'    | '25V'   | '10%'     | 'C0603'     | 'X6S'     | 'CH5224KE900'(!)   = ''              | ''                 | ''       | 'CH5224KE900'     |'C0603_H40'| '(SMC0603AW)'                                                        | '2.2UF'    | '25V'         | '10%'    | 'DISCRETE' | 'CAP CHIP 2.2U 25V(+-10%,X6S,0603)MUR'                         | 'CHIP0603'     | ''          | ''   | '20181017'
 '2.2UF'    | '25V'   | '10%'     | 'C0603'     | 'EMPTY'   | 'CH5224KE900'(!)   = ''              | ''                 | ''       | 'CH5224KE900'     |'C0603_H40'| '(SMC0603AW)'                                                        | 'NA'       | '25V'         | '10%'    | 'IO'       | 'CAP CHIP 2.2U 25V(+-10%,X6S,0603)MUR'                         | 'CHIP0603'     | ''          | ''   | '20181017'
 '1UF'      | '100V'  | '10%'     | 'C0805'     | 'X7S'     | 'CH5108K6A01'(!)   = ''              | ''                 | ''       | 'CH5108K6A01'     |'C0805_H57'| '(SMC0805AW)'                                                        | '1UF'      | '100V'        | '10%'    | 'DISCRETE' | 'CAP CHIP 1UF 100V(+-10%,X7S,0805)'                            | 'CHIP0805'     | ''          | ''   | '20181018'
 '1UF'      | '100V'  | '10%'     | 'C0805'     | 'EMPTY'   | 'CH5108K6A01'(!)   = ''              | ''                 | ''       | 'CH5108K6A01'     |'C0805_H57'| '(SMC0805AW)'                                                        | 'NA'       | '100V'        | '10%'    | 'IO'       | 'CAP CHIP 1UF 100V(+-10%,X7S,0805)'                            | 'CHIP0805'     | ''          | ''   | '20181018'
 '0.1UF'    | '16V'   | '10%'     | 'C0201'     | 'X5R'     | 'CH4103K9E01'(!)   = ''              | ''                 | ''       | 'CH4103K9E01'     |'C0201'| '(SMC0201AW)'                                                        | '0.1UF'    | '16V'         | '10%'    | 'DISCRETE' | 'CAP CHIP 0.1U 16V(+-10%,X5R,0201)'                            | 'CHIP0201'     | ''          | ''   | '20181018'
 '0.1UF'    | '16V'   | '10%'     | 'C0201'     | 'EMPTY'   | 'CH4103K9E01'(!)   = ''              | ''                 | ''       | 'CH4103K9E01'     |'C0201'| '(SMC0201AW)'                                                        | 'NA'       | '16V'         | '10%'    | 'IO'       | 'CAP CHIP 0.1U 16V(+-10%,X5R,0201)'                            | 'CHIP0201'     | ''          | ''   | '20181018'
 '0.033UF'  | '100V'  | '10%'     | 'C0603'     | 'X7R'     | 'CH3338K1900'(!)   = ''              | ''                 | ''       | 'CH3338K1900'     |'C0603'| '(SMC0603AW)'                                                        | '0.033UF'  | '100V'        | '10%'    | 'DISCRETE' | 'CAP CHIP 0.033U 100V(+-10%,X7R,0603)'                         | 'CHIP0603'     | ''          | ''   | '20181018'
 '0.033UF'  | '100V'  | '10%'     | 'C0603'     | 'EMPTY'   | 'CH3338K1900'(!)   = ''              | ''                 | ''       | 'CH3338K1900'     |'C0603'| '(SMC0603AW)'                                                        | 'NA'       | '100V'        | '10%'    | 'IO'       | 'CAP CHIP 0.033U 100V(+-10%,X7R,0603)'                         | 'CHIP0603'     | ''          | ''   | '20181018'
 '0.1UF'    | '100V'  | '10%'     | 'C0603'     | 'X7R'     | 'CH4108K1901'(!)   = 'End of Design' | 'Comp-Approve'     | ''       | 'CH4108K1901'     |'C0603'| '(SMC0603AW)'                                                        | '0.1UF'    | '100V'        | '10%'    | 'DISCRETE' | 'CAP CHIP 0.1U 100V(+-10%,X7R,0603)'                           | 'CHIP0603'     | ''          | ''   | '20181018'
 '0.1UF'    | '100V'  | '10%'     | 'C0603'     | 'EMPTY'   | 'CH4108K1901'(!)   = 'End of Design' | 'Comp-Approve'     | ''       | 'CH4108K1901'     |'C0603'| '(SMC0603AW)'                                                        | 'NA'       | '100V'        | '10%'    | 'IO'       | 'CAP CHIP 0.1U 100V(+-10%,X7R,0603)'                           | 'CHIP0603'     | ''          | ''   | '20181018'
 '0.68UF'   | '6.3V'  | '10%'     | 'C0402'     | 'X5R'     | 'CH4681K9B00'(!)   = 'End of Design' | 'Comp-Release Qty' | ''       | 'CH4681K9B00'     |'C0402'| '(C0402-0201)'                                                       | '0.68UF'   | '6.3V'        | '10%'    | 'DISCRETE' | 'CAP CHIP 0.68UF 6.3V(+-10%,X5R,0402)'                         | 'CHIP0402'     | ''          | ''   | '20181026'
 '0.68UF'   | '6.3V'  | '10%'     | 'C0402'     | 'EMPTY'   | 'CH4681K9B00'(!)   = 'End of Design' | 'Comp-Release Qty' | ''       | 'CH4681K9B00'     |'C0402'| '(C0402-0201)'                                                       | 'NA'       | '6.3V'        | '10%'    | 'IO'       | 'CAP CHIP 0.68UF 6.3V(+-10%,X5R,0402)'                         | 'CHIP0402'     | ''          | ''   | '20181026'
 '2.7PF'    | '50V'   | '0.1P'    | 'C0201'     | 'C0G'     | 'CH-276B0E00'(!)   = ''              | ''                 | ''       | 'CH-276B0E00'     |'C0201'| '(SMC0201AW)'                                                        | '2.7PF'    | '50V'         | '0.1P'   | 'DISCRETE' | 'CAP CHIP 2.7P 50V(+-0.1P,C0G,0201)'                           | 'CHIP0201'     | ''          | ''   | '20181026'
 '2.7PF'    | '50V'   | '0.1P'    | 'C0201'     | 'EMPTY'   | 'CH-276B0E00'(!)   = ''              | ''                 | ''       | 'CH-276B0E00'     |'C0201'| '(SMC0201AW)'                                                        | 'NA'       | '50V'         | '0.1P'   | 'IO'       | 'CAP CHIP 2.7P 50V(+-0.1P,C0G,0201)'                           | 'CHIP0201'     | ''          | ''   | '20181026'
 '2.2U'     | '6.3V'  | '20%'     | 'C0402'     | 'X6S'     | 'CH5221MEB03'(!)   = ''              | ''                 | ''       | 'CH5221MEB03'     |'C0402'| '(C0402-0201)'                                                       | '2.2U'     | '6.3V'        | '20%'    | 'DISCRETE' | 'CAP CHIP 2.2U 6.3V(+-20%,X6S,0402)MUR'                        | 'CHIP0402'     | ''          | ''   | '20181122'
 '2.2U'     | '6.3V'  | '20%'     | 'C0402'     | 'EMPTY'   | 'CH5221MEB03'(!)   = ''              | ''                 | ''       | 'CH5221MEB03'     |'C0402'| '(C0402-0201)'                                                       | 'NA'       | '6.3V'        | '20%'    | 'IO'       | 'CAP CHIP 2.2U 6.3V(+-20%,X6S,0402)MUR'                        | 'CHIP0402'     | ''          | ''   | '20181122'
 '2200PF'   | '50V'   | '10%'     | 'C0402'     | 'X7R'     | 'CH2226K1B10'(!)   = ''              | ''                 | ''       | 'CH2226K1B10'     |'C0402_H28'| '(C0402-0201_H28)'                                                   | '2200PF'   | '50V'         | '10%'    | 'DISCRETE' | 'CAP CHIP 2200P 50V(+-10%,X7R,0402)WTC'                        | 'CHIP0402'     | ''          | ''   | '20181126'
 '2200PF'   | '50V'   | '10%'     | 'C0402'     | 'EMPTY'   | 'CH2226K1B10'(!)   = ''              | ''                 | ''       | 'CH2226K1B10'     |'C0402_H28'| '(C0402-0201_H28)'                                                   | 'NA'       | '50V'         | '10%'    | 'IO'       | 'CAP CHIP 2200P 50V(+-10%,X7R,0402)WTC'                        | 'CHIP0402'     | ''          | ''   | '20181126'
 '10UF'     | '16V'   | '10%'     | 'C0805'     | 'X6S'     | 'CH6103KEA01'(!)   = ''              | ''                 | ''       | 'CH6103KEA01'     |'C0805_H57'| '(SMC0805AW)'                                                        | '10UF'     | '16V'         | '10%'    | 'DISCRETE' | 'CAP CHIP 10UF 16V(+-10%,X6S,0805)MUR'                         | 'CHIP0805'     | ''          | ''   | '20181128'
 '10UF'     | '16V'   | '10%'     | 'C0805'     | 'EMPTY'   | 'CH6103KEA01'(!)   = ''              | ''                 | ''       | 'CH6103KEA01'     |'C0805_H57'| '(SMC0805AW)'                                                        | 'NA'       | '16V'         | '10%'    | 'IO'       | 'CAP CHIP 10UF 16V(+-10%,X6S,0805)MUR'                         | 'CHIP0805'     | ''          | ''   | '20181128'
 '3300P'    | '50V'   | '10%'     | 'C0402'     | 'X7R'     | 'CH2336K1B19'(!)   = ''              | ''                 | ''       | 'CH2336K1B19'     |'C0402'| '(C0402-0201)'                                                       | '3300P'    | '50V'         | '10%'    | 'DISCRETE' | 'CAP CHIP 3300P 50V(+-10%,X7R,0402)WTC'                        | 'CHIP0402'     | ''          | ''   | '20181130'
 '3300P'    | '50V'   | '10%'     | 'C0402'     | 'EMPTY'   | 'CH2336K1B19'(!)   = ''              | ''                 | ''       | 'CH2336K1B19'     |'C0402'| '(C0402-0201)'                                                       | 'NA'       | '50V'         | '10%'    | 'IO'       | 'CAP CHIP 3300P 50V(+-10%,X7R,0402)WTC'                        | 'CHIP0402'     | ''          | ''   | '20181130'
 '1PF'      | '25V'   | '0.1%'    | 'C0201'     | 'C0G'     | 'CH-104B0E01'(!)   = ''              | ''                 | ''       | 'CH-104B0E01'     |'C0201'| '(SMC0201AW)'                                                        | '1PF'      | '25V'         | '0.1%'   | 'DISCRETE' | 'CAP CHIP 1PF 25V(+-0.1PF,C0G,0201)'                           | 'CHIP0201'     | ''          | ''   | '20190121'
 '1PF'      | '25V'   | '0.1%'    | 'C0201'     | 'EMPTY'   | 'CH-104B0E01'(!)   = ''              | ''                 | ''       | 'CH-104B0E01'     |'C0201'| '(SMC0201AW)'                                                        | 'NA'       | '25V'         | '0.1%'   | 'IO'       | 'CAP CHIP 1PF 25V(+-0.1PF,C0G,0201)'                           | 'CHIP0201'     | ''          | ''   | '20190121'
 '330P'     | '50V'   | '+-2%'    | 'C0402'     | 'NPO'     | 'CH1336G0B00'(!)   = ''              | ''                 | ''       | 'CH1336G0B00'     |'C0402'| '(C0402-0201)'                                                       | '330P'     | '50V'         | '+-2%'   | 'DISCRETE' | 'CAP CHIP 330P 50V(+-2%,NPO,0402)'                             | 'CHIP0402'     | ''          | ''   | '20190124'
 '330P'     | '50V'   | '+-2%'    | 'C0402'     | 'EMPTY'   | 'CH1336G0B00'(!)   = ''              | ''                 | ''       | 'CH1336G0B00'     |'C0402'| '(C0402-0201)'                                                       | 'NA'       | '50V'         | '+-2%'   | 'IO'       | 'CAP CHIP 330P 50V(+-2%,NPO,0402)'                             | 'CHIP0402'     | ''          | ''   | '20190124'
 '0.1U'     | '16V'   | '10%'     | 'C0402'     | 'X7R'     | 'CH4103K1B20'(!)   = ''              | ''                 | ''       | 'CH4103K1B20'     |'C0402'| '(C0402-0201)'                                                       | '0.1U'     | '16V'         | '10%'    | 'DISCRETE' | 'CAP CHIP 0.1U 16V(10%,X7R,0402)TAY'                           | 'CHIP0402'     | ''          | ''   | '20190124'
 '0.1U'     | '16V'   | '10%'     | 'C0402'     | 'EMPTY'   | 'CH4103K1B20'(!)   = ''              | ''                 | ''       | 'CH4103K1B20'     |'C0402'| '(C0402-0201)'                                                       | 'NA'       | '16V'         | '10%'    | 'IO'       | 'CAP CHIP 0.1U 16V(10%,X7R,0402)TAY'                           | 'CHIP0402'     | ''          | ''   | '20190124'
 '3300P'    | '50V'   | '+-10%'   | 'C0402'     | 'X7R'     | 'CH2336K1B10'(!)   = ''              | ''                 | ''       | 'CH2336K1B10'     |'C0402'| '(C0402-0201)'                                                       | '3300P'    | '50V'         | '+-10%'  | 'DISCRETE' | 'CAP CHIP 3300P 50V(+-10%,X7R,0402)SAM'                        | 'CHIP0402'     | ''          | ''   | '20190124'
 '3300P'    | '50V'   | '+-10%'   | 'C0402'     | 'EMPTY'   | 'CH2336K1B10'(!)   = ''              | ''                 | ''       | 'CH2336K1B10'     |'C0402'| '(C0402-0201)'                                                       | 'NA'       | '50V'         | '+-10%'  | 'IO'       | 'CAP CHIP 3300P 50V(+-10%,X7R,0402)SAM'                        | 'CHIP0402'     | ''          | ''   | '20190124'
 '330N'     | '250V'  | '+-10%'   | 'C1812'     | 'X7R'     | 'CH433CK1400'(!)   = ''              | ''                 | ''       | 'CH433CK1400'     |'C1812XC'| '(SMC1812AW)'                                                        | '330N'     | '250V'        | '+-10%'  | 'DISCRETE' | 'CAP CHIP 330N 250V(+-10%,X7R,1812)'                           | 'CHIP1812'     | ''          | ''   | '20190128'
 '330N'     | '250V'  | '+-10%'   | 'C1812'     | 'EMPTY'   | 'CH433CK1400'(!)   = ''              | ''                 | ''       | 'CH433CK1400'     |'C1812XC'| '(SMC1812AW)'                                                        | 'NA'       | '250V'        | '+-10%'  | 'IO'       | 'CAP CHIP 330N 250V(+-10%,X7R,1812)'                           | 'CHIP1812'     | ''          | ''   | '20190128'
 '0.22UF'   | '25V'   | '10%'     | 'C0402'     | 'X7R'     | 'CH4224K1B09'(!)   = ''              | ''                 | ''       | 'CH4224K1B09'     |'C0402'| '(C0402-0201)'                                                       | '0.22UF'   | '25V'         | '10%'    | 'DISCRETE' | 'CAP CHIP 0.22U 25V(+-10%,X7R,0402)TAY'                        | 'CHIP0402'     | ''          | ''   | '20190219'
 '0.22UF'   | '25V'   | '10%'     | 'C0402'     | 'EMPTY'   | 'CH4224K1B09'(!)   = ''              | ''                 | ''       | 'CH4224K1B09'     |'C0402'| '(C0402-0201)'                                                       | 'NA'       | '25V'         | '10%'    | 'IO'       | 'CAP CHIP 0.22U 25V(+-10%,X7R,0402)TAY'                        | 'CHIP0402'     | ''          | ''   | '20190219'
 '1UF'      | '50V'   | '10%'     | 'C0603'     | 'X7R'     | 'CH5106K1900'(!)   = ''              | ''                 | ''       | 'CH5106K1900'     |'C0603_H40'| '(SMC0603AW)'                                                        | '1UF'      | '50V'         | '10%'    | 'DISCRETE' | 'CAP CHIP 1U 50V(+-10%,X7R,0603)YGO'                           | 'CHIP0603'     | ''          | ''   | '20190401'
 '1UF'      | '50V'   | '10%'     | 'C0603'     | 'EMPTY'   | 'CH5106K1900'(!)   = ''              | ''                 | ''       | 'CH5106K1900'     |'C0603_H40'| '(SMC0603AW)'                                                        | 'NA'       | '50V'         | '10%'    | 'IO'       | 'CAP CHIP 1U 50V(+-10%,X7R,0603)YGO'                           | 'CHIP0603'     | ''          | ''   | '20190401'
 '4.7UF'    | '50V'   | '10%'     | 'C0805'     | 'X5R'     | 'CH5476K9A02'(!)   = ''              | ''                 | ''       | 'CH5476K9A02'     |'C0805_H57'| '(SMC0805AW)'                                                        | '4.7UF'    | '50V'         | '10%'    | 'DISCRETE' | 'CAP CHIP 4.7UF 50V(+-10%,X5R,0805)MUR'                        | 'CHIP0805'     | ''          | ''   | '20190401'
 '4.7UF'    | '50V'   | '10%'     | 'C0805'     | 'EMPTY'   | 'CH5476K9A02'(!)   = ''              | ''                 | ''       | 'CH5476K9A02'     |'C0805_H57'| '(SMC0805AW)'                                                        | 'NA'       | '50V'         | '10%'    | 'IO'       | 'CAP CHIP 4.7UF 50V(+-10%,X5R,0805)MUR'                        | 'CHIP0805'     | ''          | ''   | '20190401'
 '1UF'      | '50V'   | '10%'     | 'C0805'     | 'X7R'     | 'CH5106K1A05'(!)   = ''              | ''                 | ''       | 'CH5106K1A05'     |'C0805_H57'| '(SMC0805AW)'                                                        | '1UF'      | '50V'         | '10%'    | 'DISCRETE' | 'CAP CHIP 1U 50V(+-10%,X7R,0805)SAM'                           | 'CHIP0805'     | ''          | ''   | '20190412'
 '1UF'      | '50V'   | '10%'     | 'C0805'     | 'EMPTY'   | 'CH5106K1A05'(!)   = ''              | ''                 | ''       | 'CH5106K1A05'     |'C0805_H57'| '(SMC0805AW)'                                                        | 'NA'       | '50V'         | '10%'    | 'IO'       | 'CAP CHIP 1U 50V(+-10%,X7R,0805)SAM'                           | 'CHIP0805'     | ''          | ''   | '20190412'
 '220P'     | '50V'   | '5%'      | 'C0402'     | 'COG'     | 'CH1226J0B03'(!)   = ''              | ''                 | ''       | 'CH1226J0B03'     |'C0402'| '(C0402-0201)'                                                       | '220P'     | '50V'         | '5%'     | 'DISCRETE' | 'CAP CHIP 220P 50V(+-5%,COG,0402)MUR'                          | 'CHIP0402'     | ''          | ''   | '20190422'
 '220P'     | '50V'   | '5%'      | 'C0402'     | 'EMPTY'   | 'CH1226J0B03'(!)   = ''              | ''                 | ''       | 'CH1226J0B03'     |'C0402'| '(C0402-0201)'                                                       | 'NA'       | '50V'         | '5%'     | 'IO'       | 'CAP CHIP 220P 50V(+-5%,COG,0402)MUR'                          | 'CHIP0402'     | ''          | ''   | '20190422'
 '3.9P'     | '50V'   | '0.1P'    | 'C0402'     | 'NPO'     | 'CH-3916TB01'(!)   = ''              | ''                 | ''       | 'CH-3916TB01'     |'C0402'| '(C0402-0201)'                                                       | '3.9P'     | '50V'         | '0.1P'   | 'DISCRETE' | 'CAP CHIP 3.9P 50V(+-0.1P,NPO,0402)'                           | 'CHIP0402'     | ''          | ''   | '20190426'
 '3.9P'     | '50V'   | '0.1P'    | 'C0402'     | 'EMPTY'   | 'CH-3916TB01'(!)   = ''              | ''                 | ''       | 'CH-3916TB01'     |'C0402'| '(C0402-0201)'                                                       | 'NA'       | '50V'         | '0.1P'   | 'IO'       | 'CAP CHIP 3.9P 50V(+-0.1P,NPO,0402)'                           | 'CHIP0402'     | ''          | ''   | '20190426'
 '10PF'     | '50V'   | '2%'      | 'C0402'     | 'NPO'     | 'CH01006GB02'(!)   = ''              | ''                 | ''       | 'CH01006GB02'     |'C0402'| '(C0402-0201)'                                                       | '10PF'     | '50V'         | '2%'     | 'DISCRETE' | 'CAP CHIP 10P 50V(+-2%,NPO,0402)'                              | 'CHIP0402'     | ''          | ''   | '20190605'
 '10PF'     | '50V'   | '2%'      | 'C0402'     | 'EMPTY'   | 'CH01006GB02'(!)   = ''              | ''                 | ''       | 'CH01006GB02'     |'C0402'| '(C0402-0201)'                                                       | 'NA'       | '50V'         | '2%'     | 'IO'       | 'CAP CHIP 10P 50V(+-2%,NPO,0402)'                              | 'CHIP0402'     | ''          | ''   | '20190605'
 '47UF'     | '2.5V'  | '20%'     | 'C0603'     | 'X6S'     | 'CH647LME900'(!)   = 'End of Design' | 'Comp-Approve'     | ''       | 'CH647LME900'     |'C0603'| '(SMC0603AW)'                                                        | '47UF'     | '2.5V'        | '20%'    | 'DISCRETE' | 'CAP CHIP 47U 2.5V(+-20%,X6S,0603)MUR'                         | 'CHIP0603'     | ''          | ''   | '20190605'
 '47UF'     | '2.5V'  | '20%'     | 'C0603'     | 'EMPTY'   | 'CH647LME900'(!)   = 'End of Design' | 'Comp-Approve'     | ''       | 'CH647LME900'     |'C0603'| '(SMC0603AW)'                                                        | 'NA'       | '2.5V'        | '20%'    | 'IO'       | 'CAP CHIP 47U 2.5V(+-20%,X6S,0603)MUR'                         | 'CHIP0603'     | ''          | ''   | '20190605'
 '2.2PF'    | '50V'   | '0.1P'    | 'C0402'     | 'NPO'     | 'CH-2216TB02'(!)   = ''              | ''                 | ''       | 'CH-2216TB02'     |'C0402'| '(C0402-0201)'                                                       | '2.2PF'    | '50V'         | '0.1P'   | 'DISCRETE' | 'CAP CHIP 2.2P 50V (+-0.1P NPO 0402)'                          | 'CHIP0402'     | ''          | ''   | '20190605'
 '2.2PF'    | '50V'   | '0.1P'    | 'C0402'     | 'EMPTY'   | 'CH-2216TB02'(!)   = ''              | ''                 | ''       | 'CH-2216TB02'     |'C0402'| '(C0402-0201)'                                                       | 'NA'       | '50V'         | '0.1P'   | 'IO'       | 'CAP CHIP 2.2P 50V (+-0.1P NPO 0402)'                          | 'CHIP0402'     | ''          | ''   | '20190605'
 '22UF'     | '4V'    | '20%'     | 'C0805'     | 'X6S'     | 'CH622KMEA04'(!)   = ''              | ''                 | ''       | 'CH622KMEA04'     |'C0805_H57'| '(SMC0805AW)'                                                        | '22UF'     | '4V'          | '20%'    | 'DISCRETE' | 'CAP CHIP 22U 4V(+-20%,X6S,0805)SAM'                           | 'CHIP0805'     | ''          | ''   | '20190611'
 '22UF'     | '4V'    | '20%'     | 'C0805'     | 'EMPTY'   | 'CH622KMEA04'(!)   = ''              | ''                 | ''       | 'CH622KMEA04'     |'C0805_H57'| '(SMC0805AW)'                                                        | 'NA'       | '4V'          | '20%'    | 'IO'       | 'CAP CHIP 22U 4V(+-20%,X6S,0805)SAM'                           | 'CHIP0805'     | ''          | ''   | '20190611'
 '22UF'     | '16V'   | '20%'     | 'C0805'     | 'X6S'     | 'CH6223MEA03'(!)   = ''              | ''                 | ''       | 'CH6223MEA03'     |'C0805_H57'| '(SMC0805AW)'                                                        | '22UF'     | '16V'         | '20%'    | 'DISCRETE' | 'CAP CHIP 22U 16V(20%,X6S,0805)SAM'                            | 'CHIP0805'     | ''          | ''   | '20190611'
 '22UF'     | '16V'   | '20%'     | 'C0805'     | 'EMPTY'   | 'CH6223MEA03'(!)   = ''              | ''                 | ''       | 'CH6223MEA03'     |'C0805_H57'| '(SMC0805AW)'                                                        | 'NA'       | '16V'         | '20%'    | 'IO'       | 'CAP CHIP 22U 16V(20%,X6S,0805)SAM'                            | 'CHIP0805'     | ''          | ''   | '20190611'
 '3300PF'   | '50V'   | '5%'      | 'C0402'     | 'X7R'     | 'CH23306JB16'(!)   = ''              | ''                 | ''       | 'CH23306JB16'     |'C0402'| '(C0402-0201)'                                                       | '3300PF'   | '50V'         | '5%'     | 'DISCRETE' | 'CAP CHIP 3300P 50V(+-5%,X7R,0402)'                            | 'CHIP0402'     | ''          | ''   | '20190712'
 '3300PF'   | '50V'   | '5%'      | 'C0402'     | 'EMPTY'   | 'CH23306JB16'(!)   = ''              | ''                 | ''       | 'CH23306JB16'     |'C0402'| '(C0402-0201)'                                                       | 'NA'       | '50V'         | '5%'     | 'IO'       | 'CAP CHIP 3300P 50V(+-5%,X7R,0402)'                            | 'CHIP0402'     | ''          | ''   | '20190712'
 '4.7UF'    | '25V'   | '10%'     | 'C0603'     | 'X5R'     | 'CH5474K9901'(!)   = ''              | ''                 | ''       | 'CH5474K9901'     |'C0603_H40'| '(SMC0603AW)'                                                        | '4.7UF'    | '25V'         | '10%'    | 'DISCRETE' | 'CAP CHIP 4.7U 25V(+-10%,X5R,0603)'                            | 'CHIP0603'     | ''          | ''   | '20190730'
 '4.7UF'    | '25V'   | '10%'     | 'C0603'     | 'EMPTY'   | 'CH5474K9901'(!)   = ''              | ''                 | ''       | 'CH5474K9901'     |'C0603_H40'| '(SMC0603AW)'                                                        | 'NA'       | '25V'         | '10%'    | 'IO'       | 'CAP CHIP 4.7U 25V(+-10%,X5R,0603)'                            | 'CHIP0603'     | ''          | ''   | '20190730'
 '1UF'      | '25V'   | '10%'     | 'C0402'     | 'X5R'     | 'CH5104K9B01'(!)   = ''              | ''                 | ''       | 'CH5104K9B01'     |'C0402'| '(C0402-0201))'                                                      | '1UF'      | '25V'         | '10%'    | 'DISCRETE' | 'CAP CHIP 1UF 25V(+-10%,X5R,0402)'                             | 'CHIP0402'     | ''          | ''   | '20190731'
 '1UF'      | '25V'   | '10%'     | 'C0402'     | 'EMPTY'   | 'CH5104K9B01'(!)   = ''              | ''                 | ''       | 'CH5104K9B01'     |'C0402'| '(C0402-0201))'                                                      | 'NA'       | '25V'         | '10%'    | 'IO'       | 'CAP CHIP 1UF 25V(+-10%,X5R,0402)'                             | 'CHIP0402'     | ''          | ''   | '20190731'
 '4.7UF'    | '6.3V'  | '10%'     | 'C0402'     | 'X5R'     | 'CH5471K9B00'(!)   = ''              | ''                 | ''       | 'CH5471K9B00'     |'C0402_H28'| '(C0402-0201_H28)'                                                   | '4.7UF'    | '6.3V'        | '10%'    | 'DISCRETE' | 'CAP CHIP 4.7UF 6.3V(+-10%,X5R,0402)'                          | 'CHIP0402'     | ''          | ''   | '20190731'
 '4.7UF'    | '6.3V'  | '10%'     | 'C0402'     | 'EMPTY'   | 'CH5471K9B00'(!)   = ''              | ''                 | ''       | 'CH5471K9B00'     |'C0402_H28'| '(C0402-0201_H28)'                                                   | 'NA'       | '6.3V'        | '10%'    | 'IO'       | 'CAP CHIP 4.7UF 6.3V(+-10%,X5R,0402)'                          | 'CHIP0402'     | ''          | ''   | '20190731'
 '22UF'     | '6.3V'  | '20%'     | 'C0603'     | 'X6S'     | 'CH6221ME907'(!)   = ''              | ''                 | ''       | 'CH6221ME907'     |'C0603_H40'| '(SMC0603AW)'                                                        | '22UF'     | '6.3V'        | '20%'    | 'DISCRETE' | 'CAP CHIP 22U 6.3V(+-20%,X6S,0603)SAM'                         | 'CHIP0603'     | ''          | ''   | '20190807'
 '22UF'     | '6.3V'  | '20%'     | 'C0603'     | 'EMPTY'   | 'CH6221ME907'(!)   = ''              | ''                 | ''       | 'CH6221ME907'     |'C0603_H40'| '(SMC0603AW)'                                                        | 'NA'       | '6.3V'        | '20%'    | 'IO'       | 'CAP CHIP 22U 6.3V(+-20%,X6S,0603)SAM'                         | 'CHIP0603'     | ''          | ''   | '20190807'
 '2.2UF'    | '25V'   | '10%'     | 'C0402'     | 'X5R'     | 'CH5224K9B01'(!)   = ''              | ''                 | ''       | 'CH5224K9B01'     |'C0402_H28'| '(C0402-0201_H28)'                                                   | '2.2UF'    | '25V'         | '10%'    | 'DISCRETE' | 'CAP CHIP 2.2U 25V(+-10%,X5R,0402)'                            | 'CHIP0402'     | ''          | ''   | '20150729'
 '2.2UF'    | '25V'   | '10%'     | 'C0402'     | 'EMPTY'   | 'CH5224K9B01'(!)   = ''              | ''                 | ''       | 'CH5224K9B01'     |'C0402_H28'| '(C0402-0201_H28)'                                                   | 'NA'       | '25V'         | '10%'    | 'IO'       | 'CAP CHIP 2.2U 25V(+-10%,X5R,0402)'                            | 'CHIP0402'     | ''          | ''   | '20150729'
 '0.1UF'    | '100V'  | '10%'     | 'C0603'     | 'X7R'     | 'CH4108K1904'(!)   = ''              | ''                 | ''       | 'CH4108K1904'     |'C0603'| '(SMC0603AW)'                                                        | '0.1UF'    | '100V'        | '10%'    | 'DISCRETE' | 'CAP CHIP 0.1U 100V(+-10%,X7R,0603)SAM'                        | 'CHIP0603'     | ''          | ''   | '20190828'
 '0.1UF'    | '100V'  | '10%'     | 'C0603'     | 'EMPTY'   | 'CH4108K1904'(!)   = ''              | ''                 | ''       | 'CH4108K1904'     |'C0603'| '(SMC0603AW)'                                                        | 'NA'       | '100V'        | '10%'    | 'IO'       | 'CAP CHIP 0.1U 100V(+-10%,X7R,0603)SAM'                        | 'CHIP0603'     | ''          | ''   | '20190828'
 '1.8PF'    | '50V'   | '0.25PF'  | 'C0402'     | 'NPO'     | 'CH-1806TB07'(!)   = 'End of Design' | 'Comp-Approve'     | ''       | 'CH-1806TB07'     |'C0402'| '(C0402-0201)'                                                       | '1.8PF'    | '50V'         | '0.25PF' | 'DISCRETE' | 'CAP CHIP 1.8P 50V(+-0.25P,NPO,0402)'                          | 'CHIP0402'     | ''          | ''   | '20190906'
 '1.8PF'    | '50V'   | '0.25PF'  | 'C0402'     | 'EMPTY'   | 'CH-1806TB07'(!)   = 'End of Design' | 'Comp-Approve'     | ''       | 'CH-1806TB07'     |'C0402'| '(C0402-0201)'                                                       | 'NA'       | '50V'         | '0.25PF' | 'IO'       | 'CAP CHIP 1.8P 50V(+-0.25P,NPO,0402)'                          | 'CHIP0402'     | ''          | ''   | '20190906'
 '47NF'     | '50V'   | '10%'     | 'C0402'     | 'X7R'     | 'CH3476K1B00'(!)   = ''              | ''                 | ''       | 'CH3476K1B00'     |'C0402'| '(C0402-0201,C0402_OCTAGONXA)'                                       | '47NF'     | '50V'         | '10%'    | 'DISCRETE' | 'CAP CHIP 47NF 50V(+-10%,X7R,0402)'                            | 'CHIP0402'     | ''          | ''   | '20190925'
 '47NF'     | '50V'   | '10%'     | 'C0402'     | 'EMPTY'   | 'CH3476K1B00'(!)   = ''              | ''                 | ''       | 'CH3476K1B00'     |'C0402'| '(C0402-0201,C0402_OCTAGONXA)'                                       | 'NA'       | '50V'         | '10%'    | 'IO'       | 'CAP CHIP 47NF 50V(+-10%,X7R,0402)'                            | 'CHIP0402'     | ''          | ''   | '20190925'
 '100NF'    | '50V'   | '10%'     | 'C0402'     | 'X7R'     | 'CH4106K1B21'(!)   = ''              | ''                 | ''       | 'CH4106K1B21'     |'C0402_H28'| '(C0402-0201_H28)'                                                   | '100NF'    | '50V'         | '10%'    | 'DISCRETE' | 'CAP CHIP 100NF 50V(+-10%,X7R,0402)WTC'                        | 'CHIP0402'     | ''          | ''   | '20191021'
 '100NF'    | '50V'   | '10%'     | 'C0402'     | 'EMPTY'   | 'CH4106K1B21'(!)   = ''              | ''                 | ''       | 'CH4106K1B21'     |'C0402_H28'| '(C0402-0201_H28)'                                                   | 'NA'       | '50V'         | '10%'    | 'IO'       | 'CAP CHIP 100NF 50V(+-10%,X7R,0402)WTC'                        | 'CHIP0402'     | ''          | ''   | '20191021'
 '100NF'    | '50V'   | '10%'     | 'C0402'     | 'X7R'     | 'CH4106K1B20'(!)   = ''              | ''                 | ''       | 'CH4106K1B20'     |'C0402'| '(C0402-0201)'                                                       | '100NF'    | '50V'         | '10%'    | 'DISCRETE' | 'CAP CHIP 100NF 50V(+-10%,X7R,0402)SAM'                        | 'CHIP0402'     | ''          | ''   | '20191025'
 '100NF'    | '50V'   | '10%'     | 'C0402'     | 'EMPTY'   | 'CH4106K1B20'(!)   = ''              | ''                 | ''       | 'CH4106K1B20'     |'C0402'| '(C0402-0201)'                                                       | 'NA'       | '50V'         | '10%'    | 'IO'       | 'CAP CHIP 100NF 50V(+-10%,X7R,0402)SAM'                        | 'CHIP0402'     | ''          | ''   | '20191025'
 '390PF'    | '50V'   | '5%'      | 'C0402'     | 'X7R'     | 'CH13906JB16'(!)   = ''              | ''                 | ''       | 'CH13906JB16'     |'C0402'| '(C0402-0201)'                                                       | '390PF'    | '50V'         | '5%'     | 'DISCRETE' | 'CAP CHIP 390P 50V(+-5%,X7R,0402)'                             | 'CHIP0402'     | ''          | ''   | '20191101'
 '390PF'    | '50V'   | '5%'      | 'C0402'     | 'EMPTY'   | 'CH13906JB16'(!)   = ''              | ''                 | ''       | 'CH13906JB16'     |'C0402'| '(C0402-0201)'                                                       | 'NA'       | '50V'         | '5%'     | 'IO'       | 'CAP CHIP 390P 50V(+-5%,X7R,0402)'                             | 'CHIP0402'     | ''          | ''   | '20191101'
 '0.01UF'   | '100V'  | '10%'     | 'C0603'     | 'X7R'     | 'CH3108K1904'(!)   = ''              | ''                 | ''       | 'CH3108K1904'     |'C0603'| '(SMC0603AW)'                                                        | '0.01UF'   | '100V'        | '10%'    | 'DISCRETE' | 'CAP CHIP 0.01U 100V(+-10%,X7R,0603)MUR'                       | 'CHIP0603'     | ''          | ''   | '20191104'
 '0.01UF'   | '100V'  | '10%'     | 'C0603'     | 'EMPTY'   | 'CH3108K1904'(!)   = ''              | ''                 | ''       | 'CH3108K1904'     |'C0603'| '(SMC0603AW)'                                                        | 'NA'       | '100V'        | '10%'    | 'IO'       | 'CAP CHIP 0.01U 100V(+-10%,X7R,0603)MUR'                       | 'CHIP0603'     | ''          | ''   | '20191104'
 '0.01UF'   | '100V'  | '10%'     | 'C0603'     | 'X7R'     | 'CH3108K1905'(!)   = ''              | ''                 | ''       | 'CH3108K1905'     |'C0603'| '(SMC0603AW)'                                                        | '0.01UF'   | '100V'        | '10%'    | 'DISCRETE' | 'CAP CHIP 0.01U 100V(+-10%,X7R,0603)SAM'                       | 'CHIP0603'     | ''          | ''   | '20191108'
 '0.01UF'   | '100V'  | '10%'     | 'C0603'     | 'EMPTY'   | 'CH3108K1905'(!)   = ''              | ''                 | ''       | 'CH3108K1905'     |'C0603'| '(SMC0603AW)'                                                        | 'NA'       | '100V'        | '10%'    | 'IO'       | 'CAP CHIP 0.01U 100V(+-10%,X7R,0603)SAM'                       | 'CHIP0603'     | ''          | ''   | '20191108'
 '10UF'     | '50V'   | '10%'     | 'C1210'     | 'X7R'     | 'CH6106K1303'(!)   = ''              | ''                 | ''       | 'CH6106K1303'     |'C1210_GRM32E'| '(SMC1210AW)'                                                        | '10UF'     | '50V'         | '10%'    | 'DISCRETE' | 'CAP CHIP 10U 50V(+-10%,X7R,1210)MUR'                          | 'CHIP1210'     | ''          | ''   | '20191128'
 '10UF'     | '50V'   | '10%'     | 'C1210'     | 'EMPTY'   | 'CH6106K1303'(!)   = ''              | ''                 | ''       | 'CH6106K1303'     |'C1210_GRM32E'| '(SMC1210AW)'                                                        | 'NA'       | '50V'         | '10%'    | 'IO'       | 'CAP CHIP 10U 50V(+-10%,X7R,1210)MUR'                          | 'CHIP1210'     | ''          | ''   | '20191128'
 '4700PF'   | '50V'   | '5%'      | 'C0402'     | 'C0G'     | 'CH2476J0B01'(!)   = ''              | ''                 | ''       | 'CH2476J0B01'     |'C0402_H28'| '(C0402-0201_H28)'                                                   | '4700PF'   | '50V'         | '5%'     | 'DISCRETE' | 'CAP CHIP 4700P 50V(+-5%,C0G,0402)MUR'                         | 'CHIP0402'     | ''          | ''   | '20191128'
 '4700PF'   | '50V'   | '5%'      | 'C0402'     | 'EMPTY'   | 'CH2476J0B01'(!)   = ''              | ''                 | ''       | 'CH2476J0B01'     |'C0402_H28'| '(C0402-0201_H28)'                                                   | 'NA'       | '50V'         | '5%'     | 'IO'       | 'CAP CHIP 4700P 50V(+-5%,C0G,0402)MUR'                         | 'CHIP0402'     | ''          | ''   | '20191128'
 '2200PF'   | '50V'   | '5%'      | 'C0402'     | 'C0G'     | 'CH2226J0B01'(!)   = ''              | ''                 | ''       | 'CH2226J0B01'     |'C0402'| '(C0402-0201)'                                                       | '2200PF'   | '50V'         | '5%'     | 'DISCRETE' | 'CAP CHIP 2200P 50V(+-5%,C0G,0402)MUR'                         | 'CHIP0402'     | ''          | ''   | '20191128'
 '2200PF'   | '50V'   | '5%'      | 'C0402'     | 'EMPTY'   | 'CH2226J0B01'(!)   = ''              | ''                 | ''       | 'CH2226J0B01'     |'C0402'| '(C0402-0201)'                                                       | 'NA'       | '50V'         | '5%'     | 'IO'       | 'CAP CHIP 2200P 50V(+-5%,C0G,0402)MUR'                         | 'CHIP0402'     | ''          | ''   | '20191128'
 '1.1PF'    | '25V'   | '0.05PF'  | 'C0201'     | 'C0G'     | 'CH-114T0E00'(!)   = ''              | ''                 | ''       | 'CH-114T0E00'     |'C0201'| '(SMC0201AW)'                                                        | '1.1PF'    | '25V'         | '0.05PF' | 'DISCRETE' | 'CAPCHIP1.1PF25V(+-0.05PF,C0G,0201)HQ MUR'                     | 'CHIP0201'     | ''          | ''   | '20191210'
 '1.1PF'    | '25V'   | '0.05PF'  | 'C0201'     | 'EMPTY'   | 'CH-114T0E00'(!)   = ''              | ''                 | ''       | 'CH-114T0E00'     |'C0201'| '(SMC0201AW)'                                                        | 'NA'       | '25V'         | '0.05PF' | 'IO'       | 'CAPCHIP1.1PF25V(+-0.05PF,C0G,0201)HQ MUR'                     | 'CHIP0201'     | ''          | ''   | '20191210'
 '4.7UF'    | '100V'  | '10%'     | 'C1210'     | 'X7S'     | 'CH5478K6304'(!)   = ''              | ''                 | ''       | 'CH5478K6304'     |'C1210_HMK325'| '(SMC1210AW)'                                                        | '4.7UF'    | '100V'        | '10%'    | 'DISCRETE' | 'CAP CHIP 4.7U 100V(+-10%,X7S,1210)TAY'                        | 'CHIP1210'     | ''          | ''   | '20191210'
 '4.7UF'    | '100V'  | '10%'     | 'C1210'     | 'EMPTY'   | 'CH5478K6304'(!)   = ''              | ''                 | ''       | 'CH5478K6304'     |'C1210_HMK325'| '(SMC1210AW)'                                                        | 'NA'       | '100V'        | '10%'    | 'IO'       | 'CAP CHIP 4.7U 100V(+-10%,X7S,1210)TAY'                        | 'CHIP1210'     | ''          | ''   | '20191210'
 '12PF'     | '25V'   | '5%'      | 'C0201'     | 'NPO'     | 'CH0124J0E02'(!)   = ''              | ''                 | ''       | 'CH0124J0E02'     |'C0201'| '(SMC0201AW)'                                                        | '12PF'     | '25V'         | '5%'     | 'DISCRETE' | 'CAP CHIP 12PF 25V(+-5%,NPO,0201)'                             | 'CHIP0201'     | ''          | ''   | '20191210'
 '12PF'     | '25V'   | '5%'      | 'C0201'     | 'EMPTY'   | 'CH0124J0E02'(!)   = ''              | ''                 | ''       | 'CH0124J0E02'     |'C0201'| '(SMC0201AW)'                                                        | 'NA'       | '25V'         | '5%'     | 'IO'       | 'CAP CHIP 12PF 25V(+-5%,NPO,0201)'                             | 'CHIP0201'     | ''          | ''   | '20191210'
 '180PF'    | '50V'   | '5%'      | 'C0201'     | 'C0G'     | 'CH1186J0E00'(!)   = ''              | ''                 | ''       | 'CH1186J0E00'     |'C0201'| '(SMC0201AW)'                                                        | '180PF'    | '50V'         | '5%'     | 'DISCRETE' | 'CAP CHIP 180PF 50V(+-5%,C0G,0201)'                            | 'CHIP0201'     | ''          | ''   | '20191210'
 '180PF'    | '50V'   | '5%'      | 'C0201'     | 'EMPTY'   | 'CH1186J0E00'(!)   = ''              | ''                 | ''       | 'CH1186J0E00'     |'C0201'| '(SMC0201AW)'                                                        | 'NA'       | '50V'         | '5%'     | 'IO'       | 'CAP CHIP 180PF 50V(+-5%,C0G,0201)'                            | 'CHIP0201'     | ''          | ''   | '20191210'
 '15PF'     | '25V'   | '5%'      | 'C0201'     | 'COG'     | 'CH0154J0E03'(!)   = ''              | ''                 | ''       | 'CH0154J0E03'     |'C0201'| '(SMC0201AW)'                                                        | '15PF'     | '25V'         | '5%'     | 'DISCRETE' | 'CAP CHIP 15P 25V(+-5%,COG,0201)'                              | 'CHIP0201'     | ''          | ''   | '20191210'
 '15PF'     | '25V'   | '5%'      | 'C0201'     | 'EMPTY'   | 'CH0154J0E03'(!)   = ''              | ''                 | ''       | 'CH0154J0E03'     |'C0201'| '(SMC0201AW)'                                                        | 'NA'       | '25V'         | '5%'     | 'IO'       | 'CAP CHIP 15P 25V(+-5%,COG,0201)'                              | 'CHIP0201'     | ''          | ''   | '20191210'
 '18PF'     | '25V'   | '5%'      | 'C0201'     | 'COG'     | 'CH0184J0E04'(!)   = ''              | ''                 | ''       | 'CH0184J0E04'     |'C0201'| '(SMC0201AW)'                                                        | '18PF'     | '25V'         | '5%'     | 'DISCRETE' | 'CAP CHIP 18P 25V(+-5%,COG,0201)'                              | 'CHIP0201'     | ''          | ''   | '20191216'
 '18PF'     | '25V'   | '5%'      | 'C0201'     | 'EMPTY'   | 'CH0184J0E04'(!)   = ''              | ''                 | ''       | 'CH0184J0E04'     |'C0201'| '(SMC0201AW)'                                                        | 'NA'       | '25V'         | '5%'     | 'IO'       | 'CAP CHIP 18P 25V(+-5%,COG,0201)'                              | 'CHIP0201'     | ''          | ''   | '20191216'
 '33PF'     | '25V'   | '5%'      | 'C0201'     | 'COG'     | 'CH0334J0E01'(!)   = ''              | ''                 | ''       | 'CH0334J0E01'     |'C0201'| '(SMC0201AW)'                                                        | '33PF'     | '25V'         | '5%'     | 'DISCRETE' | 'CAP CHIP 33P 25V(+-5%,COG,0201)'                              | 'CHIP0201'     | ''          | ''   | '20191217'
 '33PF'     | '25V'   | '5%'      | 'C0201'     | 'EMPTY'   | 'CH0334J0E01'(!)   = ''              | ''                 | ''       | 'CH0334J0E01'     |'C0201'| '(SMC0201AW)'                                                        | 'NA'       | '25V'         | '5%'     | 'IO'       | 'CAP CHIP 33P 25V(+-5%,COG,0201)'                              | 'CHIP0201'     | ''          | ''   | '20191217'
 '5PF'      | '25V'   | '0.25PF'  | 'C0201'     | 'NPO'     | 'CH-504T0E08'(!)   = 'End of Design' | 'Comp-Approve'     | ''       | 'CH-504T0E08'     |'C0201'| '(SMC0201AW)'                                                        | '5PF'      | '25V'         | '0.25PF' | 'DISCRETE' | 'CAP CHIP 5P 25V(+-0.25P,NPO,0201)'                            | 'CHIP0201'     | ''          | ''   | '20191212'
 '5PF'      | '25V'   | '0.25PF'  | 'C0201'     | 'EMPTY'   | 'CH-504T0E08'(!)   = 'End of Design' | 'Comp-Approve'     | ''       | 'CH-504T0E08'     |'C0201'| '(SMC0201AW)'                                                        | 'NA'       | '25V'         | '0.25PF' | 'IO'       | 'CAP CHIP 5P 25V(+-0.25P,NPO,0201)'                            | 'CHIP0201'     | ''          | ''   | '20191212'
 '6.8PF'    | '25V'   | '0.5PF'   | 'C0201'     | 'COG'     | 'CH-684T0E00'(!)   = ''              | ''                 | ''       | 'CH-684T0E00'     |'C0201'| '(SMC0201AW)'                                                        | '6.8PF'    | '25V'         | '0.5PF'  | 'DISCRETE' | 'CAP CHIP 6.8P 25V(+-0.5P,COG,0201)'                           | 'CHIP0201'     | ''          | ''   | '20191217'
 '6.8PF'    | '25V'   | '0.5PF'   | 'C0201'     | 'EMPTY'   | 'CH-684T0E00'(!)   = ''              | ''                 | ''       | 'CH-684T0E00'     |'C0201'| '(SMC0201AW)'                                                        | 'NA'       | '25V'         | '0.5PF'  | 'IO'       | 'CAP CHIP 6.8P 25V(+-0.5P,COG,0201)'                           | 'CHIP0201'     | ''          | ''   | '20191217'
 '1UF'      | '16V'   | '10%'     | 'C0402'     | 'X7R'     | 'CH5103K1B00'(!)   = 'End of Design' | 'Comp-Release Qty' | ''       | 'CH5103K1B00'     |'C0402_H28'| '(C0402-0201_H28)'                                                   | '1UF'      | '16V'         | '10%'    | 'DISCRETE' | 'CAP CHIP 1UF 16V(+-10%,X7R,0402)'                             | 'CHIP0402'     | ''          | ''   | '20191213'
 '1UF'      | '16V'   | '10%'     | 'C0402'     | 'EMPTY'   | 'CH5103K1B00'(!)   = 'End of Design' | 'Comp-Release Qty' | ''       | 'CH5103K1B00'     |'C0402_H28'| '(C0402-0201_H28)'                                                   | 'NA'       | '16V'         | '10%'    | 'IO'       | 'CAP CHIP 1UF 16V(+-10%,X7R,0402)'                             | 'CHIP0402'     | ''          | ''   | '20191213'
 '330PF'    | '50V'   | '5%'      | 'C0402'     | 'NPO'     | 'CH1336J0B01'(!)   = ''              | ''                 | ''       | 'CH1336J0B01'     |'C0402'| '(C0402-0201)'                                                       | '330PF'    | '50V'         | '5%'     | 'DISCRETE' | 'CAP CHIP 330P,50V(+-5%,NPO,0402)'                             | 'CHIP0402'     | ''          | ''   | '20191213'
 '330PF'    | '50V'   | '5%'      | 'C0402'     | 'EMPTY'   | 'CH1336J0B01'(!)   = ''              | ''                 | ''       | 'CH1336J0B01'     |'C0402'| '(C0402-0201)'                                                       | 'NA'       | '50V'         | '5%'     | 'IO'       | 'CAP CHIP 330P,50V(+-5%,NPO,0402)'                             | 'CHIP0402'     | ''          | ''   | '20191213'
 '5.0PF'    | '50V'   | '0.1PF'   | 'C0402'     | 'C0G'     | 'CH-506B0B00'(!)   = ''              | ''                 | ''       | 'CH-506B0B00'     |'C0402'| '(C0402-0201)'                                                       | '5.0PF'    | '50V'         | '0.1PF'  | 'DISCRETE' | 'CAP CHIP 5.0P 50V(+-0.1P,C0G,0402)'                           | 'CHIP0402'     | ''          | ''   | '20191213'
 '5.0PF'    | '50V'   | '0.1PF'   | 'C0402'     | 'EMPTY'   | 'CH-506B0B00'(!)   = ''              | ''                 | ''       | 'CH-506B0B00'     |'C0402'| '(C0402-0201)'                                                       | 'NA'       | '50V'         | '0.1PF'  | 'IO'       | 'CAP CHIP 5.0P 50V(+-0.1P,C0G,0402)'                           | 'CHIP0402'     | ''          | ''   | '20191213'
 '2.2UF'    | '16V'   | '20%'     | 'C0603'     | 'X7R'     | 'CH5223M1900'(!)   = ''              | ''                 | ''       | 'CH5223M1900'     |'C0603_H40'| '(SMC0603AW)'                                                        | '2.2UF'    | '16V'         | '20%'    | 'DISCRETE' | 'CAP CHIP 2.2UF 16V(20%,X7R,0603)'                             | 'CHIP0603'     | ''          | ''   | '20191216'
 '2.2UF'    | '16V'   | '20%'     | 'C0603'     | 'EMPTY'   | 'CH5223M1900'(!)   = ''              | ''                 | ''       | 'CH5223M1900'     |'C0603_H40'| '(SMC0603AW)'                                                        | 'NA'       | '16V'         | '20%'    | 'IO'       | 'CAP CHIP 2.2UF 16V(20%,X7R,0603)'                             | 'CHIP0603'     | ''          | ''   | '20191216'
 '47000PF'  | '100V'  | '5%'      | 'C1206'     | 'C0G'     | 'CH3478J0200'(!)   = ''              | ''                 | ''       | 'CH3478J0200'     |'C1206XG'| '(SMC1206AW)'                                                        | '47000PF'  | '100V'        | '5%'     | 'DISCRETE' | 'CAP CHIP 47000P 100V(+-5%,C0G,1206)MUR'                       | 'CHIP1206'     | ''          | ''   | '20191220'
 '47000PF'  | '100V'  | '5%'      | 'C1206'     | 'EMPTY'   | 'CH3478J0200'(!)   = ''              | ''                 | ''       | 'CH3478J0200'     |'C1206XG'| '(SMC1206AW)'                                                        | 'NA'       | '100V'        | '5%'     | 'IO'       | 'CAP CHIP 47000P 100V(+-5%,C0G,1206)MUR'                       | 'CHIP1206'     | ''          | ''   | '20191220'
 '27PF'     | '25V'   | '5%'      | 'C0201'     | 'NPO'     | 'CH0274J0E03'(!)   = ''              | ''                 | ''       | 'CH0274J0E03'     |'C0201'| '(SMC0201AW)'                                                        | '27PF'     | '25V'         | '5%'     | 'DISCRETE' | 'CAP CHIP 27PF 25V(+-5%,NPO,0201)'                             | 'CHIP0201'     | ''          | ''   | '20200109'
 '27PF'     | '25V'   | '5%'      | 'C0201'     | 'EMPTY'   | 'CH0274J0E03'(!)   = ''              | ''                 | ''       | 'CH0274J0E03'     |'C0201'| '(SMC0201AW)'                                                        | 'NA'       | '25V'         | '5%'     | 'IO'       | 'CAP CHIP 27PF 25V(+-5%,NPO,0201)'                             | 'CHIP0201'     | ''          | ''   | '20200109'
 '5600PF'   | '50V'   | '10%'     | 'C0402'     | 'X7R'     | 'CH2566K1B00'(!)   = 'End of Design' | 'Comp-Approve'     | ''       | 'CH2566K1B00'     |'C0402'| '(C0402-0201)'                                                       | '5600PF'   | '50V'         | '10%'    | 'DISCRETE' | 'CAP CHIP 5600PF 50V(+-10%,X7R,0402)'                          | 'CHIP0402'     | ''          | ''   | '20200107'
 '5600PF'   | '50V'   | '10%'     | 'C0402'     | 'EMPTY'   | 'CH2566K1B00'(!)   = 'End of Design' | 'Comp-Approve'     | ''       | 'CH2566K1B00'     |'C0402'| '(C0402-0201)'                                                       | 'NA'       | '50V'         | '10%'    | 'IO'       | 'CAP CHIP 5600PF 50V(+-10%,X7R,0402)'                          | 'CHIP0402'     | ''          | ''   | '20200107'
 '39PF'     | '50V'   | '5%'      | 'C0402'     | 'NPO'     | 'CH0396J0B04'(!)   = ''              | ''                 | ''       | 'CH0396J0B04'     |'C0402'| '(C0402-0201)'                                                       | '39PF'     | '50V'         | '5%'     | 'DISCRETE' | 'CAP CHIP 39P 50V(+-5%,NPO,0402)MUR'                           | 'CHIP0402'     | ''          | ''   | '20200218'
 '39PF'     | '50V'   | '5%'      | 'C0402'     | 'EMPTY'   | 'CH0396J0B04'(!)   = ''              | ''                 | ''       | 'CH0396J0B04'     |'C0402'| '(C0402-0201)'                                                       | 'NA'       | '50V'         | '5%'     | 'IO'       | 'CAP CHIP 39P 50V(+-5%,NPO,0402)MUR'                           | 'CHIP0402'     | ''          | ''   | '20200218'
 '8.2PF'    | '50V'   | '0.25PF'  | 'C0402'     | 'NPO'     | 'CH-826C0B05'(!)   = ''              | ''                 | ''       | 'CH-826C0B05'     |'C0402'| '(C0402-0201)'                                                       | '8.2PF'    | '50V'         | '0.25PF' | 'DISCRETE' | 'CAP CHIP 8.2P 50V(+-0.25P,NPO,0402)MUR'                       | 'CHIP0402'     | ''          | ''   | '20200218'
 '8.2PF'    | '50V'   | '0.25PF'  | 'C0402'     | 'EMPTY'   | 'CH-826C0B05'(!)   = ''              | ''                 | ''       | 'CH-826C0B05'     |'C0402'| '(C0402-0201)'                                                       | 'NA'       | '50V'         | '0.25PF' | 'IO'       | 'CAP CHIP 8.2P 50V(+-0.25P,NPO,0402)MUR'                       | 'CHIP0402'     | ''          | ''   | '20200218'
 '0.001UF'  | '50V'   | '10%'     | 'C0402'     | 'X7R'     | 'CH30106KB19'(!)   = 'End of Design' | 'Comp-Release Qty' | ''       | 'CH30106KB19'     |'C0402'| '(C0402-0201)'                                                       | '0.001UF'  | '50V'         | '10%'    | 'DISCRETE' | 'CAP CHIP 0.001U 50V(10%,X7R,0402)'                            | 'CHIP0402'     | ''          | ''   | '20200218'
 '0.001UF'  | '50V'   | '10%'     | 'C0402'     | 'EMPTY'   | 'CH30106KB19'(!)   = 'End of Design' | 'Comp-Release Qty' | ''       | 'CH30106KB19'     |'C0402'| '(C0402-0201)'                                                       | 'NA'       | '50V'         | '10%'    | 'IO'       | 'CAP CHIP 0.001U 50V(10%,X7R,0402)'                            | 'CHIP0402'     | ''          | ''   | '20200218'
 '0.22UF'   | '6.3V'  | '10%'     | 'C0201'     | 'X6S'     | 'CH4221KEE01'(!)   = ''              | ''                 | ''       | 'CH4221KEE01'     |'C0201'| '(SMC0201AW)'                                                        | '0.22UF'   | '6.3V'        | '10%'    | 'DISCRETE' | 'CAP CHIP 0.22UF 6.3V(+-10%,X6S,0201)MUR'                      | 'CHIP0201'     | ''          | ''   | '20200224'
 '0.22UF'   | '6.3V'  | '10%'     | 'C0201'     | 'EMPTY'   | 'CH4221KEE01'(!)   = ''              | ''                 | ''       | 'CH4221KEE01'     |'C0201'| '(SMC0201AW)'                                                        | 'NA'       | '6.3V'        | '10%'    | 'IO'       | 'CAP CHIP 0.22UF 6.3V(+-10%,X6S,0201)MUR'                      | 'CHIP0201'     | ''          | ''   | '20200224'
 '0.022UF'  | '250V'  | '20%'     | 'C0805'     | 'X7R'     | 'CH3220CMA17'(!)   = 'End of Design' | 'Comp-Approve'     | ''       | 'CH3220CMA17'     |'C0805_H57'| '(SMC0805AW)'                                                        | '0.022UF'  | '250V'        | '20%'    | 'DISCRETE' | 'CAP CHIP 0.022U 250V(+-20%,X7R,0805)'                         | 'CHIP0805'     | ''          | ''   | '20200303'
 '0.022UF'  | '250V'  | '20%'     | 'C0805'     | 'EMPTY'   | 'CH3220CMA17'(!)   = 'End of Design' | 'Comp-Approve'     | ''       | 'CH3220CMA17'     |'C0805_H57'| '(SMC0805AW)'                                                        | 'NA'       | '250V'        | '20%'    | 'IO'       | 'CAP CHIP 0.022U 250V(+-20%,X7R,0805)'                         | 'CHIP0805'     | ''          | ''   | '20200303'
 '47PF'     | '50V'   | '5%'      | 'C0402'     | 'NPO'     | 'CH0476J0B12'(!)   = ''              | ''                 | ''       | 'CH0476J0B12'     |'C0402'| '(C0402-0201)'                                                       | '47PF'     | '50V'         | '5%'     | 'DISCRETE' | 'CAP CHIP 47P 50V(+-5%,NPO,0402)MUR'                           | 'CHIP0402'     | ''          | ''   | '20200312'
 '47PF'     | '50V'   | '5%'      | 'C0402'     | 'EMPTY'   | 'CH0476J0B12'(!)   = ''              | ''                 | ''       | 'CH0476J0B12'     |'C0402'| '(C0402-0201)'                                                       | 'NA'       | '50V'         | '5%'     | 'IO'       | 'CAP CHIP 47P 50V(+-5%,NPO,0402)MUR'                           | 'CHIP0402'     | ''          | ''   | '20200312'
 '220PF'    | '100V'  | '10%'     | 'C0402'     | 'X7R'     | 'CH1228K1B01'(!)   = ''              | ''                 | ''       | 'CH1228K1B01'     |'C0402'| '(C0402-0201)'                                                       | '220PF'    | '100V'        | '10%'    | 'DISCRETE' | 'CAP CHIP 220PF 100V(+-10%,X7R,0402)MUR'                       | 'CHIP0402'     | ''          | ''   | '20200312'
 '220PF'    | '100V'  | '10%'     | 'C0402'     | 'EMPTY'   | 'CH1228K1B01'(!)   = ''              | ''                 | ''       | 'CH1228K1B01'     |'C0402'| '(C0402-0201)'                                                       | 'NA'       | '100V'        | '10%'    | 'IO'       | 'CAP CHIP 220PF 100V(+-10%,X7R,0402)MUR'                       | 'CHIP0402'     | ''          | ''   | '20200312'
 '5600PF'   | '50V'   | '10%'     | 'C0402'     | 'X7R'     | 'CH2566K1B09'(!)   = ''              | ''                 | ''       | 'CH2566K1B09'     |'C0402'| '(C0402-0201)'                                                       | '5600PF'   | '50V'         | '10%'    | 'DISCRETE' | 'CAP CHIP 5600P 50V(+-10%,X7R,0402)API'                        | 'CHIP0402'     | ''          | ''   | '20200312'
 '5600PF'   | '50V'   | '10%'     | 'C0402'     | 'EMPTY'   | 'CH2566K1B09'(!)   = ''              | ''                 | ''       | 'CH2566K1B09'     |'C0402'| '(C0402-0201)'                                                       | 'NA'       | '50V'         | '10%'    | 'IO'       | 'CAP CHIP 5600P 50V(+-10%,X7R,0402)API'                        | 'CHIP0402'     | ''          | ''   | '20200312'
 '0.022UF'  | '50V'   | '10%'     | 'C0603'     | 'X7R'     | 'CH3226K1908'(!)   = ''              | ''                 | ''       | 'CH3226K1908'     |'C0603'| '(SMC0603AW)'                                                        | '0.022UF'  | '50V'         | '10%'    | 'DISCRETE' | 'CAP CHIP 0.022U 50V(+-10%,X7R,0603)API'                       | 'CHIP0603'     | ''          | ''   | '20200313'
 '0.022UF'  | '50V'   | '10%'     | 'C0603'     | 'EMPTY'   | 'CH3226K1908'(!)   = ''              | ''                 | ''       | 'CH3226K1908'     |'C0603'| '(SMC0603AW)'                                                        | 'NA'       | '50V'         | '10%'    | 'IO'       | 'CAP CHIP 0.022U 50V(+-10%,X7R,0603)API'                       | 'CHIP0603'     | ''          | ''   | '20200313'
 '22UF'     | '25V'   | '20%'     | 'C0805'     | 'X5R'     | 'CH6224M9A05'(!)   = ''              | ''                 | ''       | 'CH6224M9A05'     |'C0805_H57'| '(SMC0805AW)'                                                        | '22UF'     | '25V'         | '20%'    | 'DISCRETE' | 'CAP CHIP 22U 25V(+-20%,X5R,0805)MUR'                          | 'CHIP0805'     | ''          | ''   | '20200313'
 '22UF'     | '25V'   | '20%'     | 'C0805'     | 'EMPTY'   | 'CH6224M9A05'(!)   = ''              | ''                 | ''       | 'CH6224M9A05'     |'C0805_H57'| '(SMC0805AW)'                                                        | 'NA'       | '25V'         | '20%'    | 'IO'       | 'CAP CHIP 22U 25V(+-20%,X5R,0805)MUR'                          | 'CHIP0805'     | ''          | ''   | '20200313'
 '10UF'     | '25V'   | '20%'     | 'C0603'     | 'X5R'     | 'CH6104M9905'(!)   = ''              | ''                 | ''       | 'CH6104M9905'     |'C0603_H40'| '(SMC0603AW)'                                                        | '10UF'     | '25V'         | '20%'    | 'DISCRETE' | 'CAP CHIP 10UF 25V(+-20%,X5R,0603)MUR'                         | 'CHIP0603'     | ''          | ''   | '20200313'
 '10UF'     | '25V'   | '20%'     | 'C0603'     | 'EMPTY'   | 'CH6104M9905'(!)   = ''              | ''                 | ''       | 'CH6104M9905'     |'C0603_H40'| '(SMC0603AW)'                                                        | 'NA'       | '25V'         | '20%'    | 'IO'       | 'CAP CHIP 10UF 25V(+-20%,X5R,0603)MUR'                         | 'CHIP0603'     | ''          | ''   | '20200313'
 '4.7UF'    | '25V'   | '10%'     | 'C0805'     | 'X7R'     | 'CH5474K1A04'(!)   = 'End of Design' | 'Comp-Approve'     | ''       | 'CH5474K1A04'     |'C0805_H57'| '(SMC0805AW)'                                                        | '4.7UF'    | '25V'         | '10%'    | 'DISCRETE' | 'CAP CHIP 4.7U 25V(+-10%,X7R,0805)MUR'                         | 'CHIP0805'     | ''          | ''   | '20200317'
 '4.7UF'    | '25V'   | '10%'     | 'C0805'     | 'EMPTY'   | 'CH5474K1A04'(!)   = 'End of Design' | 'Comp-Approve'     | ''       | 'CH5474K1A04'     |'C0805_H57'| '(SMC0805AW)'                                                        | 'NA'       | '25V'         | '10%'    | 'IO'       | 'CAP CHIP 4.7U 25V(+-10%,X7R,0805)MUR'                         | 'CHIP0805'     | ''          | ''   | '20200317'
 '220PF'    | '50V'   | '10%'     | 'C0402'     | 'X7R'     | 'CH1226K1B10'(!)   = ''              | ''                 | ''       | 'CH1226K1B10'     |'C0402'| '(C0402-0201)'                                                       | '220PF'    | '50V'         | '10%'    | 'DISCRETE' | 'CAP CHIP 220PF 50V(+-10%,X7R,0402)MUR'                        | 'CHIP0402'     | ''          | ''   | '20200317'
 '220PF'    | '50V'   | '10%'     | 'C0402'     | 'EMPTY'   | 'CH1226K1B10'(!)   = ''              | ''                 | ''       | 'CH1226K1B10'     |'C0402'| '(C0402-0201)'                                                       | 'NA'       | '50V'         | '10%'    | 'IO'       | 'CAP CHIP 220PF 50V(+-10%,X7R,0402)MUR'                        | 'CHIP0402'     | ''          | ''   | '20200317'
 '0.047UF'  | '16V'   | '10%'     | 'C0402'     | 'X7R'     | 'CH3473K1B10'(!)   = ''              | ''                 | ''       | 'CH3473K1B10'     |'C0402'| '(C0402-0201)'                                                       | '0.047UF'  | '16V'         | '10%'    | 'DISCRETE' | 'CAP CHIP 0.047U 16V(+-10%,X7R,0402)MUR'                       | 'CHIP0402'     | ''          | ''   | '20200318'
 '0.047UF'  | '16V'   | '10%'     | 'C0402'     | 'EMPTY'   | 'CH3473K1B10'(!)   = ''              | ''                 | ''       | 'CH3473K1B10'     |'C0402'| '(C0402-0201)'                                                       | 'NA'       | '16V'         | '10%'    | 'IO'       | 'CAP CHIP 0.047U 16V(+-10%,X7R,0402)MUR'                       | 'CHIP0402'     | ''          | ''   | '20200318'
 '4.7UF'    | '16V'   | '10%'     | 'C0603'     | 'X6S'     | 'CH5473KE903'(!)   = ''              | ''                 | ''       | 'CH5473KE903'     |'C0603_H40'| '(SMC0603AW)'                                                        | '4.7UF'    | '16V'         | '10%'    | 'DISCRETE' | 'CAP CHIP 4.7UF 16V(+-10%,X6S,0603)MUR'                        | 'CHIP0603'     | ''          | ''   | '20200318'
 '4.7UF'    | '16V'   | '10%'     | 'C0603'     | 'EMPTY'   | 'CH5473KE903'(!)   = ''              | ''                 | ''       | 'CH5473KE903'     |'C0603_H40'| '(SMC0603AW)'                                                        | 'NA'       | '16V'         | '10%'    | 'IO'       | 'CAP CHIP 4.7UF 16V(+-10%,X6S,0603)MUR'                        | 'CHIP0603'     | ''          | ''   | '20200318'
 '0.047UF'  | '50V'   | '10%'     | 'C0603'     | 'X7R'     | 'CH3476K1905'(!)   = ''              | ''                 | ''       | 'CH3476K1905'     |'C0603'| '(SMC0603AW)'                                                        | '0.047UF'  | '50V'         | '10%'    | 'DISCRETE' | 'CAP CHIP 0.047UF 50V(+-10%,X7R,0603)SAM'                      | 'CHIP0603'     | ''          | ''   | '20200318'
 '0.047UF'  | '50V'   | '10%'     | 'C0603'     | 'EMPTY'   | 'CH3476K1905'(!)   = ''              | ''                 | ''       | 'CH3476K1905'     |'C0603'| '(SMC0603AW)'                                                        | 'NA'       | '50V'         | '10%'    | 'IO'       | 'CAP CHIP 0.047UF 50V(+-10%,X7R,0603)SAM'                      | 'CHIP0603'     | ''          | ''   | '20200318'
 '5PF'      | '50V'   | '0.25PF'  | 'C0402'     | 'C0G'     | 'CH-506C0B04'(!)   = ''              | ''                 | ''       | 'CH-506C0B04'     |'C0402'| '(C0402-0201)'                                                       | '5PF'      | '50V'         | '0.25PF' | 'DISCRETE' | 'CAP CHIP 5P 50V(0.25P,C0G,0402)MUR'                           | 'CHIP0402'     | ''          | ''   | '20200319'
 '5PF'      | '50V'   | '0.25PF'  | 'C0402'     | 'EMPTY'   | 'CH-506C0B04'(!)   = ''              | ''                 | ''       | 'CH-506C0B04'     |'C0402'| '(C0402-0201)'                                                       | 'NA'       | '50V'         | '0.25PF' | 'IO'       | 'CAP CHIP 5P 50V(0.25P,C0G,0402)MUR'                           | 'CHIP0402'     | ''          | ''   | '20200319'
 '8.2PF'    | '50V'   | '0.25PF'  | 'C0402'     | 'NPO'     | 'CH-826C0B07'(!)   = ''              | ''                 | ''       | 'CH-826C0B07'     |'C0402'| '(C0402-0201)'                                                       | '8.2PF'    | '50V'         | '0.25PF' | 'DISCRETE' | 'CAP CHIP 8.2P 50V(+-0.25P,NPO,0402)YGO'                       | 'CHIP0402'     | ''          | ''   | '20200320'
 '8.2PF'    | '50V'   | '0.25PF'  | 'C0402'     | 'EMPTY'   | 'CH-826C0B07'(!)   = ''              | ''                 | ''       | 'CH-826C0B07'     |'C0402'| '(C0402-0201)'                                                       | 'NA'       | '50V'         | '0.25PF' | 'IO'       | 'CAP CHIP 8.2P 50V(+-0.25P,NPO,0402)YGO'                       | 'CHIP0402'     | ''          | ''   | '20200320'
 '39PF'     | '50V'   | '5%'      | 'C0402'     | 'NPO'     | 'CH0396J0B06'(!)   = ''              | ''                 | ''       | 'CH0396J0B06'     |'C0402'| '(C0402-0201)'                                                       | '39PF'     | '50V'         | '5%'     | 'DISCRETE' | 'CAP CHIP 39P 50V(+-5%,NPO,0402)YGO'                           | 'CHIP0402'     | ''          | ''   | '20200327'
 '39PF'     | '50V'   | '5%'      | 'C0402'     | 'EMPTY'   | 'CH0396J0B06'(!)   = ''              | ''                 | ''       | 'CH0396J0B06'     |'C0402'| '(C0402-0201)'                                                       | 'NA'       | '50V'         | '5%'     | 'IO'       | 'CAP CHIP 39P 50V(+-5%,NPO,0402)YGO'                           | 'CHIP0402'     | ''          | ''   | '20200327'
 '1200PF'   | '50V'   | '5%'      | 'C0402'     | 'C0G'     | 'CH2126J0B01'(!)   = 'End of Design' | 'Comp-Approve'     | ''       | 'CH2126J0B01'     |'C0402'| '(C0402-0201)'                                                       | '1200PF'   | '50V'         | '5%'     | 'DISCRETE' | 'CAP CHIP 1200P 50V(+-5%,C0G,0402)MUR'                         | 'CHIP0402'     | ''          | ''   | '20200331'
 '1200PF'   | '50V'   | '5%'      | 'C0402'     | 'EMPTY'   | 'CH2126J0B01'(!)   = 'End of Design' | 'Comp-Approve'     | ''       | 'CH2126J0B01'     |'C0402'| '(C0402-0201)'                                                       | 'NA'       | '50V'         | '5%'     | 'IO'       | 'CAP CHIP 1200P 50V(+-5%,C0G,0402)MUR'                         | 'CHIP0402'     | ''          | ''   | '20200331'
 '27PF'     | '50V'   | '5%'      | 'C0402'     | 'NPO'     | 'CH0276J0B09'(!)   = ''              | ''                 | ''       | 'CH0276J0B09'     |'C0402'| '(C0402-0201)'                                                       | '27PF'     | '50V'         | '5%'     | 'DISCRETE' | 'CAP CHIP 27P 50V(+-5%,NPO,0402)MUR'                           | 'CHIP0402'     | ''          | ''   | '20200331'
 '27PF'     | '50V'   | '5%'      | 'C0402'     | 'EMPTY'   | 'CH0276J0B09'(!)   = ''              | ''                 | ''       | 'CH0276J0B09'     |'C0402'| '(C0402-0201)'                                                       | 'NA'       | '50V'         | '5%'     | 'IO'       | 'CAP CHIP 27P 50V(+-5%,NPO,0402)MUR'                           | 'CHIP0402'     | ''          | ''   | '20200331'
 '10UF'     | '35V'   | '10%'     | 'C0805'     | 'X6S'     | 'CH6105KEA01'(!)   = 'End of Design' | 'Comp-Approve'     | ''       | 'CH6105KEA01'     |'C0805_H57'| '(SMC0805AW)'                                                        | '10UF'     | '35V'         | '10%'    | 'DISCRETE' | 'CAP CHIP 10UF 35V(+-10%,X6S,0805)'                            | 'CHIP0805'     | ''          | ''   | '20200410'
 '10UF'     | '35V'   | '10%'     | 'C0805'     | 'EMPTY'   | 'CH6105KEA01'(!)   = 'End of Design' | 'Comp-Approve'     | ''       | 'CH6105KEA01'     |'C0805_H57'| '(SMC0805AW)'                                                        | 'NA'       | '35V'         | '10%'    | 'IO'       | 'CAP CHIP 10UF 35V(+-10%,X6S,0805)'                            | 'CHIP0805'     | ''          | ''   | '20200410'
 '5600PF'   | '50V'   | '10%'     | 'C0402'     | 'X7R'     | 'CH2566K1B06'(!)   = ''              | ''                 | ''       | 'CH2566K1B06'     |'C0402'| '(C0402-0201)'                                                       | '5600PF'   | '50V'         | '10%'    | 'DISCRETE' | 'CAP CHIP 5600PF 50V(+-10%,X7R,0402)SAM'                       | 'CHIP0402'     | ''          | ''   | '20200410'
 '5600PF'   | '50V'   | '10%'     | 'C0402'     | 'EMPTY'   | 'CH2566K1B06'(!)   = ''              | ''                 | ''       | 'CH2566K1B06'     |'C0402'| '(C0402-0201)'                                                       | 'NA'       | '50V'         | '10%'    | 'IO'       | 'CAP CHIP 5600PF 50V(+-10%,X7R,0402)SAM'                       | 'CHIP0402'     | ''          | ''   | '20200410'
 '0.047UF'  | '50V'   | '10%'     | 'C0402'     | 'X7R'     | 'CH3476K1B10'(!)   = ''              | ''                 | ''       | 'CH3476K1B10'     |'C0402'| '(C0402-0201)'                                                       | '0.047UF'  | '50V'         | '10%'    | 'DISCRETE' | 'CAP CHIP 0.047UF 50V(+-10%,X7R,0402)MUR'                      | 'CHIP0402'     | ''          | ''   | '20200520'
 '0.047UF'  | '50V'   | '10%'     | 'C0402'     | 'EMPTY'   | 'CH3476K1B10'(!)   = ''              | ''                 | ''       | 'CH3476K1B10'     |'C0402'| '(C0402-0201)'                                                       | 'NA'       | '50V'         | '10%'    | 'IO'       | 'CAP CHIP 0.047UF 50V(+-10%,X7R,0402)MUR'                      | 'CHIP0402'     | ''          | ''   | '20200520'
 '0.022UF'  | '100V'  | '10%'     | 'C0805'     | 'X7R'     | 'CH3228K1A00'(!)   = 'End of Design' | 'Comp-Approve'     | ''       | 'CH3228K1A00'     |'C0805_H57'| '(SMC0805AW)'                                                        | '0.022UF'  | '100V'        | '10%'    | 'DISCRETE' | 'CAP CHIP 0.022UF 100V(+-10%,X7R,0805)SAM'                     | 'CHIP0805'     | ''          | ''   | '20200520'
 '0.022UF'  | '100V'  | '10%'     | 'C0805'     | 'EMPTY'   | 'CH3228K1A00'(!)   = 'End of Design' | 'Comp-Approve'     | ''       | 'CH3228K1A00'     |'C0805_H57'| '(SMC0805AW)'                                                        | 'NA'       | '100V'        | '10%'    | 'IO'       | 'CAP CHIP 0.022UF 100V(+-10%,X7R,0805)SAM'                     | 'CHIP0805'     | ''          | ''   | '20200520'
 '68NF'     | '50V'   | '10%'     | 'C0603'     | 'X7R'     | 'CH3686K1902'(!)   = ''              | ''                 | ''       | 'CH3686K1902'     |'C0603'| '(SMC0603AW)'                                                        | '68NF'     | '50V'         | '10%'    | 'DISCRETE' | 'CAP CHIP 68NF 50V(+-10%,X7R,0603)SAM'                         | 'CHIP0603'     | ''          | ''   | '20200527'
 '68NF'     | '50V'   | '10%'     | 'C0603'     | 'EMPTY'   | 'CH3686K1902'(!)   = ''              | ''                 | ''       | 'CH3686K1902'     |'C0603'| '(SMC0603AW)'                                                        | 'NA'       | '50V'         | '10%'    | 'IO'       | 'CAP CHIP 68NF 50V(+-10%,X7R,0603)SAM'                         | 'CHIP0603'     | ''          | ''   | '20200527'
 '0.01UF'   | '100V'  | '10%'     | 'C1206'     | 'X7R'     | 'CH3108K1200'(!)   = ''              | ''                 | ''       | 'CH3108K1200'     |'C1206XG_H38'| '(SMC1206AW)'                                                        | '0.01UF'   | '100V'        | '10%'    | 'DISCRETE' | 'CAP CHIP 0.01U 100V(+-10%,X7R,1206)MUR'                       | 'CHIP1206'     | ''          | ''   | '20200617'
 '0.01UF'   | '100V'  | '10%'     | 'C1206'     | 'EMPTY'   | 'CH3108K1200'(!)   = ''              | ''                 | ''       | 'CH3108K1200'     |'C1206XG_H38'| '(SMC1206AW)'                                                        | 'NA'       | '100V'        | '10%'    | 'IO'       | 'CAP CHIP 0.01U 100V(+-10%,X7R,1206)MUR'                       | 'CHIP1206'     | ''          | ''   | '20200617'
 '10UF'     | '4V'    | '20%'     | 'C0402'     | 'X6S'     | 'CH610KMEB09'(!)   = ''              | ''                 | ''       | 'CH610KMEB09'     |'C0402_H28'| '(C0402-0201_H28)'                                                   | '10UF'     | '4V'          | '20%'    | 'DISCRETE' | 'CAP CHIP 10U 4V(+-20%,X6S,0402)MUR'                           | 'CHIP0402'     | ''          | ''   | '20200807'
 '10UF'     | '4V'    | '20%'     | 'C0402'     | 'EMPTY'   | 'CH610KMEB09'(!)   = ''              | ''                 | ''       | 'CH610KMEB09'     |'C0402_H28'| '(C0402-0201_H28)'                                                   | 'NA'       | '4V'          | '20%'    | 'IO'       | 'CAP CHIP 10U 4V(+-20%,X6S,0402)MUR'                           | 'CHIP0402'     | ''          | ''   | '20200807'
 '4700PF'   | '50V'   | '5%'      | 'C0603'     | 'C0G'     | 'CH2476J0902'(!)   = ''              | ''                 | ''       | 'CH2476J0902'     |'C0603_H40'| '(SMC0603AW)'                                                        | '4700PF'   | '50V'         | '5%'     | 'DISCRETE' | 'CAP CHIP 4700P 50V(+-5%,C0G,0603)MUR'                         | 'CHIP0603'     | ''          | ''   | '20200813'
 '4700PF'   | '50V'   | '5%'      | 'C0603'     | 'EMPTY'   | 'CH2476J0902'(!)   = ''              | ''                 | ''       | 'CH2476J0902'     |'C0603_H40'| '(SMC0603AW)'                                                        | 'NA'       | '50V'         | '5%'     | 'IO'       | 'CAP CHIP 4700P 50V(+-5%,C0G,0603)MUR'                         | 'CHIP0603'     | ''          | ''   | '20200813'
 '6.8PF'    | '50V'   | '0.25PF'  | 'C0402'     | 'C0G'     | 'CH-686C0B04'(!)   = ''              | ''                 | ''       | 'CH-686C0B04'     |'C0402'| '(C0402-0201)'                                                       | '6.8PF'    | '50V'         | '0.25PF' | 'DISCRETE' | 'CAP CHIP 6.8P 50V(+-0.25P,C0G,0402)YGO'                       | 'CHIP0402'     | ''          | ''   | '20200824'
 '6.8PF'    | '50V'   | '0.25PF'  | 'C0402'     | 'EMPTY'   | 'CH-686C0B04'(!)   = ''              | ''                 | ''       | 'CH-686C0B04'     |'C0402'| '(C0402-0201)'                                                       | 'NA'       | '50V'         | '0.25PF' | 'IO'       | 'CAP CHIP 6.8P 50V(+-0.25P,C0G,0402)YGO'                       | 'CHIP0402'     | ''          | ''   | '20200824'
 '22NF'     | '100V'  | '10%'     | 'C0805'     | 'X7R'     | 'CH3228K1A02'(!)   = ''              | ''                 | ''       | 'CH3228K1A02'     |'C0805_H43'| '(SMC0805AW)'                                                        | '22NF'     | '100V'        | '10%'    | 'DISCRETE' | 'CAP CHIP 22N 100V(+-10%,X7R,0805)YGO'                         | 'CHIP0805'     | ''          | ''   | '20200824'
 '22NF'     | '100V'  | '10%'     | 'C0805'     | 'EMPTY'   | 'CH3228K1A02'(!)   = ''              | ''                 | ''       | 'CH3228K1A02'     |'C0805_H43'| '(SMC0805AW)'                                                        | 'NA'       | '100V'        | '10%'    | 'IO'       | 'CAP CHIP 22N 100V(+-10%,X7R,0805)YGO'                         | 'CHIP0805'     | ''          | ''   | '20200824'
 '2.2UF'    | '16V'   | '10%'     | 'C0402'     | 'X6S'     | 'CH5223KEB01'(!)   = ''              | ''                 | ''       | 'CH5223KEB01'     |'C0402_H28'| '(C0402-0201_H28)'                                                   | '2.2UF'    | '16V'         | '10%'    | 'DISCRETE' | 'CAP CHIP 2.2U 16V(+-10%,X6S,0402)'                            | 'CHIP0402'     | ''          | ''   | '20200903'
 '2.2UF'    | '16V'   | '10%'     | 'C0402'     | 'EMPTY'   | 'CH5223KEB01'(!)   = ''              | ''                 | ''       | 'CH5223KEB01'     |'C0402_H28'| '(C0402-0201_H28)'                                                   | 'NA'       | '16V'         | '10%'    | 'IO'       | 'CAP CHIP 2.2U 16V(+-10%,X6S,0402)'                            | 'CHIP0402'     | ''          | ''   | '20200903'
 '75PF'     | '50V'   | '5%'      | 'C0402'     | 'C0G'     | 'CH0756J0B00'(!)   = 'End of Design' | 'Comp-Approve'     | ''       | 'CH0756J0B00'     |'C0402'| '(C0402-0201)'                                                       | '75PF'     | '50V'         | '5%'     | 'DISCRETE' | 'CAP CHIP 75PF 50V(+-5%,C0G,0402)'                             | 'CHIP0402'     | ''          | ''   | '20200909'
 '75PF'     | '50V'   | '5%'      | 'C0402'     | 'EMPTY'   | 'CH0756J0B00'(!)   = 'End of Design' | 'Comp-Approve'     | ''       | 'CH0756J0B00'     |'C0402'| '(C0402-0201)'                                                       | 'NA'       | '50V'         | '5%'     | 'IO'       | 'CAP CHIP 75PF 50V(+-5%,C0G,0402)'                             | 'CHIP0402'     | ''          | ''   | '20200909'
 '150PF'    | '50V'   | '5%'      | 'C0402'     | 'C0G'     | 'CH1156J0B00'(!)   = ''              | ''                 | ''       | 'CH1156J0B00'     |'C0402'| '(C0402-0201)'                                                       | '150PF'    | '50V'         | '5%'     | 'DISCRETE' | 'CAP CHIP 150P 50V(+-5%,0402,C0G)'                             | 'CHIP0402'     | ''          | ''   | '20200909'
 '150PF'    | '50V'   | '5%'      | 'C0402'     | 'EMPTY'   | 'CH1156J0B00'(!)   = ''              | ''                 | ''       | 'CH1156J0B00'     |'C0402'| '(C0402-0201)'                                                       | 'NA'       | '50V'         | '5%'     | 'IO'       | 'CAP CHIP 150P 50V(+-5%,0402,C0G)'                             | 'CHIP0402'     | ''          | ''   | '20200909'
 '51PF'     | '50V'   | '5%'      | 'C0402'     | 'NPO'     | 'CH0516J0B07'(!)   = ''              | ''                 | ''       | 'CH0516J0B07'     |'C0402'| '(C0402-0201)'                                                       | '51PF'     | '50V'         | '5%'     | 'DISCRETE' | 'CAP CHIP 51P 50V+-5% NPO(0402)'                               | 'CHIP0402'     | ''          | ''   | '20200914'
 '51PF'     | '50V'   | '5%'      | 'C0402'     | 'EMPTY'   | 'CH0516J0B07'(!)   = ''              | ''                 | ''       | 'CH0516J0B07'     |'C0402'| '(C0402-0201)'                                                       | 'NA'       | '50V'         | '5%'     | 'IO'       | 'CAP CHIP 51P 50V+-5% NPO(0402)'                               | 'CHIP0402'     | ''          | ''   | '20200914'
 '18PF'     | '50V'   | '2%'      | 'C0402'     | 'NP0'     | 'CH0186G0B00'(!)   = ''              | ''                 | ''       | 'CH0186G0B00'     |'C0402'| '(C0402-0201)'                                                       | '18PF'     | '50V'         | '2%'     | 'DISCRETE' | 'CAP CHIP 18PF 50V(+-2%,NP0,0402)H0.55'                        | 'CHIP0402'     | ''          | ''   | '20200914'
 '18PF'     | '50V'   | '2%'      | 'C0402'     | 'EMPTY'   | 'CH0186G0B00'(!)   = ''              | ''                 | ''       | 'CH0186G0B00'     |'C0402'| '(C0402-0201)'                                                       | 'NA'       | '50V'         | '2%'     | 'IO'       | 'CAP CHIP 18PF 50V(+-2%,NP0,0402)H0.55'                        | 'CHIP0402'     | ''          | ''   | '20200914'
 '0.3PF'    | '50V'   | '0.05PF'  | 'C0402'     | 'C0G'     | 'CH+306T0B00'(!)   = ''              | ''                 | ''       | 'CH+306T0B00'     |'C0402'| '(C0402-0201)'                                                       | '0.3PF'    | '50V'         | '0.05PF' | 'DISCRETE' | 'CAP CHIP 0.3P 50V(+-0.05P,C0G,0402)'                          | 'CHIP0402'     | ''          | ''   | '20200916'
 '0.3PF'    | '50V'   | '0.05PF'  | 'C0402'     | 'EMPTY'   | 'CH+306T0B00'(!)   = ''              | ''                 | ''       | 'CH+306T0B00'     |'C0402'| '(C0402-0201)'                                                       | 'NA'       | '50V'         | '0.05PF' | 'IO'       | 'CAP CHIP 0.3P 50V(+-0.05P,C0G,0402)'                          | 'CHIP0402'     | ''          | ''   | '20200916'
 '6.8PF'    | '50V'   | '0.5PF'   | 'C0603'     | 'NPO'     | 'CH-6806T901'(!)   = ''              | ''                 | ''       | 'CH-6806T901'     |'C0603'| '(SMC0603AW)'                                                        | '6.8PF'    | '50V'         | '0.5PF'  | 'DISCRETE' | 'CAP CHIP 6.8P 50V(+-0.5P 0603 NPO)'                           | 'CHIP0603'     | ''          | ''   | '20200916'
 '6.8PF'    | '50V'   | '0.5PF'   | 'C0603'     | 'EMPTY'   | 'CH-6806T901'(!)   = ''              | ''                 | ''       | 'CH-6806T901'     |'C0603'| '(SMC0603AW)'                                                        | 'NA'       | '50V'         | '0.5PF'  | 'IO'       | 'CAP CHIP 6.8P 50V(+-0.5P 0603 NPO)'                           | 'CHIP0603'     | ''          | ''   | '20200916'
 '0.2PF'    | '50V'   | '0.05PF'  | 'C0402'     | 'C0G'     | 'CH+206T0B00'(!)   = ''              | ''                 | ''       | 'CH+206T0B00'     |'C0402'| '(C0402-0201)'                                                       | '0.2PF'    | '50V'         | '0.05PF' | 'DISCRETE' | 'CAP CHIP 0.2P 50V(+-0.05P,C0G,0402)'                          | 'CHIP0402'     | ''          | ''   | '20200916'
 '0.2PF'    | '50V'   | '0.05PF'  | 'C0402'     | 'EMPTY'   | 'CH+206T0B00'(!)   = ''              | ''                 | ''       | 'CH+206T0B00'     |'C0402'| '(C0402-0201)'                                                       | 'NA'       | '50V'         | '0.05PF' | 'IO'       | 'CAP CHIP 0.2P 50V(+-0.05P,C0G,0402)'                          | 'CHIP0402'     | ''          | ''   | '20200916'
 '4.7UF'    | '25V'   | '10%'     | 'C0805'     | 'X5R'     | 'CH5474K9A01'(!)   = 'End of Design' | 'Comp-Release Qty' | ''       | 'CH5474K9A01'     |'C0805_H57'| '(SMC0805AW)'                                                        | '4.7UF'    | '25V'         | '10%'    | 'DISCRETE' | 'CAPACITOR CHIP 4.7U 25V(+-10% X5R 0805)'                      | 'CHIP0805'     | ''          | ''   | '20200916'
 '4.7UF'    | '25V'   | '10%'     | 'C0805'     | 'EMPTY'   | 'CH5474K9A01'(!)   = 'End of Design' | 'Comp-Release Qty' | ''       | 'CH5474K9A01'     |'C0805_H57'| '(SMC0805AW)'                                                        | 'NA'       | '100V'        | '10%'    | 'IO'       | 'CAPACITOR CHIP 4.7U 25V(+-10% X5R 0805)'                      | 'CHIP0805'     | ''          | ''   | '20200916'
 '0.5PF'    | '50V'   | '0.1PF'   | 'C0402'     | 'NPO'     | 'CH+5016TB01'(!)   = ''              | ''                 | ''       | 'CH+5016TB01'     |'C0402'| '(C0402-0201)'                                                       | '0.5PF'    | '50V'         | '0.1PF'  | 'DISCRETE' | 'CAP CHIP 0.5P 50V(+-0.1P,NPO,0402)'                           | 'CHIP0402'     | ''          | ''   | '20200918'
 '0.5PF'    | '50V'   | '0.1PF'   | 'C0402'     | 'EMPTY'   | 'CH+5016TB01'(!)   = ''              | ''                 | ''       | 'CH+5016TB01'     |'C0402'| '(C0402-0201)'                                                       | 'NA'       | '50V'         | '0.1PF'  | 'IO'       | 'CAP CHIP 0.5P 50V(+-0.1P,NPO,0402)'                           | 'CHIP0402'     | ''          | ''   | '20200918'
 '47UF'     | '25V'   | '20%'     | 'C1206'     | 'X5R'     | 'CH6474M9200'(!)   = 'End of Design' | 'Comp-Approve'     | ''       | 'CH6474M9200'     |'C1206XH'| '(SMC1206AW)'                                                        | '47UF'     | '25V'         | '20%'    | 'DISCRETE' | 'CAP CHIP 47U 25V(+-20%,X5R,1206)'                             | 'CHIP1206'     | ''          | ''   | '20200921'
 '47UF'     | '25V'   | '20%'     | 'C1206'     | 'EMPTY'   | 'CH6474M9200'(!)   = 'End of Design' | 'Comp-Approve'     | ''       | 'CH6474M9200'     |'C1206XH'| '(SMC1206AW)'                                                        | 'NA'       | '25V'         | '20%'    | 'IO'       | 'CAP CHIP 47U 25V(+-20%,X5R,1206)'                             | 'CHIP1206'     | ''          | ''   | '20200921'
 '10UF'     | '50V'   | '10%'     | 'C1206'     | 'X5R'     | 'CH6106K9201'(!)   = 'End of Design' | 'Comp-Release Qty' | ''       | 'CH6106K9201'     |'C1206XI'| '(SMC1206AW)'                                                        | '10UF'     | '50V'         | '10%'    | 'DISCRETE' | 'CAP CHIP 10UF 50V(+-10%,X5R,1206)'                            | 'CHIP1206'     | ''          | ''   | '20200923'
 '10UF'     | '50V'   | '10%'     | 'C1206'     | 'EMPTY'   | 'CH6106K9201'(!)   = 'End of Design' | 'Comp-Release Qty' | ''       | 'CH6106K9201'     |'C1206XI'| '(SMC1206AW)'                                                        | 'NA'       | '50V'         | '10%'    | 'IO'       | 'CAP CHIP 10UF 50V(+-10%,X5R,1206)'                            | 'CHIP1206'     | ''          | ''   | '20200923'
 '100UF'    | '10V'   | '20%'     | 'C1210'     | 'X5R'     | 'CH7102M9300'(!)   = 'End of Design' | 'Comp-Approve'     | ''       | 'CH7102M9300'     |'C1210_CL32A'| '(SMC1210AW)'                                                        | '100UF'    | '10V'         | '20%'    | 'DISCRETE' | 'CAP CHIP 100U 10V(+-20%,X5R,1210)H2.5'                        | 'CHIP1210'     | ''          | ''   | '20200923'
 '100UF'    | '10V'   | '20%'     | 'C1210'     | 'EMPTY'   | 'CH7102M9300'(!)   = 'End of Design' | 'Comp-Approve'     | ''       | 'CH7102M9300'     |'C1210_CL32A'| '(SMC1210AW)'                                                        | 'NA'       | '10V'         | '20%'    | 'IO'       | 'CAP CHIP 100U 10V(+-20%,X5R,1210)H2.5'                        | 'CHIP1210'     | ''          | ''   | '20200923'
 '4.7UF'    | '100V'  | '10%'     | 'C1206'     | 'X7S'     | 'CH5478K6201'(!)   = 'End of Design' | 'Comp-Approve'     | ''       | 'CH5478K6201'     |'C1206XB'| '(SMC1206AW)'                                                        | '4.7UF'    | '100V'        | '10%'    | 'DISCRETE' | 'CAP CHIP 4.7U 100V(10%,X7S,1206)'                             | 'CHIP1206'     | ''          | ''   | '20200925'
 '4.7UF'    | '100V'  | '10%'     | 'C1206'     | 'EMPTY'   | 'CH5478K6201'(!)   = 'End of Design' | 'Comp-Approve'     | ''       | 'CH5478K6201'     |'C1206XB'| '(SMC1206AW)'                                                        | 'NA'       | '100V'        | '10%'    | 'IO'       | 'CAP CHIP 4.7U 100V(10%,X7S,1206)'                             | 'CHIP1206'     | ''          | ''   | '20200925'
 '47UF'     | '6.3V'  | '20%'     | 'C0805'     | 'X6S'     | 'CH6471MEA02'(!)   = ''              | ''                 | ''       | 'CH6471MEA02'     |'C0805_H57'| '(C0805_BHS)'                                                        | '47UF'     | '6.3V'        | '20%'    | 'DISCRETE' | 'CAP CHIP 47U 6.3V(+-20%,X6S,0805)'                            | 'CHIP0805'     | ''          | ''   | '20200930'
 '47UF'     | '6.3V'  | '20%'     | 'C0805'     | 'EMPTY'   | 'CH6471MEA02'(!)   = ''              | ''                 | ''       | 'CH6471MEA02'     |'C0805_H57'| '(C0805_BHS)'                                                        | 'NA'       | '6.3V'        | '20%'    | 'IO'       | 'CAP CHIP 47U 6.3V(+-20%,X6S,0805)'                            | 'CHIP0805'     | ''          | ''   | '20200930'
 '4.7UF'    | '100V'  | '10%'     | 'C1206'     | 'X7R'     | 'CH5478K1201'(!)   = 'End of Design' | 'Comp-Approve'     | ''       | 'CH5478K1201'     |'C1206XB'| '(SMC1206AW)'                                                        | '4.7UF'    | '100V'        | '10%'    | 'DISCRETE' | 'CAP CHIP 4.7UF 100V(+-10%,X7R,1206)'                          | 'CHIP1206'     | ''          | ''   | '20201026'
 '4.7UF'    | '100V'  | '10%'     | 'C1206'     | 'EMPTY'   | 'CH5478K1201'(!)   = 'End of Design' | 'Comp-Approve'     | ''       | 'CH5478K1201'     |'C1206XB'| '(SMC1206AW)'                                                        | 'NA'       | '100V'        | '10%'    | 'IO'       | 'CAP CHIP 4.7UF 100V(+-10%,X7R,1206)'                          | 'CHIP1206'     | ''          | ''   | '20201026'
 '0.1UF'    | '25V'   | '10%'     | 'C0402'     | 'X7R'     | 'CH4104K1B13'(!)   = ''              | ''                 | ''       | 'CH4104K1B13'     |'C0402'| '(C0402-0201)'                                                       | '0.1UF'    | '25V'         | '10%'    | 'DISCRETE' | 'CAP CHIP 0.1U 25V(+-10%,X7R,0402)YGO'                         | 'CHIP0402'     | ''          | ''   | '20201223'
 '0.1UF'    | '25V'   | '10%'     | 'C0402'     | 'EMPTY'   | 'CH4104K1B13'(!)   = ''              | ''                 | ''       | 'CH4104K1B13'     |'C0402'| '(C0402-0201)'                                                       | 'NA'       | '25V'         | '10%'    | 'IO'       | 'CAP CHIP 0.1U 25V(+-10%,X7R,0402)YGO'                         | 'CHIP0402'     | ''          | ''   | '20201223'
 '33PF'     | '50V'   | '5%'      | 'C0402'     | 'NPO'     | 'CH0336J0B19'(!)   = ''              | ''                 | ''       | 'CH0336J0B19'     |'C0402'| '(C0402-0201)'                                                       | '33PF'     | '50V'         | '5%'     | 'DISCRETE' | 'CAP CHIP 33P 50V(+-5%,NPO,0402)YGO'                           | 'CHIP0402'     | ''          | ''   | '20201223'
 '33PF'     | '50V'   | '5%'      | 'C0402'     | 'EMPTY'   | 'CH0336J0B19'(!)   = ''              | ''                 | ''       | 'CH0336J0B19'     |'C0402'| '(C0402-0201)'                                                       | 'NA'       | '50V'         | '5%'     | 'IO'       | 'CAP CHIP 33P 50V(+-5%,NPO,0402)YGO'                           | 'CHIP0402'     | ''          | ''   | '20201223'
 '220PF'    | '50V'   | '5%'      | 'C0402'     | 'C0G'     | 'CH1226J0B04'(!)   = ''              | ''                 | ''       | 'CH1226J0B04'     |'C0402'| '(C0402-0201)'                                                       | '220PF'    | '50V'         | '5%'     | 'DISCRETE' | 'CAP CHIP 220P 50V(+-5%,C0G,0402)SAM'                          | 'CHIP0402'     | ''          | ''   | '20201223'
 '220PF'    | '50V'   | '5%'      | 'C0402'     | 'EMPTY'   | 'CH1226J0B04'(!)   = ''              | ''                 | ''       | 'CH1226J0B04'     |'C0402'| '(C0402-0201)'                                                       | 'NA'       | '50V'         | '5%'     | 'IO'       | 'CAP CHIP 220P 50V(+-5%,C0G,0402)SAM'                          | 'CHIP0402'     | ''          | ''   | '20201223'
 '0.01UF'   | '50V'   | '10%'     | 'C0603'     | 'X7R'     | 'CH3106K1921'(!)   = ''              | ''                 | ''       | 'CH3106K1921'     |'C0603'| '(SMC0603AW)'                                                        | '0.01UF'   | '50V'         | '10%'    | 'DISCRETE' | 'CAP CHIP 0.01U 50V(+-10%,X7R,0603)YGO'                        | 'CHIP0603'     | ''          | ''   | '20201223'
 '0.01UF'   | '50V'   | '10%'     | 'C0603'     | 'EMPTY'   | 'CH3106K1921'(!)   = ''              | ''                 | ''       | 'CH3106K1921'     |'C0603'| '(SMC0603AW)'                                                        | 'NA'       | '50V'         | '10%'    | 'IO'       | 'CAP CHIP 0.01U 50V(+-10%,X7R,0603)YGO'                        | 'CHIP0603'     | ''          | ''   | '20201223'
 '0.2PF'    | '50V'   | '0.1PF'   | 'C0603'     | 'NPO'     | 'CH+206B0900'(!)   = ''              | ''                 | ''       | 'CH+206B0900'     |'C0603'| '(SMC0603AW)'                                                        | '0.2PF'    | '50V'         | '0.1PF'  | 'DISCRETE' | 'CAP CHIP 0.2PF 50V(+-0.1P,NPO,0603)HQ'                        | 'CHIP0603'     | ''          | ''   | '20201223'
 '0.2PF'    | '50V'   | '0.1PF'   | 'C0603'     | 'EMPTY'   | 'CH+206B0900'(!)   = ''              | ''                 | ''       | 'CH+206B0900'     |'C0603'| '(SMC0603AW)'                                                        | 'NA'       | '50V'         | '0.1PF'  | 'IO'       | 'CAP CHIP 0.2PF 50V(+-0.1P,NPO,0603)HQ'                        | 'CHIP0603'     | ''          | ''   | '20201223'
 '5.6PF'    | '50V'   | '0.5PF'   | 'C0402'     | 'NPO'     | 'CH-566D0B01'(!)   = ''              | ''                 | ''       | 'CH-566D0B01'     |'C0402'| '(C0402-0201)'                                                       | '5.6PF'    | '50V'         | '0.5PF'  | 'DISCRETE' | 'CAP CHIP 5.6P 50V(+-0.5P,NPO,0402)'                           | 'CHIP0402'     | ''          | ''   | '20210126'
 '5.6PF'    | '50V'   | '0.5PF'   | 'C0402'     | 'EMPTY'   | 'CH-566D0B01'(!)   = ''              | ''                 | ''       | 'CH-566D0B01'     |'C0402'| '(C0402-0201)'                                                       | 'NA'       | '50V'         | '0.5PF'  | 'IO'       | 'CAP CHIP 5.6P 50V(+-0.5P,NPO,0402)'                           | 'CHIP0402'     | ''          | ''   | '20210126'
 '100UF'    | '6.3V'  | '20%'     | 'C1210'     | 'X6S'     | 'CH7101ME301'(!)   = ''              | ''                 | ''       | 'CH7101ME301'     |'C1210_CL32X'| '(SMC1210AW)'                                                        | '100UF'    | '6.3V'        | '20%'    | 'DISCRETE' | 'CAP CHIP 100U 6.3V(+-20%,X6S,1210)'                           | 'CHIP1210'     | ''          | ''   | '20210325'
 '100UF'    | '6.3V'  | '20%'     | 'C1210'     | 'EMPTY'   | 'CH7101ME301'(!)   = ''              | ''                 | ''       | 'CH7101ME301'     |'C1210_CL32X'| '(SMC1210AW)'                                                        | 'NA'       | '6.3V'        | '20%'    | 'IO'       | 'CAP CHIP 100U 6.3V(+-20%,X6S,1210)'                           | 'CHIP1210'     | ''          | ''   | '20210325'
 '330UF'    | '2.5V'  | '20%'     | 'C1210'     | 'X6S'     | 'CH733LME301'(!)   = ''              | ''                 | ''       | 'CH733LME301'     |'C1210_GRM32EXA'| '(SMC1210AW)'                                                        | '330UF'    | '2.5V'        | '20%'    | 'DISCRETE' | 'CAP CHIP 330UF 2.5V(+-20%,X6S,1210)'                          | 'CHIP1210'     | ''          | ''   | '20210407'
 '330UF'    | '2.5V'  | '20%'     | 'C1210'     | 'EMPTY'   | 'CH733LME301'(!)   = ''              | ''                 | ''       | 'CH733LME301'     |'C1210_GRM32EXA'| '(SMC1210AW)'                                                        | 'NA'       | '2.5V'        | '20%'    | 'IO'       | 'CAP CHIP 330UF 2.5V(+-20%,X6S,1210)'                          | 'CHIP1210'     | ''          | ''   | '20210407'
 '10UF'     | '4V'    | '20%'     | 'C0402'     | 'X6S'     | 'CH610KMEB10'(!)   = ''              | ''                 | ''       | 'CH610KMEB10'     |'C0402_H28'| '(C0402-0201_H28)'                                                   | '10UF'     | '4V'          | '20%'    | 'DISCRETE' | 'CAP CHIP 10U 4V(+-20%,X6S,0402)'                              | 'CHIP0402'     | ''          | ''   | '20210426'
 '10UF'     | '4V'    | '20%'     | 'C0402'     | 'EMPTY'   | 'CH610KMEB10'(!)   = ''              | ''                 | ''       | 'CH610KMEB10'     |'C0402_H28'| '(C0402-0201_H28)'                                                   | 'NA'       | '4V'          | '20%'    | 'IO'       | 'CAP CHIP 10U 4V(+-20%,X6S,0402)'                              | 'CHIP0402'     | ''          | ''   | '20210426'
 '220UF'    | '4V'    | '20%'     | 'C1206'     | 'X6S'     | 'CH722KME201'(!)   = ''              | ''                 | ''       | 'CH722KME201'     |'C1206XB'| '(SMC1206AW)'                                                        | '220UF'    | '4V'          | '20%'    | 'DISCRETE' | 'CAP CHIP 220U 4V(+-20%,X6S,1206)MUR'                          | 'CHIP1206'     | ''          | ''   | '20210426'
 '220UF'    | '4V'    | '20%'     | 'C1206'     | 'EMPTY'   | 'CH722KME201'(!)   = ''              | ''                 | ''       | 'CH722KME201'     |'C1206XB'| '(SMC1206AW)'                                                        | 'NA'       | '4V'          | '20%'    | 'IO'       | 'CAP CHIP 220U 4V(+-20%,X6S,1206)MUR'                          | 'CHIP1206'     | ''          | ''   | '20210426'
 '2.2UF'    | '6.3V'  | '20%'     | 'C0201'     | 'X5R'     | 'CH5221M9E07'(!)   = ''              | ''                 | ''       | 'CH5221M9E07'     |'C0201_H16'| '(C0201_HOME-PLATE_H22)'                                             | '2.2UF'    | '6.3V'        | '20%'    | 'DISCRETE' | 'CAP CHIP 2.2UF 6.3V(+-20%,X5R,0201)SAM'                       | 'CHIP0201'     | ''          | ''   | '20210429'
 '2.2UF'    | '6.3V'  | '20%'     | 'C0201'     | 'EMPTY'   | 'CH5221M9E07'(!)   = ''              | ''                 | ''       | 'CH5221M9E07'     |'C0201_H16'| '(C0201_HOME-PLATE_H22)'                                             | 'NA'       | '6.3V'        | '20%'    | 'IO'       | 'CAP CHIP 2.2UF 6.3V(+-20%,X5R,0201)SAM'                       | 'CHIP0201'     | ''          | ''   | '20210429'
 '10UF'     | '6.3V'  | '20%'     | 'C0402'     | 'X6S'     | 'CH6101MEB08'(!)   = ''              | ''                 | ''       | 'CH6101MEB08'     |'C0402_H28'| '(C0402-0201_H28)'                                                   | '10UF'     | '6.3V'        | '20%'    | 'DISCRETE' | 'CAP CHIP 10UF 6.3V(+-20%,X6S,0402)SAM'                        | 'CHIP0402'     | ''          | ''   | '20210506'
 '10UF'     | '6.3V'  | '20%'     | 'C0402'     | 'EMPTY'   | 'CH6101MEB08'(!)   = ''              | ''                 | ''       | 'CH6101MEB08'     |'C0402_H28'| '(C0402-0201_H28)'                                                   | 'NA'       | '6.3V'        | '20%'    | 'IO'       | 'CAP CHIP 10UF 6.3V(+-20%,X6S,0402)SAM'                        | 'CHIP0402'     | ''          | ''   | '20210506'
 '2.2UF'    | '6.3V'  | '20%'     | 'C0201'     | 'X5R'     | 'CH5221M9E00'(!)   = ''              | ''                 | ''       | 'CH5221M9E00'     |'C0201_H16'| '(SMC0201AW)'                                                        | '2.2UF'    | '6.3V'        | '20%'    | 'DISCRETE' | 'CAP CHIP 2.2UF 6.3V(+-20%,X5R,0201)'                          | 'CHIP0201'     | ''          | ''   | '20210507'
 '2.2UF'    | '6.3V'  | '20%'     | 'C0201'     | 'EMPTY'   | 'CH5221M9E00'(!)   = ''              | ''                 | ''       | 'CH5221M9E00'     |'C0201_H16'| '(SMC0201AW)'                                                        | 'NA'       | '6.3V'        | '20%'    | 'IO'       | 'CAP CHIP 2.2UF 6.3V(+-20%,X5R,0201)'                          | 'CHIP0201'     | ''          | ''   | '20210507'
 '10UF'     | '25V'   | '20%'     | 'C0805'     | 'X7S'     | 'CH6104M6A00'(!)   = ''              | ''                 | ''       | 'CH6104M6A00'     |'C0805_H57'| '(SMC0805AW)'                                                        | '10UF'     | '25V'         | '20%'    | 'DISCRETE' | 'CAP CHIP 10UF 25V(+-20%,X7S,0805)'                            | 'CHIP0805'     | ''          | ''   | '20210525'
 '10UF'     | '25V'   | '20%'     | 'C0805'     | 'EMPTY'   | 'CH6104M6A00'(!)   = ''              | ''                 | ''       | 'CH6104M6A00'     |'C0805_H57'| '(SMC0805AW)'                                                        | 'NA'       | '25V'         | '20%'    | 'IO'       | 'CAP CHIP 10UF 25V(+-20%,X7S,0805)'                            | 'CHIP0805'     | ''          | ''   | '20210525'
 '4.7UF'    | '25V'   | '10%'     | 'C0805'     | 'X7S'     | 'CH5474K6A01'(!)   = ''              | ''                 | ''       | 'CH5474K6A01'     |'C0805_H43'| '(SMC0805AW)'                                                        | '4.7UF'    | '25V'         | '10%'    | 'DISCRETE' | 'CAP CHIP 4.7U 25V(10%,X7S,0805)MUR'                           | 'CHIP0805'     | ''          | ''   | '20210525'
 '4.7UF'    | '25V'   | '10%'     | 'C0805'     | 'EMPTY'   | 'CH5474K6A01'(!)   = ''              | ''                 | ''       | 'CH5474K6A01'     |'C0805_H43'| '(SMC0805AW)'                                                        | 'NA'       | '25V'         | '10%'    | 'IO'       | 'CAP CHIP 4.7U 25V(10%,X7S,0805)MUR'                           | 'CHIP0805'     | ''          | ''   | '20210525'
 '0.027UF'  | '16V'   | '10%'     | 'C0402'     | 'X7R'     | 'CH3273K1B00'(!)   = ''              | ''                 | ''       | 'CH3273K1B00'     |'C0402'| '(C0402-0201)'                                                       | '0.027UF'  | '16V'         | '10%'    | 'DISCRETE' | 'CAP CHIP 0.027UF 16V(+-10%, X7R,0402)'                        | 'CHIP0402'     | ''          | ''   | '20210526'
 '0.027UF'  | '16V'   | '10%'     | 'C0402'     | 'EMPTY'   | 'CH3273K1B00'(!)   = ''              | ''                 | ''       | 'CH3273K1B00'     |'C0402'| '(C0402-0201)'                                                       | 'NA'       | '16V'         | '10%'    | 'IO'       | 'CAP CHIP 0.027UF 16V(+-10%, X7R,0402)'                        | 'CHIP0402'     | ''          | ''   | '20210526'
 '4700PF'   | '25V'   | '10%'     | 'C0201'     | 'X7R'     | 'CH2474K1E00'(!)   = ''              | ''                 | ''       | 'CH2474K1E00'     |'C0201'| '(SMC0201AW)'                                                        | '4700PF'   | '25V'         | '10%'    | 'DISCRETE' | 'CAP CHIP 4700P 25V(+-10%,X7R,0201)'                           | 'CHIP0201'     | ''          | ''   | '20210526'
 '4700PF'   | '25V'   | '10%'     | 'C0201'     | 'EMPTY'   | 'CH2474K1E00'(!)   = ''              | ''                 | ''       | 'CH2474K1E00'     |'C0201'| '(SMC0201AW)'                                                        | 'NA'       | '25V'         | '10%'    | 'IO'       | 'CAP CHIP 4700P 25V(+-10%,X7R,0201)'                           | 'CHIP0201'     | ''          | ''   | '20210526'
 '1UF'      | '10V'   | '20%'     | 'C0201'     | 'X6S'     | 'CH5102MEE02'(!)   = ''              | ''                 | ''       | 'CH5102MEE02'     |'C0201_H16'| '(SMC0201AW)'                                                        | '1UF'      | '10V'         | '20%'    | 'DISCRETE' | 'CAP CHIP 1UF 10V(20%,X6S,0201)'                               | 'CHIP0201'     | ''          | ''   | '20210531'
 '1UF'      | '10V'   | '20%'     | 'C0201'     | 'EMPTY'   | 'CH5102MEE02'(!)   = ''              | ''                 | ''       | 'CH5102MEE02'     |'C0201_H16'| '(SMC0201AW)'                                                        | 'NA'       | '10V'         | '20%'    | 'IO'       | 'CAP CHIP 1UF 10V(20%,X6S,0201)'                               | 'CHIP0201'     | ''          | ''   | '20210531'
 '4.7UF'    | '50V'   | '10%'     | 'C1206'     | 'X7R'     | 'CH5476K1207'(!)   = 'End of Design' | 'Comp-Approve'     | ''       | 'CH5476K1207'     |'C1206XG_H71'| '(SMC1206AW)'                                                        | '4.7UF'    | '50V'         | '10%'    | 'DISCRETE' | 'CAP CHIP 4.7U 50V(+-10%, X7R,1206,H1.6)'                      | 'CHIP1206'     | ''          | ''   | '20210609'
 '4.7UF'    | '50V'   | '10%'     | 'C1206'     | 'EMPTY'   | 'CH5476K1207'(!)   = 'End of Design' | 'Comp-Approve'     | ''       | 'CH5476K1207'     |'C1206XG_H71'| '(SMC1206AW)'                                                        | 'NA'       | '50V'         | '10%'    | 'IO'       | 'CAP CHIP 4.7U 50V(+-10%, X7R,1206,H1.6)'                      | 'CHIP1206'     | ''          | ''   | '20210609'
 '100UF'    | '6.3V'  | '20%'     | 'C1206'     | 'X6S'     | 'CH7101ME200'(!)   = 'End of Design' | 'Comp-Release Qty' | ''       | 'CH7101ME200'     |'C1206XE'| '(SMC1206AW)'                                                        | '100UF'    | '6.3V'        | '20%'    | 'DISCRETE' | 'CAP CHIP 100UF 6.3V(+-20%,X6S,1206)'                          | 'CHIP1206'     | ''          | ''   | '20210609'
 '100UF'    | '6.3V'  | '20%'     | 'C1206'     | 'EMPTY'   | 'CH7101ME200'(!)   = 'End of Design' | 'Comp-Release Qty' | ''       | 'CH7101ME200'     |'C1206XE'| '(SMC1206AW)'                                                        | 'NA'       | '6.3V'        | '20%'    | 'IO'       | 'CAP CHIP 100UF 6.3V(+-20%,X6S,1206)'                          | 'CHIP1206'     | ''          | ''   | '20210609'
 '200PF'    | '50V'   | '5%'      | 'C0402'     | 'NPO'     | 'CH1206J0B00'(!)   = 'End of Design' | 'Comp-Approve'     | ''       | 'CH1206J0B00'     |'C0402'| '(C0402-0201)'                                                       | '200PF'    | '50V'         | '5%'     | 'DISCRETE' | 'CAP CHIP 200P 50V(+-5%,NPO,0402)'                             | 'CHIP0402'     | ''          | ''   | '20210616'
 '200PF'    | '50V'   | '5%'      | 'C0402'     | 'EMPTY'   | 'CH1206J0B00'(!)   = 'End of Design' | 'Comp-Approve'     | ''       | 'CH1206J0B00'     |'C0402'| '(C0402-0201)'                                                       | 'NA'       | '50V'         | '5%'     | 'IO'       | 'CAP CHIP 200P 50V(+-5%,NPO,0402)'                             | 'CHIP0402'     | ''          | ''   | '20210616'
 '0.01UF'   | '50V'   | '10%'     | 'C0402'     | 'X7R'     | 'CH3106K1B10'(!)   = ''              | ''                 | ''       | 'CH3106K1B10'     |'C0402'| '(C0402-0201)'                                                       | '0.01UF'   | '50V'         | '10%'    | 'DISCRETE' | 'CAP CHIP 0.01U 50V(+-10%,X7R,0402)MUR'                        | 'CHIP0402'     | ''          | ''   | '20210727'
 '0.01UF'   | '50V'   | '10%'     | 'C0402'     | 'EMPTY'   | 'CH3106K1B10'(!)   = ''              | ''                 | ''       | 'CH3106K1B10'     |'C0402'| '(C0402-0201)'                                                       | 'NA'       | '50V'         | '10%'    | 'IO'       | 'CAP CHIP 0.01U 50V(+-10%,X7R,0402)MUR'                        | 'CHIP0402'     | ''          | ''   | '20210727'
 '0.3PF'    | '50V'   | '0.1PF'   | 'C0603'     | 'NPO'     | 'CH+306B0900'(!)   = ''              | ''                 | ''       | 'CH+306B0900'     |'C0603'| '(SMC0603AW)'                                                        | '0.3PF'    | '50V'         | '0.1PF'  | 'DISCRETE' | 'CAP CHIP 0.3PF 50V(+-0.1P,NPO,0603)HQ'                        | 'CHIP0603'     | ''          | ''   | '20210809'
 '0.3PF'    | '50V'   | '0.1PF'   | 'C0603'     | 'EMPTY'   | 'CH+306B0900'(!)   = ''              | ''                 | ''       | 'CH+306B0900'     |'C0603'| '(SMC0603AW)'                                                        | 'NA'       | '50V'         | '0.1PF'  | 'IO'       | 'CAP CHIP 0.3PF 50V(+-0.1P,NPO,0603)HQ'                        | 'CHIP0603'     | ''          | ''   | '20210809'
 '0.1UF'    | '50V'   | '10%'     | 'C0603'     | 'X7R'     | 'CH4106K1912'(!)   = 'End of Design' | 'Comp-Approve'     | ''       | 'CH4106K1912'     |'C0603'| '(SMC0603AW)'                                                        | '0.1UF'    | '50V'         | '10%'    | 'DISCRETE' | 'CAP CHIP 0.1U 50V(+-10%,X7R,0603)SAM'                         | 'CHIP0603'     | ''          | ''   | '20210812'
 '0.1UF'    | '50V'   | '10%'     | 'C0603'     | 'EMPTY'   | 'CH4106K1912'(!)   = 'End of Design' | 'Comp-Approve'     | ''       | 'CH4106K1912'     |'C0603'| '(SMC0603AW)'                                                        | 'NA'       | '50V'         | '10%'    | 'IO'       | 'CAP CHIP 0.1U 50V(+-10%,X7R,0603)SAM'                         | 'CHIP0603'     | ''          | ''   | '20210812'
 '47PF'     | '50V'   | '1%'      | 'C0402'     | 'NPO'     | 'CH0476F0B00'(!)   = ''              | ''                 | ''       | 'CH0476F0B00'     |'C0402'| '(C0402-0201)'                                                       | '47PF'     | '50V'         | '1%'     | 'DISCRETE' | 'CAP CHIP 47P 50V(+-1%,NPO,0402)'                              | 'CHIP0402'     | ''          | ''   | '20210817'
 '47PF'     | '50V'   | '1%'      | 'C0402'     | 'EMPTY'   | 'CH0476F0B00'(!)   = ''              | ''                 | ''       | 'CH0476F0B00'     |'C0402'| '(C0402-0201)'                                                       | 'NA'       | '50V'         | '1%'     | 'IO'       | 'CAP CHIP 47P 50V(+-1%,NPO,0402)'                              | 'CHIP0402'     | ''          | ''   | '20210817'
 '1000PF'   | '100V'  | '10%'     | 'C0402'     | 'X7R'     | 'CH2108K1B00'(!)   = ''              | ''                 | ''       | 'CH2108K1B00'     |'C0402'| '(C0402-0201)'                                                       | '1000PF'   | '100V'        | '10%'    | 'DISCRETE' | 'CAP CHIP 1000P 100V(+-10%,X7R,0402)'                          | 'CHIP0402'     | ''          | ''   | '20210817'
 '1000PF'   | '100V'  | '10%'     | 'C0402'     | 'EMPTY'   | 'CH2108K1B00'(!)   = ''              | ''                 | ''       | 'CH2108K1B00'     |'C0402'| '(C0402-0201)'                                                       | 'NA'       | '100V'        | '10%'    | 'IO'       | 'CAP CHIP 1000P 100V(+-10%,X7R,0402)'                          | 'CHIP0402'     | ''          | ''   | '20210817'
 '0.1UF'    | '1KV'   | '10%'     | 'C2220'     | 'X7R'     | 'CH410FK1F00'(!)   = ''              | ''                 | ''       | 'CH410FK1F00'     |'C2220XB'| '(SMC2220AW)'                                                        | '0.1UF'    | '1KV'         | '10%'    | 'DISCRETE' | 'CAP CHIP 0.1U 1KV(+-10%,X7R,2220)H2.5'                        | 'CHIP2220'     | ''          | ''   | '20210823'
 '0.1UF'    | '1KV'   | '10%'     | 'C2220'     | 'EMPTY'   | 'CH410FK1F00'(!)   = ''              | ''                 | ''       | 'CH410FK1F00'     |'C2220XB'| '(SMC2220AW)'                                                        | 'NA'       | '1KV'         | '10%'    | 'IO'       | 'CAP CHIP 0.1U 1KV(+-10%,X7R,2220)H2.5'                        | 'CHIP2220'     | ''          | ''   | '20210823'
 '0.033UF'  | '100V'  | '10%'     | 'C0805'     | 'X7R'     | 'CH3338K1A00'(!)   = ''              | ''                 | ''       | 'CH3338K1A00'     |'C0805_H57'| '(SMC0805AW)'                                                        | '0.033UF'  | '100V'        | '10%'    | 'DISCRETE' | 'CAP CHIP 0.033U 100V(+-10%,X7R,0805)'                         | 'CHIP0805'     | ''          | ''   | '20210827'
 '0.033UF'  | '100V'  | '10%'     | 'C0805'     | 'EMPTY'   | 'CH3338K1A00'(!)   = ''              | ''                 | ''       | 'CH3338K1A00'     |'C0805_H57'| '(SMC0805AW)'                                                        | 'NA'       | '100V'        | '10%'    | 'IO'       | 'CAP CHIP 0.033U 100V(+-10%,X7R,0805)'                         | 'CHIP0805'     | ''          | ''   | '20210827'
 '0.022UF'  | '50V'   | '10%'     | 'C0402'     | 'X7R'     | 'CH3226K1B00'(!)   = ''              | ''                 | ''       | 'CH3226K1B00'     |'C0402'| '(C0402-0201)'                                                       | '0.022UF'  | '50V'         | '10%'    | 'DISCRETE' | 'CAP CHIP 0.022U 50V(+-10%,X7R,0402)'                          | 'CHIP0402'     | ''          | ''   | '20210909'
 '0.022UF'  | '50V'   | '10%'     | 'C0402'     | 'EMPTY'   | 'CH3226K1B00'(!)   = ''              | ''                 | ''       | 'CH3226K1B00'     |'C0402'| '(C0402-0201)'                                                       | 'NA'       | '50V'         | '10%'    | 'IO'       | 'CAP CHIP 0.022U 50V(+-10%,X7R,0402)'                          | 'CHIP0402'     | ''          | ''   | '20210909'
 '0.33UF'   | '10V'   | '10%'     | 'C0402'     | 'X5R'     | 'CH4332K9B00'(!)   = ''              | ''                 | ''       | 'CH4332K9B00'     |'C0402'| '(C0402-0201)'                                                       | '0.33UF'   | '10V'         | '10%'    | 'DISCRETE' | 'CAP CHIP 0.33UF 10V(+-10%,X5R,0402)'                          | 'CHIP0402'     | ''          | ''   | '20211018'
 '0.33UF'   | '10V'   | '10%'     | 'C0402'     | 'EMPTY'   | 'CH4332K9B00'(!)   = ''              | ''                 | ''       | 'CH4332K9B00'     |'C0402'| '(C0402-0201)'                                                       | 'NA'       | '10V'         | '10%'    | 'IO'       | 'CAP CHIP 0.33UF 10V(+-10%,X5R,0402)'                          | 'CHIP0402'     | ''          | ''   | '20211018'
 '10UF'     | '10V'   | '10%'     | 'C0805'     | 'X7R'     | 'CH6102K1A05'(!)   = ''              | ''                 | ''       | 'CH6102K1A05'     |'C0805_H57'| '(SMC0805AW)'                                                        | '10UF'     | '10V'         | '10%'    | 'DISCRETE' | 'CAP CHIP 10U 10V(+-10%,X7R,0805)YGO'                          | 'CHIP0805'     | ''          | ''   | '20211115'
 '10UF'     | '10V'   | '10%'     | 'C0805'     | 'EMPTY'   | 'CH6102K1A05'(!)   = ''              | ''                 | ''       | 'CH6102K1A05'     |'C0805_H57'| '(SMC0805AW)'                                                        | 'NA'       | '10V'         | '10%'    | 'IO'       | 'CAP CHIP 10U 10V(+-10%,X7R,0805)YGO'                          | 'CHIP0805'     | ''          | ''   | '20211115'
 '100PF'    | '50V'   | '5%'      | 'C0402'     | 'NPO'     | 'CH1106J0B17'(!)   = ''              | ''                 | ''       | 'CH1106J0B17'     |'C0402'| '(C0402-0201)'                                                       | '100PF'    | '50V'         | '5%'     | 'DISCRETE' | 'CAP CHIP 100P 50V(+-5%,NPO,0402)SAM'                          | 'CHIP0402'     | ''          | ''   | '20211126'
 '100PF'    | '50V'   | '5%'      | 'C0402'     | 'EMPTY'   | 'CH1106J0B17'(!)   = ''              | ''                 | ''       | 'CH1106J0B17'     |'C0402'| '(C0402-0201)'                                                       | 'NA'       | '50V'         | '5%'     | 'IO'       | 'CAP CHIP 100P 50V(+-5%,NPO,0402)SAM'                          | 'CHIP0402'     | ''          | ''   | '20211126'
 '12PF'     | '50V'   | '5%'      | 'C0402'     | 'NP0'     | 'CH0126J0B16'(!)   = ''              | ''                 | ''       | 'CH0126J0B16'     |'C0402'| '(C0402-0201)'                                                       | '12PF'     | '50V'         | '5%'     | 'DISCRETE' | 'CAP CHIP 12P 50V(+-5%,NP0,0402)SAM'                           | 'CHIP0402'     | ''          | ''   | '20211129'
 '12PF'     | '50V'   | '5%'      | 'C0402'     | 'EMPTY'   | 'CH0126J0B16'(!)   = ''              | ''                 | ''       | 'CH0126J0B16'     |'C0402'| '(C0402-0201)'                                                       | 'NA'       | '50V'         | '5%'     | 'IO'       | 'CAP CHIP 12P 50V(+-5%,NP0,0402)SAM'                           | 'CHIP0402'     | ''          | ''   | '20211129'
 '1NF'      | '50V'   | '10%'     | 'C0402'     | 'X7R'     | 'CH2106K1B28'(!)   = ''              | ''                 | ''       | 'CH2106K1B28'     |'C0402'| '(C0402-0201)'                                                       | '1NF'      | '50V'         | '10%'    | 'DISCRETE' | 'CAP CHIP 1N 50V(+-10%,X7R,0402)SAM'                           | 'CHIP0402'     | ''          | ''   | '20211227'
 '1NF'      | '50V'   | '10%'     | 'C0402'     | 'EMPTY'   | 'CH2106K1B28'(!)   = ''              | ''                 | ''       | 'CH2106K1B28'     |'C0402'| '(C0402-0201)'                                                       | 'NA'       | '50V'         | '10%'    | 'IO'       | 'CAP CHIP 1N 50V(+-10%,X7R,0402)SAM'                           | 'CHIP0402'     | ''          | ''   | '20211227'
 '1.5UF'    | '25V'   | '10%'     | 'C0805'     | 'X7R'     | 'CH5154K1A05'(!)   = 'End of Design' | 'Comp-Approve'     | ''       | 'CH5154K1A05'     |'C0805_H57'| '(SMC0805AW)'                                                        | '1.5UF'    | '25V'         | '10%'    | 'DISCRETE' | 'CAP CHIP 1.5U 25V(10%,X7R,0805)H1.25'                         | 'CHIP0805'     | ''          | ''   | '20211227'
 '1.5UF'    | '25V'   | '10%'     | 'C0805'     | 'EMPTY'   | 'CH5154K1A05'(!)   = 'End of Design' | 'Comp-Approve'     | ''       | 'CH5154K1A05'     |'C0805_H57'| '(SMC0805AW)'                                                        | 'NA'       | '25V'         | '10%'    | 'IO'       | 'CAP CHIP 1.5U 25V(10%,X7R,0805)H1.25'                         | 'CHIP0805'     | ''          | ''   | '20211227'
 '0.5PF'    | '250V'  | '0.1PF'   | 'C0603'     | 'C0G'     | 'CH+50CB0900'(!)   = ''              | ''                 | ''       | 'CH+50CB0900'     |'C0603'| '(SMC0603AW)'                                                        | '0.5PF'    | '250V'        | '0.1PF'  | 'DISCRETE' | 'CAP CHIP 0.5P 250V(+-0.1P,C0G,0603)HQ'                        | 'CHIP0603'     | ''          | ''   | '20220106'
 '0.5PF'    | '250V'  | '0.1PF'   | 'C0603'     | 'EMPTY'   | 'CH+50CB0900'(!)   = ''              | ''                 | ''       | 'CH+50CB0900'     |'C0603'| '(SMC0603AW)'                                                        | 'NA'       | '250V'        | '0.1PF'  | 'IO'       | 'CAP CHIP 0.5P 250V(+-0.1P,C0G,0603)HQ'                        | 'CHIP0603'     | ''          | ''   | '20220106'
 '1.2PF'    | '250V'  | '0.1PF'   | 'C0603'     | 'C0G'     | 'CH-12CB0900'(!)   = ''              | ''                 | ''       | 'CH-12CB0900'     |'C0603'| '(SMC0603AW)'                                                        | '1.2PF'    | '250V'        | '0.1PF'  | 'DISCRETE' | 'CAP CHIP 1.2P 250V(+-0.1P,C0G,0603)HQ'                        | 'CHIP0603'     | ''          | ''   | '20220106'
 '1.2PF'    | '250V'  | '0.1PF'   | 'C0603'     | 'EMPTY'   | 'CH-12CB0900'(!)   = ''              | ''                 | ''       | 'CH-12CB0900'     |'C0603'| '(SMC0603AW)'                                                        | 'NA'       | '250V'        | '0.1PF'  | 'IO'       | 'CAP CHIP 1.2P 250V(+-0.1P,C0G,0603)HQ'                        | 'CHIP0603'     | ''          | ''   | '20220106'
 '8.2PF'    | '250V'  | '0.25PF'  | 'C0603'     | 'C0G'     | 'CH-82CC0900'(!)   = ''              | ''                 | ''       | 'CH-82CC0900'     |'C0603'| '(SMC0603AW)'                                                        | '8.2PF'    | '250V'        | '0.25PF' | 'DISCRETE' | 'CAP CHIP 8.2P 250V(+-0.25P,C0G,0603)HQ'                       | 'CHIP0603'     | ''          | ''   | '20220106'
 '8.2PF'    | '250V'  | '0.25PF'  | 'C0603'     | 'EMPTY'   | 'CH-82CC0900'(!)   = ''              | ''                 | ''       | 'CH-82CC0900'     |'C0603'| '(SMC0603AW)'                                                        | 'NA'       | '250V'        | '0.25PF' | 'IO'       | 'CAP CHIP 8.2P 250V(+-0.25P,C0G,0603)HQ'                       | 'CHIP0603'     | ''          | ''   | '20220106'
 '8.2PF'    | '50V'   | '0.25PF'  | 'C0402'     | 'C0G'     | 'CH-826C0B01'(!)   = 'End of Design' | 'Comp-Approve'     | ''       | 'CH-826C0B01'     |'C0402'| '(C0402-0201)'                                                       | '8.2PF'    | '50V'         | '0.25PF' | 'DISCRETE' | 'CAP CHIP 8.2PF,50V(+-0.25PF,C0G,0402)HIQ'                     | 'CHIP0402'     | ''          | ''   | '20220106'
 '8.2PF'    | '50V'   | '0.25PF'  | 'C0402'     | 'EMPTY'   | 'CH-826C0B01'(!)   = 'End of Design' | 'Comp-Approve'     | ''       | 'CH-826C0B01'     |'C0402'| '(C0402-0201)'                                                       | 'NA'       | '50V'         | '0.25PF' | 'IO'       | 'CAP CHIP 8.2PF,50V(+-0.25PF,C0G,0402)HIQ'                     | 'CHIP0402'     | ''          | ''   | '20220106'
 '330PF'    | '50V'   | '5%'      | 'C0402'     | 'X7R'     | 'CH13306JB14'(!)   = ''              | ''                 | ''       | 'CH13306JB14'     |'C0402'| '(C0402-0201)'                                                       | '330PF'    | '50V'         | '5%'     | 'DISCRETE' | 'CAP CHIP 330P 50V (+-5% X7R 0402)'                            | 'CHIP0402'     | ''          | ''   | '20220110'
 '330PF'    | '50V'   | '5%'      | 'C0402'     | 'EMPTY'   | 'CH13306JB14'(!)   = ''              | ''                 | ''       | 'CH13306JB14'     |'C0402'| '(C0402-0201)'                                                       | 'NA'       | '50V'         | '5%'     | 'IO'       | 'CAP CHIP 330P 50V (+-5% X7R 0402)'                            | 'CHIP0402'     | ''          | ''   | '20220110'
 '1PF'      | '250V'  | '0.1PF'   | 'C0603'     | 'C0G'     | 'CH-10CB0900'(!)   = ''              | ''                 | ''       | 'CH-10CB0900'     |'C0603'| '(SMC0603AW)'                                                        | '1PF'      | '250V'        | '0.1PF'  | 'DISCRETE' | 'CAP CHIP 1P 250V(+-0.1P,C0G,0603)HQ'                          | 'CHIP0603'     | ''          | ''   | '20220113'
 '1PF'      | '250V'  | '0.1PF'   | 'C0603'     | 'EMPTY'   | 'CH-10CB0900'(!)   = ''              | ''                 | ''       | 'CH-10CB0900'     |'C0603'| '(SMC0603AW)'                                                        | 'NA'       | '250V'        | '0.1PF'  | 'IO'       | 'CAP CHIP 1P 250V(+-0.1P,C0G,0603)HQ'                          | 'CHIP0603'     | ''          | ''   | '20220113'
 '6.8PF'    | '250V'  | '0.1PF'   | 'C0603'     | 'C0G'     | 'CH-68CB0900'(!)   = ''              | ''                 | ''       | 'CH-68CB0900'     |'C0603'| '(SMC0603AW)'                                                        | '6.8PF'    | '250V'        | '0.1PF'  | 'DISCRETE' | 'CAP CHIP 6.8P 250V(+-0.1P,C0G,0603)HQ'                        | 'CHIP0603'     | ''          | ''   | '20220113'
 '6.8PF'    | '250V'  | '0.1PF'   | 'C0603'     | 'EMPTY'   | 'CH-68CB0900'(!)   = ''              | ''                 | ''       | 'CH-68CB0900'     |'C0603'| '(SMC0603AW)'                                                        | 'NA'       | '250V'        | '0.1PF'  | 'IO'       | 'CAP CHIP 6.8P 250V(+-0.1P,C0G,0603)HQ'                        | 'CHIP0603'     | ''          | ''   | '20220113'
 '22UF'     | '4V'    | '20%'     | 'C0402'     | 'X6S'     | 'CH622KMEB04'(!)   = ''              | ''                 | ''       | 'CH622KMEB04'     |'C0402_H28'| '(C0402-0201_H28)'                                                   | '22UF'     | '4V'          | '20%'    | 'DISCRETE' | 'CAP CHIP 22UF 4V(+-20%,X6S,0402)SAM'                          | 'CHIP0402'     | ''          | ''   | '20220120'
 '22UF'     | '4V'    | '20%'     | 'C0402'     | 'EMPTY'   | 'CH622KMEB04'(!)   = ''              | ''                 | ''       | 'CH622KMEB04'     |'C0402_H28'| '(C0402-0201_H28)'                                                   | 'NA'       | '4V'          | '20%'    | 'IO'       | 'CAP CHIP 22UF 4V(+-20%,X6S,0402)SAM'                          | 'CHIP0402'     | ''          | ''   | '20220120'
 '47UF'     | '2.5V'  | '20%'     | 'C0603'     | 'X6S'     | 'CH647LME902'(!)   = ''              | ''                 | ''       | 'CH647LME902'     |'C0603_H40'| '(SMC0603AW)'                                                        | '47UF'     | '2.5V'        | '20%'    | 'DISCRETE' | 'CAP CHIP 47U 2.5V(+-20%,X6S,0603)SAM'                         | 'CHIP0603'     | ''          | ''   | '20220120'
 '47UF'     | '2.5V'  | '20%'     | 'C0603'     | 'EMPTY'   | 'CH647LME902'(!)   = ''              | ''                 | ''       | 'CH647LME902'     |'C0603_H40'| '(SMC0603AW)'                                                        | 'NA'       | '2.5V'        | '20%'    | 'IO'       | 'CAP CHIP 47U 2.5V(+-20%,X6S,0603)SAM'                         | 'CHIP0603'     | ''          | ''   | '20220120'
 '10UF'     | '16V'   | '10%'     | 'C0805'     | 'X6S'     | 'CH6103KEA03'(!)   = ''              | ''                 | ''       | 'CH6103KEA03'     |'C0805_H57'| '(SMC0805AW)'                                                        | '10UF'     | '16V'         | '10%'    | 'DISCRETE' | 'CAP CHIP 10UF 16V(+-10%,X6S,0805)SAM'                         | 'CHIP0805'     | ''          | ''   | '20220120'
 '10UF'     | '16V'   | '10%'     | 'C0805'     | 'EMPTY'   | 'CH6103KEA03'(!)   = ''              | ''                 | ''       | 'CH6103KEA03'     |'C0805_H57'| '(SMC0805AW)'                                                        | 'NA'       | '16V'         | '10%'    | 'IO'       | 'CAP CHIP 10UF 16V(+-10%,X6S,0805)SAM'                         | 'CHIP0805'     | ''          | ''   | '20220120'
 '0.3PF'    | '250V'  | '0.1PF'   | 'C0603'     | 'C0G'     | 'CH+30CB0900'(!)   = ''              | ''                 | ''       | 'CH+30CB0900'     |'C0603'| '(SMC0603AW)'                                                        | '0.3PF'    | '250V'        | '0.1PF'  | 'DISCRETE' | 'CAP CHIP 0.3P 250V(+-0.1P,C0G,0603)HQ'                        | 'CHIP0603'     | ''          | ''   | '20220120'
 '0.3PF'    | '250V'  | '0.1PF'   | 'C0603'     | 'EMPTY'   | 'CH+30CB0900'(!)   = ''              | ''                 | ''       | 'CH+30CB0900'     |'C0603'| '(SMC0603AW)'                                                        | 'NA'       | '250V'        | '0.1PF'  | 'IO'       | 'CAP CHIP 0.3P 250V(+-0.1P,C0G,0603)HQ'                        | 'CHIP0603'     | ''          | ''   | '20220120'
 '22UF'     | '10V'   | '20%'     | 'C0805'     | 'X6S'     | 'CH6222MEA06'(!)   = 'End of Design' | 'Comp-Approve'     | ''       | 'CH6222MEA06'     |'C0805_H57'| '(SMC0805AW)'                                                        | '22UF'     | '10V'         | '20%'    | 'DISCRETE' | 'CAP CHIP 22U 10V(20%,X6S,0805)SAM'                            | 'CHIP0805'     | ''          | ''   | '20220120'
 '22UF'     | '10V'   | '20%'     | 'C0805'     | 'EMPTY'   | 'CH6222MEA06'(!)   = 'End of Design' | 'Comp-Approve'     | ''       | 'CH6222MEA06'     |'C0805_H57'| '(SMC0805AW)'                                                        | 'NA'       | '10V'         | '20%'    | 'IO'       | 'CAP CHIP 22U 10V(20%,X6S,0805)SAM'                            | 'CHIP0805'     | ''          | ''   | '20220120'
 '2.2UF'    | '25V'   | '20%'     | 'C0402'     | 'X6S'     | 'CH5224MEB04'(!)   = ''              | ''                 | ''       | 'CH5224MEB04'     |'C0402_H28'| '(C0402-0201_H28)'                                                   | '2.2UF'    | '25V'         | '20%'    | 'DISCRETE' | 'CAP CHIP 2.2UF 25V(+-20%,X6S,0402)'                           | 'CHIP0402'     | ''          | ''   | '20220125'
 '2.2UF'    | '25V'   | '20%'     | 'C0402'     | 'EMPTY'   | 'CH5224MEB04'(!)   = ''              | ''                 | ''       | 'CH5224MEB04'     |'C0402_H28'| '(C0402-0201_H28)'                                                   | 'NA'       | '25V'         | '20%'    | 'IO'       | 'CAP CHIP 2.2UF 25V(+-20%,X6S,0402)'                           | 'CHIP0402'     | ''          | ''   | '20220125'
 '1000PF'   | '50V'   | '5%'      | 'C0402'     | 'NPO'     | 'CH2106J0B06'(!)   = ''              | ''                 | ''       | 'CH2106J0B06'     |'C0402'| '(C0402-0201)'                                                       | '1000PF'   | '50V'         | '5%'     | 'DISCRETE' | 'CAP CHIP 1000P,50V(+-5%,NPO,0402)'                            | 'CHIP0402'     | ''          | ''   | '20220221'
 '1000PF'   | '50V'   | '5%'      | 'C0402'     | 'EMPTY'   | 'CH2106J0B06'(!)   = ''              | ''                 | ''       | 'CH2106J0B06'     |'C0402'| '(C0402-0201)'                                                       | 'NA'       | '50V'         | '5%'     | 'IO'       | 'CAP CHIP 1000P,50V(+-5%,NPO,0402)'                            | 'CHIP0402'     | ''          | ''   | '20220221'
 '0.15UF'   | '100V'  | '10%'     | 'C0805'     | 'X7R'     | 'CH4158K1A00'(!)   = ''              | ''                 | ''       | 'CH4158K1A00'     |'C0805_H57'| '(SMC0805AW)'                                                        | '0.15UF'   | '100V'        | '10%'    | 'DISCRETE' | 'CAP CHIP 0.15U 100V(+-10%,X7R,0805)'                          | 'CHIP0805'     | ''          | ''   | '20220301'
 '0.15UF'   | '100V'  | '10%'     | 'C0805'     | 'EMPTY'   | 'CH4158K1A00'(!)   = ''              | ''                 | ''       | 'CH4158K1A00'     |'C0805_H57'| '(SMC0805AW)'                                                        | 'NA'       | '100V'        | '10%'    | 'IO'       | 'CAP CHIP 0.15U 100V(+-10%,X7R,0805)'                          | 'CHIP0805'     | ''          | ''   | '20220301'
 '18PF'     | '50V'   | '2%'      | 'C0201'     | 'C0G'     | 'CH0186G0E00'(!)   = ''              | ''                 | ''       | 'CH0186G0E00'     |'C0201'| '(SMC0201AW)'                                                        | '18PF'     | '50V'         | '2%'     | 'DISCRETE' | 'CAP CHIP 18PF 50V(+-2%,C0G,0201)'                             | 'CHIP0201'     | ''          | ''   | '20220303'
 '18PF'     | '50V'   | '2%'      | 'C0201'     | 'EMPTY'   | 'CH0186G0E00'(!)   = ''              | ''                 | ''       | 'CH0186G0E00'     |'C0201'| '(SMC0201AW)'                                                        | 'NA'       | '50V'         | '2%'     | 'IO'       | 'CAP CHIP 18PF 50V(+-2%,C0G,0201)'                             | 'CHIP0201'     | ''          | ''   | '20220303'
 '22UF'     | '10V'   | '20%'     | 'C0402'     | 'X5R'     | 'CH6222M9B01'(!)   = ''              | ''                 | ''       | 'CH6222M9B01'     |'C0402_H32'| '(C0402-0201_H32)'                                                   | '22UF'     | '10V'         | '20%'    | 'DISCRETE' | 'CAP CHIP 22U 10V(+-20%,X5R,0402)'                             | 'CHIP0402'     | ''          | ''   | '20220307'
 '22UF'     | '10V'   | '20%'     | 'C0402'     | 'EMPTY'   | 'CH6222M9B01'(!)   = ''              | ''                 | ''       | 'CH6222M9B01'     |'C0402_H32'| '(C0402-0201_H32)'                                                   | 'NA'       | '10V'         | '20%'    | 'IO'       | 'CAP CHIP 22U 10V(+-20%,X5R,0402)'                             | 'CHIP0402'     | ''          | ''   | '20220307'
 '1.8PF'    | '50V'   | '0.1PF'   | 'C0402'     | 'NPO'     | 'CH-1826TB06'(!)   = ''              | ''                 | ''       | 'CH-1826TB06'     |'C0402'| '(C0402-0201)'                                                       | '1.8PF'    | '50V'         | '0.1PF'  | 'DISCRETE' | 'CAP CHIP 1.8P 50V(+-0.1P,NPO,0402)'                           | 'CHIP0402'     | ''          | ''   | '20220307'
 '1.8PF'    | '50V'   | '0.1PF'   | 'C0402'     | 'EMPTY'   | 'CH-1826TB06'(!)   = ''              | ''                 | ''       | 'CH-1826TB06'     |'C0402'| '(C0402-0201)'                                                       | 'NA'       | '50V'         | '0.1PF'  | 'IO'       | 'CAP CHIP 1.8P 50V(+-0.1P,NPO,0402)'                           | 'CHIP0402'     | ''          | ''   | '20220307'
 '100PF'    | '50V'   | '5%'      | 'C0201'     | 'NPO'     | 'CH1106J0E00'(!)   = ''              | ''                 | ''       | 'CH1106J0E00'     |'C0201'| '(SMC0201AW)'                                                        | '100PF'    | '50V'         | '5%'     | 'DISCRETE' | 'CAP CHIP 100P 50V(+-5%,NPO,0201)'                             | 'CHIP0201'     | ''          | ''   | '20220307'
 '100PF'    | '50V'   | '5%'      | 'C0201'     | 'EMPTY'   | 'CH1106J0E00'(!)   = ''              | ''                 | ''       | 'CH1106J0E00'     |'C0201'| '(SMC0201AW)'                                                        | 'NA'       | '50V'         | '5%'     | 'IO'       | 'CAP CHIP 100P 50V(+-5%,NPO,0201)'                             | 'CHIP0201'     | ''          | ''   | '20220307'
 '0.22UF'   | '50V'   | '10%'     | 'C0603'     | 'X7R'     | 'CH4226K1902'(!)   = ''              | ''                 | ''       | 'CH4226K1902'     |'C0603'| '(SMC0603AW)'                                                        | '0.22UF'   | '50V'         | '10%'    | 'DISCRETE' | 'CAP CHIP 0.22U 50V(+-10%,X7R,0603)'                           | 'CHIP0603'     | ''          | ''   | '20220321'
 '0.22UF'   | '50V'   | '10%'     | 'C0603'     | 'EMPTY'   | 'CH4226K1902'(!)   = ''              | ''                 | ''       | 'CH4226K1902'     |'C0603'| '(SMC0603AW)'                                                        | 'NA'       | '50V'         | '10%'    | 'IO'       | 'CAP CHIP 0.22U 50V(+-10%,X7R,0603)'                           | 'CHIP0603'     | ''          | ''   | '20220321'
 '330PF'    | '16V'   | '10%'     | 'C0201'     | 'X7R'     | 'CH1333K1E01'(!)   = ''              | ''                 | ''       | 'CH1333K1E01'     |'C0201'| '(SMC0201AW)'                                                        | '330PF'    | '16V'         | '10%'    | 'DISCRETE' | 'CAP CHIP 330PF 16V(+-10%,X7R,0201)'                           | 'CHIP0201'     | ''          | ''   | '20220321'
 '330PF'    | '16V'   | '10%'     | 'C0201'     | 'EMPTY'   | 'CH1333K1E01'(!)   = ''              | ''                 | ''       | 'CH1333K1E01'     |'C0201'| '(SMC0201AW)'                                                        | 'NA'       | '16V'         | '10%'    | 'IO'       | 'CAP CHIP 330PF 16V(+-10%,X7R,0201)'                           | 'CHIP0201'     | ''          | ''   | '20220321'
 '0.022UF'  | '100V'  | '10%'     | 'C0603'     | 'X7R'     | 'CH3228K1900'(!)   = ''              | ''                 | ''       | 'CH3228K1900'     |'C0603'| '(SMC0603AW)'                                                        | '0.022UF'  | '100V'        | '10%'    | 'DISCRETE' | 'CAP CHIP 0.022UF 100V(+-10%,X7R,0603)'                        | 'CHIP0603'     | ''          | ''   | '20220321'
 '0.022UF'  | '100V'  | '10%'     | 'C0603'     | 'EMPTY'   | 'CH3228K1900'(!)   = ''              | ''                 | ''       | 'CH3228K1900'     |'C0603'| '(SMC0603AW)'                                                        | 'NA'       | '100V'        | '10%'    | 'IO'       | 'CAP CHIP 0.022UF 100V(+-10%,X7R,0603)'                        | 'CHIP0603'     | ''          | ''   | '20220321'
 '680PF'    | '50V'   | '10%'     | 'C0402'     | 'X7R'     | 'CH1686K1B09'(!)   = ''              | ''                 | ''       | 'CH1686K1B09'     |'C0402'| '(C0402-0201)'                                                       | '680PF'    | '50V'         | '10%'    | 'DISCRETE' | 'CAP CHIP 680P 50V(+-10%,X7R,0402)MUR'                         | 'CHIP0402'     | ''          | ''   | '20220414'
 '680PF'    | '50V'   | '10%'     | 'C0402'     | 'EMPTY'   | 'CH1686K1B09'(!)   = ''              | ''                 | ''       | 'CH1686K1B09'     |'C0402'| '(C0402-0201)'                                                       | 'NA'       | '50V'         | '10%'    | 'IO'       | 'CAP CHIP 680P 50V(+-10%,X7R,0402)MUR'                         | 'CHIP0402'     | ''          | ''   | '20220414'
 '0.01UF'   | '100V'  | '10%'     | 'C0805'     | 'X7R'     | 'CH3108K1A03'(!)   = ''              | ''                 | ''       | 'CH3108K1A03'     |'C0805_H57'| '(SMC0805AW)'                                                        | '0.01UF'   | '100V'        | '10%'    | 'DISCRETE' | 'CAP CHIP 0.01U 100V(10%,X7R,0805)'                            | 'CHIP0805'     | ''          | ''   | '20220421'
 '0.01UF'   | '100V'  | '10%'     | 'C0805'     | 'EMPTY'   | 'CH3108K1A03'(!)   = ''              | ''                 | ''       | 'CH3108K1A03'     |'C0805_H57'| '(SMC0805AW)'                                                        | 'NA'       | '100V'        | '10%'    | 'IO'       | 'CAP CHIP 0.01U 100V(10%,X7R,0805)'                            | 'CHIP0805'     | ''          | ''   | '20220421'
 '4.7UF'    | '10V'   | '20%'     | 'C0402'     | 'X5R'     | 'CH5472M9B01'(!)   = 'End of Design' | 'Comp-Approve'     | ''       | 'CH5472M9B01'     |'C0402_H28'| '(C0402-0201_H28)'                                                   | '4.7UF'    | '10V'         | '20%'    | 'DISCRETE' | 'CAP CHIP 4.7U 10V(+-20%,X5R,0402)'                            | 'CHIP0402'     | ''          | ''   | '20220422'
 '4.7UF'    | '10V'   | '20%'     | 'C0402'     | 'EMPTY'   | 'CH5472M9B01'(!)   = 'End of Design' | 'Comp-Approve'     | ''       | 'CH5472M9B01'     |'C0402_H28'| '(C0402-0201_H28)'                                                   | 'NA'       | '10V'         | '20%'    | 'IO'       | 'CAP CHIP 4.7U 10V(+-20%,X5R,0402)'                            | 'CHIP0402'     | ''          | ''   | '20220422'
 '330PF'    | '50V'   | '5%'      | 'C0402'     | 'NPO'     | 'CH1336J0B10'(!)   = ''              | ''                 | ''       | 'CH1336J0B10'     |'C0402'| '(C0402-0201)'                                                       | '330PF'    | '50V'         | '5%'     | 'DISCRETE' | 'CAP CHIP 330P 50V(+-5%,NPO,0402)MUR'                          | 'CHIP0402'     | ''          | ''   | '20220422'
 '330PF'    | '50V'   | '5%'      | 'C0402'     | 'EMPTY'   | 'CH1336J0B10'(!)   = ''              | ''                 | ''       | 'CH1336J0B10'     |'C0402'| '(C0402-0201)'                                                       | 'NA'       | '50V'         | '5%'     | 'IO'       | 'CAP CHIP 330P 50V(+-5%,NPO,0402)MUR'                          | 'CHIP0402'     | ''          | ''   | '20220422'
 '680PF'    | '50V'   | '5%'      | 'C0402'     | 'C0G'     | 'CH1686J0B03'(!)   = ''              | ''                 | ''       | 'CH1686J0B03'     |'C0402'| '(C0402-0201)'                                                       | '680PF'    | '50V'         | '5%'     | 'DISCRETE' | 'CAP CHIP 680P 50V(+-5%,C0G,0402)MUR'                          | 'CHIP0402'     | ''          | ''   | '20220422'
 '680PF'    | '50V'   | '5%'      | 'C0402'     | 'EMPTY'   | 'CH1686J0B03'(!)   = ''              | ''                 | ''       | 'CH1686J0B03'     |'C0402'| '(C0402-0201)'                                                       | 'NA'       | '50V'         | '5%'     | 'IO'       | 'CAP CHIP 680P 50V(+-5%,C0G,0402)MUR'                          | 'CHIP0402'     | ''          | ''   | '20220422'
 '0.5PF'    | '250V'  | '0.05PF'  | 'C0603'     | 'C0G'     | 'CH+50CT0900'(!)   = ''              | ''                 | ''       | 'CH+50CT0900'     |'C0603'| '(SMC0603AW)'                                                        | '0.5PF'    | '250V'        | '0.05PF' | 'DISCRETE' | 'CAP CHIP 0.5P 250V(0.05P,C0G,0603)HQ'                         | 'CHIP0603'     | ''          | ''   | '20220504'
 '0.5PF'    | '250V'  | '0.05PF'  | 'C0603'     | 'EMPTY'   | 'CH+50CT0900'(!)   = ''              | ''                 | ''       | 'CH+50CT0900'     |'C0603'| '(SMC0603AW)'                                                        | 'NA'       | '250V'        | '0.05PF' | 'IO'       | 'CAP CHIP 0.5P 250V(0.05P,C0G,0603)HQ'                         | 'CHIP0603'     | ''          | ''   | '20220504'
 '0.2PF'    | '250V'  | '0.05PF'  | 'C0603'     | 'C0G'     | 'CH+20CT0900'(!)   = ''              | ''                 | ''       | 'CH+20CT0900'     |'C0603'| '(SMC0603AW)'                                                        | '0.2PF'    | '250V'        | '0.05PF' | 'DISCRETE' | 'CAP CHIP 0.2P 250V(0.05P,C0G,0603)HQ'                         | 'CHIP0603'     | ''          | ''   | '20220504'
 '0.2PF'    | '250V'  | '0.05PF'  | 'C0603'     | 'EMPTY'   | 'CH+20CT0900'(!)   = ''              | ''                 | ''       | 'CH+20CT0900'     |'C0603'| '(SMC0603AW)'                                                        | 'NA'       | '250V'        | '0.05PF' | 'IO'       | 'CAP CHIP 0.2P 250V(0.05P,C0G,0603)HQ'                         | 'CHIP0603'     | ''          | ''   | '20220504'
 '1000PF'   | '50V'   | '5%'      | 'C0402'     | 'C0G'     | 'CH2106J0B01'(!)   = ''              | ''                 | ''       | 'CH2106J0B01'     |'C0402'| '(C0402-0201)'                                                       | '1000PF'   | '50V'         | '5%'     | 'DISCRETE' | 'CAP CHIP 1000PF 50V( 5%,C0G, 0402)MUR'                        | 'CHIP0402'     | ''          | ''   | '20220506'
 '1000PF'   | '50V'   | '5%'      | 'C0402'     | 'EMPTY'   | 'CH2106J0B01'(!)   = ''              | ''                 | ''       | 'CH2106J0B01'     |'C0402'| '(C0402-0201)'                                                       | 'NA'       | '50V'         | '5%'     | 'IO'       | 'CAP CHIP 1000PF 50V( 5%,C0G, 0402)MUR'                        | 'CHIP0402'     | ''          | ''   | '20220506'
 '0.15UF'   | '50V'   | '10%'     | 'C0603'     | 'X7R'     | 'CH4156K1901'(!)   = ''              | ''                 | ''       | 'CH4156K1901'     |'C0603'| '(SMC0603AW)'                                                        | '0.15UF'   | '50V'         | '10%'    | 'DISCRETE' | 'CAP CHIP 0.15U 50V(10%,X7R,0603)'                             | 'CHIP0603'     | ''          | ''   | '20220512'
 '0.15UF'   | '50V'   | '10%'     | 'C0603'     | 'EMPTY'   | 'CH4156K1901'(!)   = ''              | ''                 | ''       | 'CH4156K1901'     |'C0603'| '(SMC0603AW)'                                                        | 'NA'       | '50V'         | '10%'    | 'IO'       | 'CAP CHIP 0.15U 50V(10%,X7R,0603)'                             | 'CHIP0603'     | ''          | ''   | '20220512'
 '2.2UF'    | '16V'   | '20%'     | 'C0402'     | 'X6S'     | 'CH5223MEB01'(!)   = ''              | ''                 | ''       | 'CH5223MEB01'     |'C0402'| '(C0402-0201)'                                                       | '2.2UF'    | '16V'         | '20%'    | 'DISCRETE' | 'CAP CHIP 2.2U 16V(+-20%,X6S,0402)MUR'                         | 'CHIP0402'     | ''          | ''   | '20220518'
 '2.2UF'    | '16V'   | '20%'     | 'C0402'     | 'EMPTY'   | 'CH5223MEB01'(!)   = ''              | ''                 | ''       | 'CH5223MEB01'     |'C0402'| '(C0402-0201)'                                                       | 'NA'       | '16V'         | '20%'    | 'IO'       | 'CAP CHIP 2.2U 16V(+-20%,X6S,0402)MUR'                         | 'CHIP0402'     | ''          | ''   | '20220518'
 '0.01UF'   | '2KV'   | '10%'     | 'C1812'     | 'X7R'     | 'CH310IK1402'(!)   = ''              | ''                 | ''       | 'CH310IK1402'     |'C1812XC_H111'| '(SMC1812AW)'                                                        | '0.01UF'   | '2KV'         | '10%'    | 'DISCRETE' | 'CAP CHIP 0.01U 2KV(+-10%,X7R,1812)H2.5'                       | 'CHIP1812'     | ''          | ''   | '20220520'
 '0.01UF'   | '2KV'   | '10%'     | 'C1812'     | 'EMPTY'   | 'CH310IK1402'(!)   = ''              | ''                 | ''       | 'CH310IK1402'     |'C1812XC_H111'| '(SMC1812AW)'                                                        | 'NA'       | '2KV'         | '10%'    | 'IO'       | 'CAP CHIP 0.01U 2KV(+-10%,X7R,1812)H2.5'                       | 'CHIP1812'     | ''          | ''   | '20220520'
 '1500PF'   | '50V'   | '2%'      | 'C0402'     | 'C0G'     | 'CH2156G0B01'(!)   = ''              | ''                 | ''       | 'CH2156G0B01'     |'C0402'| '(C0402-0201)'                                                       | '1500PF'   | '50V'         | '2%'     | 'DISCRETE' | 'CAP CHIP 1500PF 50V(+-2%,C0G,0402)MUR'                        | 'CHIP0402'     | ''          | ''   | '20220520'
 '1500PF'   | '50V'   | '2%'      | 'C0402'     | 'EMPTY'   | 'CH2156G0B01'(!)   = ''              | ''                 | ''       | 'CH2156G0B01'     |'C0402'| '(C0402-0201)'                                                       | 'NA'       | '50V'         | '2%'     | 'IO'       | 'CAP CHIP 1500PF 50V(+-2%,C0G,0402)MUR'                        | 'CHIP0402'     | ''          | ''   | '20220520'
 '47UF'     | '4V'    | '20%'     | 'C0603'     | 'X6S'     | 'CH647KME900'(!)   = 'End of Design' | 'Comp-Approve'     | ''       | 'CH647KME900'     |'C0603_H40'| '(C0603_BHS-SP)'                                                     | '47UF'     | '4V'          | '20%'    | 'DISCRETE' | 'CAP CHIP 47U 4V(+-20%,X6S,0603)'                              | 'CHIP0603'     | ''          | ''   | '20220523'
 '47UF'     | '4V'    | '20%'     | 'C0603'     | 'EMPTY'   | 'CH647KME900'(!)   = 'End of Design' | 'Comp-Approve'     | ''       | 'CH647KME900'     |'C0603_H40'| '(C0603_BHS-SP)'                                                     | 'NA'       | '4V'          | '20%'    | 'IO'       | 'CAP CHIP 47U 4V(+-20%,X6S,0603)'                              | 'CHIP0603'     | ''          | ''   | '20220523'
 '15PF'     | '25V'   | '5%'      | 'C0201'     | 'C0G'     | 'CH0154J0E13'(!)   = ''              | ''                 | ''       | 'CH0154J0E13'     |'C0201'| '(SMC0201AW)'                                                        | '15PF'     | '25V'         | '5%'     | 'DISCRETE' | 'CAP CHIP 15P 25V(+-5%,C0G,0201)MUR SELA'                      | 'CHIP0201'     | ''          | ''   | '20220608'
 '15PF'     | '25V'   | '5%'      | 'C0201'     | 'EMPTY'   | 'CH0154J0E13'(!)   = ''              | ''                 | ''       | 'CH0154J0E13'     |'C0201'| '(SMC0201AW)'                                                        | 'NA'       | '25V'         | '5%'     | 'IO'       | 'CAP CHIP 15P 25V(+-5%,C0G,0201)MUR SELA'                      | 'CHIP0201'     | ''          | ''   | '20220608'
 '18PF'     | '50V'   | '2%'      | 'C0201'     | 'C0G'     | 'CH0186G0E01'(!)   = ''              | ''                 | ''       | 'CH0186G0E01'     |'C0201'| '(SMC0201AW)'                                                        | '18PF'     | '50V'         | '2%'     | 'DISCRETE' | 'CAP CHIP 18PF 50V(+-2%,C0G,0201)MUR'                          | 'CHIP0201'     | ''          | ''   | '20220608'
 '18PF'     | '50V'   | '2%'      | 'C0201'     | 'EMPTY'   | 'CH0186G0E01'(!)   = ''              | ''                 | ''       | 'CH0186G0E01'     |'C0201'| '(SMC0201AW)'                                                        | 'NA'       | '50V'         | '2%'     | 'IO'       | 'CAP CHIP 18PF 50V(+-2%,C0G,0201)MUR'                          | 'CHIP0201'     | ''          | ''   | '20220608'
 '100PF'    | '25V'   | '5%'      | 'C0402'     | 'C0G'     | 'CH1104J0B00'(!)   = ''              | ''                 | ''       | 'CH1104J0B00'     |'C0402'| '(C0402-0201)'                                                       | '100PF'    | '25V'         | '5%'     | 'DISCRETE' | 'CAP CHIP 100P 25V(+-5%,C0G,0402)'                             | 'CHIP0402'     | ''          | ''   | '20220608'
 '100PF'    | '25V'   | '5%'      | 'C0402'     | 'EMPTY'   | 'CH1104J0B00'(!)   = ''              | ''                 | ''       | 'CH1104J0B00'     |'C0402'| '(C0402-0201)'                                                       | 'NA'       | '25V'         | '5%'     | 'IO'       | 'CAP CHIP 100P 25V(+-5%,C0G,0402)'                             | 'CHIP0402'     | ''          | ''   | '20220608'
 '0.1UF'    | '16V'   | '10%'     | 'C0402'     | 'X5R'     | 'CH4103K9B06'(!)   = ''              | ''                 | ''       | 'CH4103K9B06'     |'C0402'| '(C0402-0201)'                                                       | '0.1UF'    | '16V'         | '10%'    | 'DISCRETE' | 'CAP CHIP 0.1U 16V(+-10%,X5R,0402)MUR'                         | 'CHIP0402'     | ''          | ''   | '20220608'
 '0.1UF'    | '16V'   | '10%'     | 'C0402'     | 'EMPTY'   | 'CH4103K9B06'(!)   = ''              | ''                 | ''       | 'CH4103K9B06'     |'C0402'| '(C0402-0201)'                                                       | 'NA'       | '16V'         | '10%'    | 'IO'       | 'CAP CHIP 0.1U 16V(+-10%,X5R,0402)MUR'                         | 'CHIP0402'     | ''          | ''   | '20220608'
 '1UF'      | '25V'   | '20%'     | 'C0402'     | 'X5R'     | 'CH5104M9B01'(!)   = ''              | ''                 | ''       | 'CH5104M9B01'     |'C0402'| '(C0402-0201)'                                                       | '1UF'      | '25V'         | '20%'    | 'DISCRETE' | 'CAP CHIP 1UF 25V(+-20%,X5R,0402)MUR'                          | 'CHIP0402'     | ''          | ''   | '20220608'
 '1UF'      | '25V'   | '20%'     | 'C0402'     | 'EMPTY'   | 'CH5104M9B01'(!)   = ''              | ''                 | ''       | 'CH5104M9B01'     |'C0402'| '(C0402-0201)'                                                       | 'NA'       | '25V'         | '20%'    | 'IO'       | 'CAP CHIP 1UF 25V(+-20%,X5R,0402)MUR'                          | 'CHIP0402'     | ''          | ''   | '20220608'
 '0.01UF'   | '10V'   | '10%'     | 'C0402'     | 'X7R'     | 'CH3102K1B00'(!)   = 'End of Design' | 'Comp-Approve'     | ''       | 'CH3102K1B00'     |'C0402'| '(C0402-0201)'                                                       | '0.01UF'   | '10V'         | '10%'    | 'DISCRETE' | 'CAP CHIP 0.01UF 10V(+-10%,X7R,0402)'                          | 'CHIP0402'     | ''          | ''   | '20220609'
 '0.01UF'   | '10V'   | '10%'     | 'C0402'     | 'EMPTY'   | 'CH3102K1B00'(!)   = 'End of Design' | 'Comp-Approve'     | ''       | 'CH3102K1B00'     |'C0402'| '(C0402-0201)'                                                       | 'NA'       | '10V'         | '10%'    | 'IO'       | 'CAP CHIP 0.01UF 10V(+-10%,X7R,0402)'                          | 'CHIP0402'     | ''          | ''   | '20220609'
 '47UF'     | '6.3V'  | '20%'     | 'C0805'     | 'X6S'     | 'CH6471MEA03'(!)   = ''              | ''                 | ''       | 'CH6471MEA03'     |'C0805_H57'| '(SMC0805AW)'                                                        | '47UF'     | '6.3V'        | '20%'    | 'DISCRETE' | 'CAP CHIP 47U 6.3V(+-20%,X6S,0805)MUR'                         | 'CHIP0805'     | ''          | ''   | '20220609'
 '47UF'     | '6.3V'  | '20%'     | 'C0805'     | 'EMPTY'   | 'CH6471MEA03'(!)   = ''              | ''                 | ''       | 'CH6471MEA03'     |'C0805_H57'| '(SMC0805AW)'                                                        | 'NA'       | '6.3V'        | '20%'    | 'IO'       | 'CAP CHIP 47U 6.3V(+-20%,X6S,0805)MUR'                         | 'CHIP0805'     | ''          | ''   | '20220609'
 '100UF'    | '4V'    | '20%'     | 'C0805'     | 'X5R'     | 'CH710KM9A01'(!)   = ''              | ''                 | ''       | 'CH710KM9A01'     |'C0805_H61'| '(SMC0805AW)'                                                        | '100UF'    | '4V'          | '20%'    | 'DISCRETE' | 'CAP CHIP 100U 4V(+-20%,X5R,0805)MUR'                          | 'CHIP0805'     | ''          | ''   | '20220609'
 '100UF'    | '4V'    | '20%'     | 'C0805'     | 'EMPTY'   | 'CH710KM9A01'(!)   = ''              | ''                 | ''       | 'CH710KM9A01'     |'C0805_H61'| '(SMC0805AW)'                                                        | 'NA'       | '4V'          | '20%'    | 'IO'       | 'CAP CHIP 100U 4V(+-20%,X5R,0805)MUR'                          | 'CHIP0805'     | ''          | ''   | '20220609'
 '47UF'     | '10V'   | '20%'     | 'C0805'     | 'X5R'     | 'CH6472M9A02'(!)   = ''              | ''                 | ''       | 'CH6472M9A02'     |'C0805_H61'| '(SMC0805AW)'                                                        | '47UF'     | '10V'         | '20%'    | 'DISCRETE' | 'CAP CHIP 47U 10V(+-20%,X5R,0805)MUR'                          | 'CHIP0805'     | ''          | ''   | '20220609'
 '47UF'     | '10V'   | '20%'     | 'C0805'     | 'EMPTY'   | 'CH6472M9A02'(!)   = ''              | ''                 | ''       | 'CH6472M9A02'     |'C0805_H61'| '(SMC0805AW)'                                                        | 'NA'       | '10V'         | '20%'    | 'IO'       | 'CAP CHIP 47U 10V(+-20%,X5R,0805)MUR'                          | 'CHIP0805'     | ''          | ''   | '20220609'
 '0.1UF'    | '100V'  | '10%'     | 'C0603'     | 'X7R'     | 'CH4108K1909'(!)   = ''              | ''                 | ''       | 'CH4108K1909'     |'C0603'| '(SMC0603AW)'                                                        | '0.1UF'    | '100V'        | '10%'    | 'DISCRETE' | 'CAP CHIP 0.1U 100V(+-10%,X7R,0603)MUR'                        | 'CHIP0603'     | ''          | ''   | '20220609'
 '0.1UF'    | '100V'  | '10%'     | 'C0603'     | 'EMPTY'   | 'CH4108K1909'(!)   = ''              | ''                 | ''       | 'CH4108K1909'     |'C0603'| '(SMC0603AW)'                                                        | 'NA'       | '100V'        | '10%'    | 'IO'       | 'CAP CHIP 0.1U 100V(+-10%,X7R,0603)MUR'                        | 'CHIP0603'     | ''          | ''   | '20220609'
 '15PF'     | '25V'   | '5%'      | 'C0201'     | 'C0G'     | 'CH0154J0E22'(!)   = ''              | ''                 | ''       | 'CH0154J0E22'     |'C0201'| '(SMC0201AW)'                                                        | '15PF'     | '25V'         | '5%'     | 'DISCRETE' | 'CAP CHIP 15P 25V(+-5%,C0G,0201)MUR'                           | 'CHIP0201'     | ''          | ''   | '20220620'
 '15PF'     | '25V'   | '5%'      | 'C0201'     | 'EMPTY'   | 'CH0154J0E22'(!)   = ''              | ''                 | ''       | 'CH0154J0E22'     |'C0201'| '(SMC0201AW)'                                                        | 'NA'       | '25V'         | '5%'     | 'IO'       | 'CAP CHIP 15P 25V(+-5%,C0G,0201)MUR'                           | 'CHIP0201'     | ''          | ''   | '20220620'
 '1UF'      | '25V'   | '10%'     | 'C0402'     | 'X5R'     | 'CH5104K9B15'(!)   = ''              | ''                 | ''       | 'CH5104K9B15'     |'C0402'| '(C0402-0201)'                                                       | '1UF'      | '25V'         | '10%'    | 'DISCRETE' | 'CAP CHIP 1UF 25V(+-10%,X5R,0402)MUR'                          | 'CHIP0402'     | ''          | ''   | '20220620'
 '1UF'      | '25V'   | '10%'     | 'C0402'     | 'EMPTY'   | 'CH5104K9B15'(!)   = ''              | ''                 | ''       | 'CH5104K9B15'     |'C0402'| '(C0402-0201)'                                                       | 'NA'       | '25V'         | '10%'    | 'IO'       | 'CAP CHIP 1UF 25V(+-10%,X5R,0402)MUR'                          | 'CHIP0402'     | ''          | ''   | '20220620'
 '0.1NF'    | '25V'   | '5%'      | 'C0201'     | 'C0G'     | 'CH1104J0E09'(!)   = ''              | ''                 | ''       | 'CH1104J0E09'     |'C0201'| '(SMC0201AW)'                                                        | '0.1NF'    | '25V'         | '5%'     | 'DISCRETE' | 'CAP CHIP 0.1NF 25V(+-5%,C0G,0201)MUR'                         | 'CHIP0201'     | ''          | ''   | '20220621'
 '0.1NF'    | '25V'   | '5%'      | 'C0201'     | 'EMPTY'   | 'CH1104J0E09'(!)   = ''              | ''                 | ''       | 'CH1104J0E09'     |'C0201'| '(SMC0201AW)'                                                        | 'NA'       | '25V'         | '5%'     | 'IO'       | 'CAP CHIP 0.1NF 25V(+-5%,C0G,0201)MUR'                         | 'CHIP0201'     | ''          | ''   | '20220621'
 '1500PF'   | '50V'   | '10%'     | 'C0402'     | 'X7R'     | 'CH2156K1B14'(!)   = ''              | ''                 | ''       | 'CH2156K1B14'     |'C0402'| '(C0402-0201)'                                                       | '1500PF'   | '50V'         | '10%'    | 'DISCRETE' | 'CAP CHIP 1500PF 50V(+-10%,X7R,0402)YGO'                       | 'CHIP0402'     | ''          | ''   | '20220621'
 '1500PF'   | '50V'   | '10%'     | 'C0402'     | 'EMPTY'   | 'CH2156K1B14'(!)   = ''              | ''                 | ''       | 'CH2156K1B14'     |'C0402'| '(C0402-0201)'                                                       | 'NA'       | '50V'         | '10%'    | 'IO'       | 'CAP CHIP 1500PF 50V(+-10%,X7R,0402)YGO'                       | 'CHIP0402'     | ''          | ''   | '20220621'
 '0.01UF'   | '10V'   | '10%'     | 'C0402'     | 'X7R'     | 'CH3102K1B06'(!)   = ''              | ''                 | ''       | 'CH3102K1B06'     |'C0402'| '(C0402_OCTAGONXA,C0402-0201)'                                       | '0.01UF'   | '10V'         | '10%'    | 'DISCRETE' | 'CAP CHIP 0.01UF 10V(+-10%,X7R,0402)YGO'                       | 'CHIP0402'     | ''          | ''   | '20220621'
 '0.01UF'   | '10V'   | '10%'     | 'C0402'     | 'EMPTY'   | 'CH3102K1B06'(!)   = ''              | ''                 | ''       | 'CH3102K1B06'     |'C0402'| '(C0402_OCTAGONXA,C0402-0201)'                                       | 'NA'       | '10V'         | '10%'    | 'IO'       | 'CAP CHIP 0.01UF 10V(+-10%,X7R,0402)YGO'                       | 'CHIP0402'     | ''          | ''   | '20220621'
 '2.2PF'    | '50V'   | '0.1PF'   | 'C0402'     | 'NPO'     | 'CH-226B0B02'(!)   = ''              | ''                 | ''       | 'CH-226B0B02'     |'C0402'| '(C0402-0201)'                                                       | '2.2PF'    | '50V'         | '0.1PF'  | 'DISCRETE' | 'CAP CHIP 2.2P 50V (+-0.1P,NPO,0402)MUR'                       | 'CHIP0402'     | ''          | ''   | '20220621'
 '2.2PF'    | '50V'   | '0.1PF'   | 'C0402'     | 'EMPTY'   | 'CH-226B0B02'(!)   = ''              | ''                 | ''       | 'CH-226B0B02'     |'C0402'| '(C0402-0201)'                                                       | 'NA'       | '50V'         | '0.1PF'  | 'IO'       | 'CAP CHIP 2.2P 50V (+-0.1P,NPO,0402)MUR'                       | 'CHIP0402'     | ''          | ''   | '20220621'
 '3900PF'   | '50V'   | '10%'     | 'C0402'     | 'X7R'     | 'CH2396K1B07'(!)   = ''              | ''                 | ''       | 'CH2396K1B07'     |'C0402'| '(C0402-0201)'                                                       | '3900PF'   | '50V'         | '10%'    | 'DISCRETE' | 'CAP CHIP 3900P 50V(+-10%,X7R,0402)MUR'                        | 'CHIP0402'     | ''          | ''   | '20220622'
 '3900PF'   | '50V'   | '10%'     | 'C0402'     | 'EMPTY'   | 'CH2396K1B07'(!)   = ''              | ''                 | ''       | 'CH2396K1B07'     |'C0402'| '(C0402-0201)'                                                       | 'NA'       | '50V'         | '10%'    | 'IO'       | 'CAP CHIP 3900P 50V(+-10%,X7R,0402)MUR'                        | 'CHIP0402'     | ''          | ''   | '20220622'
 '0.22UF'   | '6.3V'  | '20%'     | 'C0201'     | 'X6S'     | 'CH4221MEE03'(!)   = ''              | ''                 | ''       | 'CH4221MEE03'     |'C0201'| '(SMC0201AW)'                                                        | '0.22UF'   | '6.3V'        | '20%'    | 'DISCRETE' | 'CAP CHIP 0.22UF 6.3V(20%,X6S,0201)MUR'                        | 'CHIP0201'     | ''          | ''   | '20220623'
 '0.22UF'   | '6.3V'  | '20%'     | 'C0201'     | 'EMPTY'   | 'CH4221MEE03'(!)   = ''              | ''                 | ''       | 'CH4221MEE03'     |'C0201'| '(SMC0201AW)'                                                        | 'NA'       | '6.3V'        | '20%'    | 'IO'       | 'CAP CHIP 0.22UF 6.3V(20%,X6S,0201)MUR'                        | 'CHIP0201'     | ''          | ''   | '20220623'
 '0.22UF'   | '6.3V'  | '20%'     | 'C0201'     | 'X6S'     | 'CH4221MEE04'(!)   = ''              | ''                 | ''       | 'CH4221MEE04'     |'C0201'| '(SMC0201AW)'                                                        | '0.22UF'   | '6.3V'        | '20%'    | 'DISCRETE' | 'CAP CHIP 0.22UF 6.3V(20%,X6S,0201)TAY'                        | 'CHIP0201'     | ''          | ''   | '20220623'
 '0.22UF'   | '6.3V'  | '20%'     | 'C0201'     | 'EMPTY'   | 'CH4221MEE04'(!)   = ''              | ''                 | ''       | 'CH4221MEE04'     |'C0201'| '(SMC0201AW)'                                                        | 'NA'       | '6.3V'        | '20%'    | 'IO'       | 'CAP CHIP 0.22UF 6.3V(20%,X6S,0201)TAY'                        | 'CHIP0201'     | ''          | ''   | '20220623'
 '0.015UF'  | '16V'   | '20%'     | 'C0402'     | 'X7R'     | 'CH3153M1B01'(!)   = ''              | ''                 | ''       | 'CH3153M1B01'     |'C0402'| '(C0402-0201)'                                                       | '0.015UF'  | '16V'         | '20%'    | 'DISCRETE' | 'CAP CHIP 0.015U 16V(+-20%,X7R,0402)YGO'                       | 'CHIP0402'     | ''          | ''   | '20220624'
 '0.015UF'  | '16V'   | '20%'     | 'C0402'     | 'EMPTY'   | 'CH3153M1B01'(!)   = ''              | ''                 | ''       | 'CH3153M1B01'     |'C0402'| '(C0402-0201)'                                                       | 'NA'       | '16V'         | '20%'    | 'IO'       | 'CAP CHIP 0.015U 16V(+-20%,X7R,0402)YGO'                       | 'CHIP0402'     | ''          | ''   | '20220624'
 '3300PF'   | '50V'   | '5%'      | 'C0402'     | 'X7R'     | 'CH2336J1B05'(!)   = ''              | ''                 | ''       | 'CH2336J1B05'     |'C0402'| '(C0402-0201)'                                                       | '3300PF'   | '50V'         | '5%'     | 'DISCRETE' | 'CAP CHIP 3300P 50V(+-5%,X7R,0402)MUR'                         | 'CHIP0402'     | ''          | ''   | '20220624'
 '3300PF'   | '50V'   | '5%'      | 'C0402'     | 'EMPTY'   | 'CH2336J1B05'(!)   = ''              | ''                 | ''       | 'CH2336J1B05'     |'C0402'| '(C0402-0201)'                                                       | 'NA'       | '50V'         | '5%'     | 'IO'       | 'CAP CHIP 3300P 50V(+-5%,X7R,0402)MUR'                         | 'CHIP0402'     | ''          | ''   | '20220624'
 '3300PF'   | '50V'   | '5%'      | 'C0402'     | 'X7R'     | 'CH2336J1B07'(!)   = ''              | ''                 | ''       | 'CH2336J1B07'     |'C0402'| '(C0402-0201)'                                                       | '3300PF'   | '50V'         | '5%'     | 'DISCRETE' | 'CAP CHIP 3300P 50V(+-5%,X7R,0402)YGO'                         | 'CHIP0402'     | ''          | ''   | '20220630'
 '3300PF'   | '50V'   | '5%'      | 'C0402'     | 'EMPTY'   | 'CH2336J1B07'(!)   = ''              | ''                 | ''       | 'CH2336J1B07'     |'C0402'| '(C0402-0201)'                                                       | 'NA'       | '50V'         | '5%'     | 'IO'       | 'CAP CHIP 3300P 50V(+-5%,X7R,0402)YGO'                         | 'CHIP0402'     | ''          | ''   | '20220630'
 '2.2UF'    | '25V'   | '10%'     | 'C0402'     | 'X5R'     | 'CH5224K9B06'(!)   = ''              | ''                 | ''       | 'CH5224K9B06'     |'C0402_H28'| '(C0402-0201_H28)'                                                   | '2.2UF'    | '25V'         | '10%'    | 'DISCRETE' | 'CAP CHIP 2.2U 25V(+-10%,X5R,0402)MUR'                         | 'CHIP0402'     | ''          | ''   | '20220704'
 '2.2UF'    | '25V'   | '10%'     | 'C0402'     | 'EMPTY'   | 'CH5224K9B06'(!)   = ''              | ''                 | ''       | 'CH5224K9B06'     |'C0402_H28'| '(C0402-0201_H28)'                                                   | 'NA'       | '25V'         | '10%'    | 'IO'       | 'CAP CHIP 2.2U 25V(+-10%,X5R,0402)MUR'                         | 'CHIP0402'     | ''          | ''   | '20220704'
 '2.2UF'    | '25V'   | '10%'     | 'C0402'     | 'X5R'     | 'CH5224K9B07'(!)   = ''              | ''                 | ''       | 'CH5224K9B07'     |'C0402_H28'| '(C0402-0201_H28)'                                                   | '2.2UF'    | '25V'         | '10%'    | 'DISCRETE' | 'CAP CHIP 2.2U 25V(+-10%,X5R,0402)SAM'                         | 'CHIP0402'     | ''          | ''   | '20220705'
 '2.2UF'    | '25V'   | '10%'     | 'C0402'     | 'EMPTY'   | 'CH5224K9B07'(!)   = ''              | ''                 | ''       | 'CH5224K9B07'     |'C0402_H28'| '(C0402-0201_H28)'                                                   | 'NA'       | '25V'         | '10%'    | 'IO'       | 'CAP CHIP 2.2U 25V(+-10%,X5R,0402)SAM'                         | 'CHIP0402'     | ''          | ''   | '20220705'
 '2.2UF'    | '25V'   | '10%'     | 'C0402'     | 'X5R'     | 'CH5224K9B08'(!)   = ''              | ''                 | ''       | 'CH5224K9B08'     |'C0402_H28'| '(C0402-0201_H28)'                                                   | '2.2UF'    | '25V'         | '10%'    | 'DISCRETE' | 'CAP CHIP 2.2U 25V(+-10%,X5R,0402)WTC'                         | 'CHIP0402'     | ''          | ''   | '20220705'
 '2.2UF'    | '25V'   | '10%'     | 'C0402'     | 'EMPTY'   | 'CH5224K9B08'(!)   = ''              | ''                 | ''       | 'CH5224K9B08'     |'C0402_H28'| '(C0402-0201_H28)'                                                   | 'NA'       | '25V'         | '10%'    | 'IO'       | 'CAP CHIP 2.2U 25V(+-10%,X5R,0402)WTC'                         | 'CHIP0402'     | ''          | ''   | '20220705'
 '2.2UF'    | '6.3V'  | '20%'     | 'C0201'     | 'X6S'     | 'CH5221MEE00'(!)   = ''              | ''                 | ''       | 'CH5221MEE00'     |'C0201_H22'| '(C0201-0402_H22)'                                                   | '2.2UF'    | '6.3V'        | '20%'    | 'DISCRETE' | 'CAP CHIP 2.2UF 6.3V(+-20%,X6S,0201)'                          | 'CHIP0201'     | ''          | ''   | '20220715'
 '2.2UF'    | '6.3V'  | '20%'     | 'C0201'     | 'EMPTY'   | 'CH5221MEE00'(!)   = ''              | ''                 | ''       | 'CH5221MEE00'     |'C0201_H22'| '(C0201-0402_H22)'                                                   | 'NA'       | '6.3V'        | '20%'    | 'IO'       | 'CAP CHIP 2.2UF 6.3V(+-20%,X6S,0201)'                          | 'CHIP0201'     | ''          | ''   | '20220715'
 '820PF'    | '50V'   | '5%'      | 'C0402'     | 'NPO'     | 'CH1826J0B10'(!)   = ''              | ''                 | ''       | 'CH1826J0B10'     |'C0402'| '(C0402-0201)'                                                       | '820PF'    | '50V'         | '5%'     | 'DISCRETE' | 'CAP CHIP 820P 50V(+-5%,NPO,0402)MUR'                          | 'CHIP0402'     | ''          | ''   | '20220722'
 '820PF'    | '50V'   | '5%'      | 'C0402'     | 'EMPTY'   | 'CH1826J0B10'(!)   = ''              | ''                 | ''       | 'CH1826J0B10'     |'C0402'| '(C0402-0201)'                                                       | 'NA'       | '50V'         | '5%'     | 'IO'       | 'CAP CHIP 820P 50V(+-5%,NPO,0402)MUR'                          | 'CHIP0402'     | ''          | ''   | '20220722'
 '0.22UF'   | '10V'   | '10%'     | 'C0201'     | 'X5R'     | 'CH4222K9E00'(!)   = ''              | ''                 | ''       | 'CH4222K9E00'     |'C0201'| '(C0201_HOME-PLATE_H22)'                                             | '0.22UF'   | '10V'         | '10%'    | 'DISCRETE' | 'CAP CHIP 0.22UF 10V(+-10%,X5R,0201)MUR'                       | 'CHIP0201'     | ''          | ''   | '20220725'
 '0.22UF'   | '10V'   | '10%'     | 'C0201'     | 'EMPTY'   | 'CH4222K9E00'(!)   = ''              | ''                 | ''       | 'CH4222K9E00'     |'C0201'| '(C0201_HOME-PLATE_H22)'                                             | 'NA'       | '10V'         | '10%'    | 'IO'       | 'CAP CHIP 0.22UF 10V(+-10%,X5R,0201)MUR'                       | 'CHIP0201'     | ''          | ''   | '20220725'
 '22UF'     | '10V'   | '20%'     | 'C0603'     | 'X5R'     | 'CH6222M9905'(!)   = ''              | ''                 | ''       | 'CH6222M9905'     |'C0603_H40'| '(SMC0603AW)'                                                        | '22UF'     | '10V'         | '20%'    | 'DISCRETE' | 'CAP CHIP 22UF 10V(+-20%,X5R,0603)MUR'                         | 'CHIP0603'     | ''          | ''   | '20220725'
 '22UF'     | '10V'   | '20%'     | 'C0603'     | 'EMPTY'   | 'CH6222M9905'(!)   = ''              | ''                 | ''       | 'CH6222M9905'     |'C0603_H40'| '(SMC0603AW)'                                                        | 'NA'       | '10V'         | '20%'    | 'IO'       | 'CAP CHIP 22UF 10V(+-20%,X5R,0603)MUR'                         | 'CHIP0603'     | ''          | ''   | '20220725'
 '33NF'     | '50V'   | '10%'     | 'C0402'     | 'X7R'     | 'CH3336K1B00'(!)   = ''              | ''                 | ''       | 'CH3336K1B00'     |'C0402'| '(C0402-0201)'                                                       | '33NF'     | '50V'         | '10%'    | 'DISCRETE' | 'CAP CHIP 33NF 50V(+-10%,X7R,0402)'                            | 'CHIP0402'     | ''          | ''   | '20220816'
 '33NF'     | '50V'   | '10%'     | 'C0402'     | 'EMPTY'   | 'CH3336K1B00'(!)   = ''              | ''                 | ''       | 'CH3336K1B00'     |'C0402'| '(C0402-0201)'                                                       | 'NA'       | '50V'         | '10%'    | 'IO'       | 'CAP CHIP 33NF 50V(+-10%,X7R,0402)'                            | 'CHIP0402'     | ''          | ''   | '20220816'
 '0.022UF'  | '50V'   | '10%'     | 'C0402'     | 'X7R'     | 'CH3226K1B08'(!)   = ''              | ''                 | ''       | 'CH3226K1B08'     |'C0402'| '(C0402-0201)'                                                       | '0.022UF'  | '50V'         | '10%'    | 'DISCRETE' | 'CAP CHIP 0.022U 50V(+-10%,X7R,0402)MUR'                       | 'CHIP0402'     | ''          | ''   | '20220816'
 '0.022UF'  | '50V'   | '10%'     | 'C0402'     | 'EMPTY'   | 'CH3226K1B08'(!)   = ''              | ''                 | ''       | 'CH3226K1B08'     |'C0402'| '(C0402-0201)'                                                       | 'NA'       | '50V'         | '10%'    | 'IO'       | 'CAP CHIP 0.022U 50V(+-10%,X7R,0402)MUR'                       | 'CHIP0402'     | ''          | ''   | '20220816'
 '10UF'     | '100V'  | '10%'     | 'C1210'     | 'X7S'     | 'CH6108K6301'(!)   = ''              | ''                 | ''       | 'CH6108K6301'     |'C1210_GRM32E'| '(SMC1210AW)'                                                        | '10UF'     | '100V'        | '10%'    | 'DISCRETE' | 'CAP CHIP 10UF 100V(+-10%,X7S,1210)'                           | 'CHIP1210'     | ''          | ''   | '20220826'
 '10UF'     | '100V'  | '10%'     | 'C1210'     | 'EMPTY'   | 'CH6108K6301'(!)   = ''              | ''                 | ''       | 'CH6108K6301'     |'C1210_GRM32E'| '(SMC1210AW)'                                                        | 'NA'       | '100V'        | '10%'    | 'IO'       | 'CAP CHIP 10UF 100V(+-10%,X7S,1210)'                           | 'CHIP1210'     | ''          | ''   | '20220826'
 '2200PF'   | '50V'   | '5%'      | 'C0603'     | 'C0G'     | 'CH2226J0903'(!)   = ''              | ''                 | ''       | 'CH2226J0903'     |'C0603'| '(SMC0603AW)'                                                        | '2200PF'   | '50V'         | '5%'     | 'DISCRETE' | 'CAP CHIP 2200PF 50V(+-5%,C0G,0603)MUR'                        | 'CHIP0603'     | ''          | ''   | '20220826'
 '2200PF'   | '50V'   | '5%'      | 'C0603'     | 'EMPTY'   | 'CH2226J0903'(!)   = ''              | ''                 | ''       | 'CH2226J0903'     |'C0603'| '(SMC0603AW)'                                                        | 'NA'       | '50V'         | '5%'     | 'IO'       | 'CAP CHIP 2200PF 50V(+-5%,C0G,0603)MUR'                        | 'CHIP0603'     | ''          | ''   | '20220826'
 '1500PF'   | '50V'   | '5%'      | 'C0603'     | 'C0G'     | 'CH2156J0900'(!)   = ''              | ''                 | ''       | 'CH2156J0900'     |'C0603'| '(SMC0603AW)'                                                        | '1500PF'   | '50V'         | '5%'     | 'DISCRETE' | 'CAP CHIP 1500P 50V(+-5%,C0G,0603)MUR'                         | 'CHIP0603'     | ''          | ''   | '20220826'
 '1500PF'   | '50V'   | '5%'      | 'C0603'     | 'EMPTY'   | 'CH2156J0900'(!)   = ''              | ''                 | ''       | 'CH2156J0900'     |'C0603'| '(SMC0603AW)'                                                        | 'NA'       | '50V'         | '5%'     | 'IO'       | 'CAP CHIP 1500P 50V(+-5%,C0G,0603)MUR'                         | 'CHIP0603'     | ''          | ''   | '20220826'
 '4.7UF'    | '10V'   | '20%'     | 'C0402'     | 'X6S'     | 'CH5472MEB00'(!)   = ''              | ''                 | ''       | 'CH5472MEB00'     |'C0402_H28'| '(C0402-0201_H28)'                                                   | '4.7UF'    | '10V'         | '20%'    | 'DISCRETE' | 'CAP CHIP 4.7U 10V(+-20%,X6S,0402)'                            | 'CHIP0402'     | ''          | ''   | '20220826'
 '4.7UF'    | '10V'   | '20%'     | 'C0402'     | 'EMPTY'   | 'CH5472MEB00'(!)   = ''              | ''                 | ''       | 'CH5472MEB00'     |'C0402_H28'| '(C0402-0201_H28)'                                                   | 'NA'       | '10V'         | '20%'    | 'IO'       | 'CAP CHIP 4.7U 10V(+-20%,X6S,0402)'                            | 'CHIP0402'     | ''          | ''   | '20220826'
 '10NF'     | '10V'   | '10%'     | 'C0201'     | 'X7R'     | 'CH3102K1E06'(!)   = ''              | ''                 | ''       | 'CH3102K1E06'     |'C0201'| '(SMC0201AW)'                                                        | '10NF'     | '10V'         | '10%'    | 'DISCRETE' | 'CAP CHIP 10NF 10V(+-10%,X7R,0201)MUR'                         | 'CHIP0201'     | ''          | ''   | '20220901'
 '10NF'     | '10V'   | '10%'     | 'C0201'     | 'EMPTY'   | 'CH3102K1E06'(!)   = ''              | ''                 | ''       | 'CH3102K1E06'     |'C0201'| '(SMC0201AW)'                                                        | 'NA'       | '10V'         | '10%'    | 'IO'       | 'CAP CHIP 10NF 10V(+-10%,X7R,0201)MUR'                         | 'CHIP0201'     | ''          | ''   | '20220901'
 '4700PF'   | '2KV'   | '10%'     | 'C1812'     | 'X7R'     | 'CH247IK1400'(!)   = ''              | ''                 | ''       | 'CH247IK1400'     |'C1812XD'| '(SMC1812AW)'                                                        | '4700PF'   | '2KV'         | '10%'    | 'DISCRETE' | 'CAP CHIP 4700P 2KV(+-10%,X7R,1812)'                           | 'CHIP1812'     | ''          | ''   | '20220905'
 '4700PF'   | '2KV'   | '10%'     | 'C1812'     | 'EMPTY'   | 'CH247IK1400'(!)   = ''              | ''                 | ''       | 'CH247IK1400'     |'C1812XD'| '(SMC1812AW)'                                                        | 'NA'       | '2KV'         | '10%'    | 'IO'       | 'CAP CHIP 4700P 2KV(+-10%,X7R,1812)'                           | 'CHIP1812'     | ''          | ''   | '20220905'
 '0.01UF'   | '25V'   | '10%'     | 'C0402'     | 'X7R'     | 'CH3104K1B12'(!)   = ''              | ''                 | ''       | 'CH3104K1B12'     |'C0402'| '(C0402-0201)'                                                       | '0.01UF'   | '25V'         | '10%'    | 'DISCRETE' | 'CAP CHIP 0.01U 25V(+-10%,X7R,0402)SAM'                        | 'CHIP0402'     | ''          | ''   | '20220926'
 '0.01UF'   | '25V'   | '10%'     | 'C0402'     | 'EMPTY'   | 'CH3104K1B12'(!)   = ''              | ''                 | ''       | 'CH3104K1B12'     |'C0402'| '(C0402-0201)'                                                       | 'NA'       | '25V'         | '10%'    | 'IO'       | 'CAP CHIP 0.01U 25V(+-10%,X7R,0402)SAM'                        | 'CHIP0402'     | ''          | ''   | '20220926'
 '470PF'    | '50V'   | '10%'     | 'C0402'     | 'X7R'     | 'CH1476K1B14'(!)   = ''              | ''                 | ''       | 'CH1476K1B14'     |'C0402'| '(C0402-0201)'                                                       | '470PF'    | '50V'         | '10%'    | 'DISCRETE' | 'CAP CHIP 470P 50V(+-10%,X7R,0402)SAM'                         | 'CHIP0402'     | ''          | ''   | '20220926'
 '470PF'    | '50V'   | '10%'     | 'C0402'     | 'EMPTY'   | 'CH1476K1B14'(!)   = ''              | ''                 | ''       | 'CH1476K1B14'     |'C0402'| '(C0402-0201)'                                                       | 'NA'       | '50V'         | '10%'    | 'IO'       | 'CAP CHIP 470P 50V(+-10%,X7R,0402)SAM'                         | 'CHIP0402'     | ''          | ''   | '20220926'
 '22UF'     | '6.3V'  | '20%'     | 'C0805'     | 'X7T'     | 'CH6221MJA01'(!)   = 'End of Design' | 'Comp-Release Qty' | ''       | 'CH6221MJA01'     |'C0805_H57'| '(SMC0805AW)'                                                        | '22UF'     | '6.3V'        | '20%'    | 'DISCRETE' | 'CAP CHIP 22U 6.3V(+-20%,X7T,0805)'                            | 'CHIP0805'     | ''          | ''   | '20220929'
 '22UF'     | '6.3V'  | '20%'     | 'C0805'     | 'EMPTY'   | 'CH6221MJA01'(!)   = 'End of Design' | 'Comp-Release Qty' | ''       | 'CH6221MJA01'     |'C0805_H57'| '(SMC0805AW)'                                                        | 'NA'       | '6.3V'        | '20%'    | 'IO'       | 'CAP CHIP 22U 6.3V(+-20%,X7T,0805)'                            | 'CHIP0805'     | ''          | ''   | '20220929'
 '0.22UF'   | '6.3V'  | '10%'     | 'C0201'     | 'X6S'     | 'CH4221KEE04'(!)   = ''              | ''                 | ''       | 'CH4221KEE04'     |'C0201'| '(SMC0201AW)'                                                        | '0.22UF'   | '6.3V'        | '10%'    | 'DISCRETE' | 'CAP CHIP 0.22UF 6.3V(+-10%,X6S,0201)SAM'                      | 'CHIP0201'     | ''          | ''   | '20221017'
 '0.22UF'   | '6.3V'  | '10%'     | 'C0201'     | 'EMPTY'   | 'CH4221KEE04'(!)   = ''              | ''                 | ''       | 'CH4221KEE04'     |'C0201'| '(SMC0201AW)'                                                        | 'NA'       | '6.3V'        | '10%'    | 'IO'       | 'CAP CHIP 0.22UF 6.3V(+-10%,X6S,0201)SAM'                      | 'CHIP0201'     | ''          | ''   | '20221017'
 '1UF'      | '25V'   | '10%'     | 'C0603'     | 'X7R'     | 'CH5104K1909'(!)   = ''              | ''                 | ''       | 'CH5104K1909'     |'C0603'| '(SMC0603AW)'                                                        | '1UF'      | '25V'         | '10%'    | 'DISCRETE' | 'CAP CHIP 1U 25V(+-10%,X7R,0603)YGO'                           | 'CHIP0603'     | ''          | ''   | '20221017'
 '1UF'      | '25V'   | '10%'     | 'C0603'     | 'EMPTY'   | 'CH5104K1909'(!)   = ''              | ''                 | ''       | 'CH5104K1909'     |'C0603'| '(SMC0603AW)'                                                        | 'NA'       | '25V'         | '10%'    | 'IO'       | 'CAP CHIP 1U 25V(+-10%,X7R,0603)YGO'                           | 'CHIP0603'     | ''          | ''   | '20221017'
 '10PF'     | '50V'   | '2%'      | 'C0402'     | 'NPO'     | 'CH0106G0B07'(!)   = ''              | ''                 | ''       | 'CH0106G0B07'     |'C0402'| '(C0402-0201)'                                                       | '10PF'     | '50V'         | '2%'     | 'DISCRETE' | 'CAP CHIP 10P 50V(+-2%,NPO,0402)YGO'                           | 'CHIP0402'     | ''          | ''   | '20221017'
 '10PF'     | '50V'   | '2%'      | 'C0402'     | 'EMPTY'   | 'CH0106G0B07'(!)   = ''              | ''                 | ''       | 'CH0106G0B07'     |'C0402'| '(C0402-0201)'                                                       | 'NA'       | '50V'         | '2%'     | 'IO'       | 'CAP CHIP 10P 50V(+-2%,NPO,0402)YGO'                           | 'CHIP0402'     | ''          | ''   | '20221017'
 '10UF'     | '25V'   | '10%'     | 'C0805'     | 'X6S'     | 'CH6104KEA08'(!)   = ''              | ''                 | ''       | 'CH6104KEA08'     |'C0805_H57'| '(SMC0805AW)'                                                        | '10UF'     | '25V'         | '10%'    | 'DISCRETE' | 'CAP CHIP 10U 25V(+-10%,X6S,0805)TAY'                          | 'CHIP0805'     | ''          | ''   | '20221017'
 '10UF'     | '25V'   | '10%'     | 'C0805'     | 'EMPTY'   | 'CH6104KEA08'(!)   = ''              | ''                 | ''       | 'CH6104KEA08'     |'C0805_H57'| '(SMC0805AW)'                                                        | 'NA'       | '25V'         | '10%'    | 'IO'       | 'CAP CHIP 10U 25V(+-10%,X6S,0805)TAY'                          | 'CHIP0805'     | ''          | ''   | '20221017'
 '0.1UF'    | '10V'   | '10%'     | 'C0201'     | 'X7S'     | 'CH4102K6E00'(!)   = 'End of Design' | 'Comp-Approve'     | ''       | 'CH4102K6E00'     |'C0201'| '(SMC0201AW)'                                                        | '0.1UF'    | '10V'         | '10%'    | 'DISCRETE' | 'CAP CHIP 0.1U 10V(+-10%,X7S,0201)'                            | 'CHIP0201'     | ''          | ''   | '20221017'
 '0.1UF'    | '10V'   | '10%'     | 'C0201'     | 'EMPTY'   | 'CH4102K6E00'(!)   = 'End of Design' | 'Comp-Approve'     | ''       | 'CH4102K6E00'     |'C0201'| '(SMC0201AW)'                                                        | 'NA'       | '10V'         | '10%'    | 'IO'       | 'CAP CHIP 0.1U 10V(+-10%,X7S,0201)'                            | 'CHIP0201'     | ''          | ''   | '20221017'
 '12PF'     | '50V'   | '5%'      | 'C0402'     | 'C0G'     | 'CH0126J0B13'(!)   = ''              | ''                 | ''       | 'CH0126J0B13'     |'C0402'| '(C0402-0201)'                                                       | '12PF'     | '50V'         | '5%'     | 'DISCRETE' | 'CAP CHIP 12P 50V(+-5%,C0G,0402)MUR'                           | 'CHIP0402'     | ''          | ''   | '20221019'
 '12PF'     | '50V'   | '5%'      | 'C0402'     | 'EMPTY'   | 'CH0126J0B13'(!)   = ''              | ''                 | ''       | 'CH0126J0B13'     |'C0402'| '(C0402-0201)'                                                       | 'NA'       | '50V'         | '5%'     | 'IO'       | 'CAP CHIP 12P 50V(+-5%,C0G,0402)MUR'                           | 'CHIP0402'     | ''          | ''   | '20221019'
 '1NF'      | '25V'   | '10%'     | 'C0201'     | 'X7R'     | 'CH2104K1E04'(!)   = ''              | ''                 | ''       | 'CH2104K1E04'     |'C0201'| '(SMC0201AW)'                                                        | '1NF'      | '25V'         | '10%'    | 'DISCRETE' | 'CAP CHIP 1NF 25V(+-10%,X7R,0201)MUR'                          | 'CHIP0201'     | ''          | ''   | '20221019'
 '1NF'      | '25V'   | '10%'     | 'C0201'     | 'EMPTY'   | 'CH2104K1E04'(!)   = ''              | ''                 | ''       | 'CH2104K1E04'     |'C0201'| '(SMC0201AW)'                                                        | 'NA'       | '25V'         | '10%'    | 'IO'       | 'CAP CHIP 1NF 25V(+-10%,X7R,0201)MUR'                          | 'CHIP0201'     | ''          | ''   | '20221019'
 '1.8PF'    | '50V'   | '0.1PF'   | 'C0402'     | 'NPO'     | 'CH-186B0B03'(!)   = ''              | ''                 | ''       | 'CH-186B0B03'     |'C0402'| '(C0402-0201)'                                                       | '1.8PF'    | '50V'         | '0.1PF'  | 'DISCRETE' | 'CAP CHIP 1.8P 50V(+-0.1P,NPO,0402)MUR'                        | 'CHIP0402'     | ''          | ''   | '20221101'
 '1.8PF'    | '50V'   | '0.1PF'   | 'C0402'     | 'EMPTY'   | 'CH-186B0B03'(!)   = ''              | ''                 | ''       | 'CH-186B0B03'     |'C0402'| '(C0402-0201)'                                                       | 'NA'       | '50V'         | '0.1PF'  | 'IO'       | 'CAP CHIP 1.8P 50V(+-0.1P,NPO,0402)MUR'                        | 'CHIP0402'     | ''          | ''   | '20221101'
 '0.33UF'   | '6.3V'  | '10%'     | 'C0402'     | 'X6S'     | 'CH4331KEB02'(!)   = ''              | ''                 | ''       | 'CH4331KEB02'     |'C0402'| '(C0402-0201)'                                                       | '0.33UF'   | '6.3V'        | '10%'    | 'DISCRETE' | 'CAP CHIP 0.33UF 6.3V(10%,X6S,0402)MUR'                        | 'CHIP0402'     | ''          | ''   | '20221101'
 '0.33UF'   | '6.3V'  | '10%'     | 'C0402'     | 'EMPTY'   | 'CH4331KEB02'(!)   = ''              | ''                 | ''       | 'CH4331KEB02'     |'C0402'| '(C0402-0201)'                                                       | 'NA'       | '6.3V'        | '10%'    | 'IO'       | 'CAP CHIP 0.33UF 6.3V(10%,X6S,0402)MUR'                        | 'CHIP0402'     | ''          | ''   | '20221101'
 '10PF'     | '50V'   | '1%'      | 'C0402'     | 'NPO'     | 'CH0106F0B07'(!)   = ''              | ''                 | ''       | 'CH0106F0B07'     |'C0402'| '(C0402-0201)'                                                       | '10PF'     | '50V'         | '1%'     | 'DISCRETE' | 'CAP CHIP 10PF 50V(+-1%,NPO,0402)MUR'                          | 'CHIP0402'     | ''          | ''   | '20221101'
 '10PF'     | '50V'   | '1%'      | 'C0402'     | 'EMPTY'   | 'CH0106F0B07'(!)   = ''              | ''                 | ''       | 'CH0106F0B07'     |'C0402'| '(C0402-0201)'                                                       | 'NA'       | '50V'         | '1%'     | 'IO'       | 'CAP CHIP 10PF 50V(+-1%,NPO,0402)MUR'                          | 'CHIP0402'     | ''          | ''   | '20221101'
 '120PF'    | '50V'   | '5%'      | 'C0402'     | 'NPO'     | 'CH1126J0B14'(!)   = ''              | ''                 | ''       | 'CH1126J0B14'     |'C0402'| '(C0402-0201)'                                                       | '120PF'    | '50V'         | '5%'     | 'DISCRETE' | 'CAP CHIP 120P 50V(+-5%,NPO,0402)MUR'                          | 'CHIP0402'     | ''          | ''   | '20221101'
 '120PF'    | '50V'   | '5%'      | 'C0402'     | 'EMPTY'   | 'CH1126J0B14'(!)   = ''              | ''                 | ''       | 'CH1126J0B14'     |'C0402'| '(C0402-0201)'                                                       | 'NA'       | '50V'         | '5%'     | 'IO'       | 'CAP CHIP 120P 50V(+-5%,NPO,0402)MUR'                          | 'CHIP0402'     | ''          | ''   | '20221101'
 '2.2UF'    | '16V'   | '10%'     | 'C0402'     | 'X6S'     | 'CH5223KEB03'(!)   = ''              | ''                 | ''       | 'CH5223KEB03'     |'C0402_H28'| '(C0402-0201_H28)'                                                   | '2.2UF'    | '16V'         | '10%'    | 'DISCRETE' | 'CAP CHIP 2.2U 16V(+-10%,X6S,0402)MUR'                         | 'CHIP0402'     | ''          | ''   | '20221101'
 '2.2UF'    | '16V'   | '10%'     | 'C0402'     | 'EMPTY'   | 'CH5223KEB03'(!)   = ''              | ''                 | ''       | 'CH5223KEB03'     |'C0402_H28'| '(C0402-0201_H28)'                                                   | 'NA'       | '16V'         | '10%'    | 'IO'       | 'CAP CHIP 2.2U 16V(+-10%,X6S,0402)MUR'                         | 'CHIP0402'     | ''          | ''   | '20221101'
 '22UF'     | '16V'   | '20%'     | 'C0805'     | 'X6S'     | 'CH6223MEA05'(!)   = ''              | ''                 | ''       | 'CH6223MEA05'     |'C0805_H57'| '(SMC0805AW)'                                                        | '22UF'     | '16V'         | '20%'    | 'DISCRETE' | 'CAP CHIP 22U 16V(+-20%,X6S,0805)TAY'                          | 'CHIP0805'     | ''          | ''   | '20221130'
 '22UF'     | '16V'   | '20%'     | 'C0805'     | 'EMPTY'   | 'CH6223MEA05'(!)   = ''              | ''                 | ''       | 'CH6223MEA05'     |'C0805_H57'| '(SMC0805AW)'                                                        | 'NA'       | '16V'         | '20%'    | 'IO'       | 'CAP CHIP 22U 16V(+-20%,X6S,0805)TAY'                          | 'CHIP0805'     | ''          | ''   | '20221130'
 '22UF'     | '4V'    | '20%'     | 'C0805'     | 'X6S'     | 'CH622KMEA05'(!)   = ''              | ''                 | ''       | 'CH622KMEA05'     |'C0805_H57'| '(SMC0805AW)'                                                        | '22UF'     | '4V'          | '20%'    | 'DISCRETE' | 'CAP CHIP 22U 4V(+-20%,X6S,0805)TAY'                           | 'CHIP0805'     | ''          | ''   | '20221130'
 '22UF'     | '4V'    | '20%'     | 'C0805'     | 'EMPTY'   | 'CH622KMEA05'(!)   = ''              | ''                 | ''       | 'CH622KMEA05'     |'C0805_H57'| '(SMC0805AW)'                                                        | 'NA'       | '4V'          | '20%'    | 'IO'       | 'CAP CHIP 22U 4V(+-20%,X6S,0805)TAY'                           | 'CHIP0805'     | ''          | ''   | '20221130'
 '10UF'     | '25V'   | '10%'     | 'C0805'     | 'X6S'     | 'CH6104KEA04'(!)   = ''              | ''                 | ''       | 'CH6104KEA04'     |'C0805_H57'| '(SMC0805AW)'                                                        | '10UF'     | '25V'         | '10%'    | 'DISCRETE' | 'CAP CHIP 10U 25V(10%,X6S,0805,H1.25)SAM'                      | 'CHIP0805'     | ''          | ''   | '20221208'
 '10UF'     | '25V'   | '10%'     | 'C0805'     | 'EMPTY'   | 'CH6104KEA04'(!)   = ''              | ''                 | ''       | 'CH6104KEA04'     |'C0805_H57'| '(SMC0805AW)'                                                        | 'NA'       | '25V'         | '10%'    | 'IO'       | 'CAP CHIP 10U 25V(10%,X6S,0805,H1.25)SAM'                      | 'CHIP0805'     | ''          | ''   | '20221208'
 '1PF'      | '50V'   | '0.05PF'  | 'C0402'     | 'C0G'     | 'CH-106T0B04'(!)   = ''              | ''                 | ''       | 'CH-106T0B04'     |'C0402'| '(C0402-0201)'                                                       | '1PF'      | '50V'         | '0.05PF' | 'DISCRETE' | 'CAP CHIP 1P 50V(+-0.05P,C0G,0402)WTC'                         | 'CHIP0402'     | ''          | ''   | '20221223'
 '1PF'      | '50V'   | '0.05PF'  | 'C0402'     | 'EMPTY'   | 'CH-106T0B04'(!)   = ''              | ''                 | ''       | 'CH-106T0B04'     |'C0402'| '(C0402-0201)'                                                       | 'NA'       | '50V'         | '0.05PF' | 'IO'       | 'CAP CHIP 1P 50V(+-0.05P,C0G,0402)WTC'                         | 'CHIP0402'     | ''          | ''   | '20221223'
 '150PF'    | '50V'   | '5%'      | 'C0402'     | 'NPO'     | 'CH1156J0B07'(!)   = ''              | ''                 | ''       | 'CH1156J0B07'     |'C0402'| '(C0402-0201)'                                                       | '150PF'    | '50V'         | '5%'     | 'DISCRETE' | 'CAP CHIP 150P 50V(+-5%,NPO,0402)WTC'                          | 'CHIP0402'     | ''          | ''   | '20221223'
 '150PF'    | '50V'   | '5%'      | 'C0402'     | 'EMPTY'   | 'CH1156J0B07'(!)   = ''              | ''                 | ''       | 'CH1156J0B07'     |'C0402'| '(C0402-0201)'                                                       | 'NA'       | '50V'         | '5%'     | 'IO'       | 'CAP CHIP 150P 50V(+-5%,NPO,0402)WTC'                          | 'CHIP0402'     | ''          | ''   | '20221223'
 '10UF'     | '10V'   | '20%'     | 'C0402'     | 'X5R'     | 'CH6102M9B09'(!)   = ''              | ''                 | ''       | 'CH6102M9B09'     |'C0402_H28'| '(C0402-0201_H28)'                                                   | '10UF'     | '10V'         | '20%'    | 'DISCRETE' | 'CAP CHIP 10U 10V(+-20%, X5R,0402)MUR'                         | 'CHIP0402'     | ''          | ''   | '20221223'
 '10UF'     | '10V'   | '20%'     | 'C0402'     | 'EMPTY'   | 'CH6102M9B09'(!)   = ''              | ''                 | ''       | 'CH6102M9B09'     |'C0402_H28'| '(C0402-0201_H28)'                                                   | 'NA'       | '10V'         | '20%'    | 'IO'       | 'CAP CHIP 10U 10V(+-20%, X5R,0402)MUR'                         | 'CHIP0402'     | ''          | ''   | '20221223'
 '2.2UF'    | '25V'   | '10%'     | 'C0402'     | 'X6S'     | 'CH5224KEB00'(!)   = ''              | ''                 | ''       | 'CH5224KEB00'     |'C0402_H28'| '(C0402-0201_H28)'                                                   | '2.2UF'    | '25V'         | '10%'    | 'DISCRETE' | 'CAP CHIP 2.2U 25V(+-10%,X6S,0402)MUR'                         | 'CHIP0402'     | ''          | ''   | '20221226'
 '2.2UF'    | '25V'   | '10%'     | 'C0402'     | 'EMPTY'   | 'CH5224KEB00'(!)   = ''              | ''                 | ''       | 'CH5224KEB00'     |'C0402_H28'| '(C0402-0201_H28)'                                                   | 'NA'       | '25V'         | '10%'    | 'IO'       | 'CAP CHIP 2.2U 25V(+-10%,X6S,0402)MUR'                         | 'CHIP0402'     | ''          | ''   | '20221226'
 '3.9PF'    | '50V'   | '0.1PF'   | 'C0402'     | 'NP0'     | 'CH-396B0B01'(!)   = ''              | ''                 | ''       | 'CH-396B0B01'     |'C0402'| '(C0402-0201)'                                                       | '3.9PF'    | '50V'         | '0.1PF'  | 'DISCRETE' | 'CAP CHIP 3.9P 50V(+-0.1P,NP0,0402)WTC'                        | 'CHIP0402'     | ''          | ''   | '20221227'
 '3.9PF'    | '50V'   | '0.1PF'   | 'C0402'     | 'EMPTY'   | 'CH-396B0B01'(!)   = ''              | ''                 | ''       | 'CH-396B0B01'     |'C0402'| '(C0402-0201)'                                                       | 'NA'       | '50V'         | '0.1PF'  | 'IO'       | 'CAP CHIP 3.9P 50V(+-0.1P,NP0,0402)WTC'                        | 'CHIP0402'     | ''          | ''   | '20221227'
 '10PF'     | '50V'   | '1%'      | 'C0402'     | 'NPO'     | 'CH0106F0B08'(!)   = ''              | ''                 | ''       | 'CH0106F0B08'     |'C0402'| '(C0402-0201)'                                                       | '10PF'     | '50V'         | '1%'     | 'DISCRETE' | 'CAP CHIP 10PF 50V(+-1%,NPO,0402)WTC'                          | 'CHIP0402'     | ''          | ''   | '20230104'
 '10PF'     | '50V'   | '1%'      | 'C0402'     | 'EMPTY'   | 'CH0106F0B08'(!)   = ''              | ''                 | ''       | 'CH0106F0B08'     |'C0402'| '(C0402-0201)'                                                       | 'NA'       | '50V'         | '1%'     | 'IO'       | 'CAP CHIP 10PF 50V(+-1%,NPO,0402)WTC'                          | 'CHIP0402'     | ''          | ''   | '20230104'
 '1.8PF'    | '50V'   | '0.1PF'   | 'C0402'     | 'NPO'     | 'CH-186B0B05'(!)   = ''              | ''                 | ''       | 'CH-186B0B05'     |'C0402'| '(C0402-0201)'                                                       | '1.8PF'    | '50V'         | '0.1PF'  | 'DISCRETE' | 'CAP CHIP 1.8P 50V(+-0.1P,NPO,0402)WTC'                        | 'CHIP0402'     | ''          | ''   | '20230104'
 '1.8PF'    | '50V'   | '0.1PF'   | 'C0402'     | 'EMPTY'   | 'CH-186B0B05'(!)   = ''              | ''                 | ''       | 'CH-186B0B05'     |'C0402'| '(C0402-0201)'                                                       | 'NA'       | '50V'         | '0.1PF'  | 'IO'       | 'CAP CHIP 1.8P 50V(+-0.1P,NPO,0402)WTC'                        | 'CHIP0402'     | ''          | ''   | '20230104'
 '120PF'    | '50V'   | '5%'      | 'C0402'     | 'NPO'     | 'CH1126J0B09'(!)   = ''              | ''                 | ''       | 'CH1126J0B09'     |'C0402'| '(C0402-0201)'                                                       | '120PF'    | '50V'         | '5%'     | 'DISCRETE' | 'CAP CHIP 120P 50V(+-5%,NPO,0402)WTC'                          | 'CHIP0402'     | ''          | ''   | '20230104'
 '120PF'    | '50V'   | '5%'      | 'C0402'     | 'EMPTY'   | 'CH1126J0B09'(!)   = ''              | ''                 | ''       | 'CH1126J0B09'     |'C0402'| '(C0402-0201)'                                                       | 'NA'       | '50V'         | '5%'     | 'IO'       | 'CAP CHIP 120P 50V(+-5%,NPO,0402)WTC'                          | 'CHIP0402'     | ''          | ''   | '20230104'
 '0.33UF'   | '6.3V'  | '10%'     | 'C0402'     | 'X6S'     | 'CH4331KEB03'(!)   = ''              | ''                 | ''       | 'CH4331KEB03'     |'C0402'| '(C0402-0201)'                                                       | '0.33UF'   | '6.3V'        | '10%'    | 'DISCRETE' | 'CAP CHIP 0.33U 6.3V(+-10%,X6S,0402)API'                       | 'CHIP0402'     | ''          | ''   | '20230106'
 '0.33UF'   | '6.3V'  | '10%'     | 'C0402'     | 'EMPTY'   | 'CH4331KEB03'(!)   = ''              | ''                 | ''       | 'CH4331KEB03'     |'C0402'| '(C0402-0201)'                                                       | 'NA'       | '6.3V'        | '10%'    | 'IO'       | 'CAP CHIP 0.33U 6.3V(+-10%,X6S,0402)API'                       | 'CHIP0402'     | ''          | ''   | '20230106'
 '1000PF'   | '100V'  | '10%'     | 'C0402'     | 'X7R'     | 'CH2108K1B03'(!)   = ''              | ''                 | ''       | 'CH2108K1B03'     |'C0402_OCTAGONXA_BOUND22'| '(SMC0402AW)'                                                        | '1000PF'   | '100V'        | '10%'    | 'DISCRETE' | 'CAP CHIP 1000P 100V(+-10%,X7R,0402)MUR_OCTAGON'               | 'CHIP0402'     | ''          | ''   | '20230221'
 '1000PF'   | '100V'  | '10%'     | 'C0402'     | 'EMPTY'   | 'CH2108K1B03'(!)   = ''              | ''                 | ''       | 'CH2108K1B03'     |'C0402_OCTAGONXA_BOUND22'| '(SMC0402AW)'                                                        | 'NA'       | '100V'        | '10%'    | 'IO'       | 'CAP CHIP 1000P 100V(+-10%,X7R,0402)MUR_OCTAGON'               | 'CHIP0402'     | ''          | ''   | '20230221'
 '2.7PF'    | '50V'   | '0.1PF'   | 'C0402'     | 'NPO'     | 'CH-276B0B00'(!)   = ''              | ''                 | ''       | 'CH-276B0B00'     |'C0402'| '(C0402-0201)'                                                       | '2.7PF'    | '50V'         | '0.1PF'  | 'DISCRETE' | 'CAP CHIP 2.7P 50V(+-0.1P,NPO,0402)'                           | 'CHIP0402'     | ''          | ''   | '20230316'
 '2.7PF'    | '50V'   | '0.1PF'   | 'C0402'     | 'EMPTY'   | 'CH-276B0B00'(!)   = ''              | ''                 | ''       | 'CH-276B0B00'     |'C0402'| '(C0402-0201)'                                                       | 'NA'       | '50V'         | '0.1PF'  | 'IO'       | 'CAP CHIP 2.7P 50V(+-0.1P,NPO,0402)'                           | 'CHIP0402'     | ''          | ''   | '20230316'
 '620PF'    | '25V'   | '5%'      | 'C0603'     | 'C0G'     | 'CH1624J0900'(!)   = ''              | ''                 | ''       | 'CH1624J0900'     |'C0603'| '(SMC0603AW)'                                                        | '620PF'    | '25V'         | '5%'     | 'DISCRETE' | 'CAP CHIP 620PF 25V(+-5%,C0G,0603)'                            | 'CHIP0603'     | ''          | ''   | '20230407'
 '620PF'    | '25V'   | '5%'      | 'C0603'     | 'EMPTY'   | 'CH1624J0900'(!)   = ''              | ''                 | ''       | 'CH1624J0900'     |'C0603'| '(SMC0603AW)'                                                        | 'NA'       | '25V'         | '5%'     | 'IO'       | 'CAP CHIP 620PF 25V(+-5%,C0G,0603)'                            | 'CHIP0603'     | ''          | ''   | '20230407'
 '100PF'    | '100V'  | '5%'      | 'C0805'     | 'NPO'     | 'CH1108J0A00'(!)   = ''              | ''                 | ''       | 'CH1108J0A00'     |'C0805'| '(SMC0805AW)'                                                        | '100PF'    | '100V'        | '5%'     | 'DISCRETE' | 'CAP CHIP 100P,100V(+-5%,NPO,0805)'                            | 'CHIP0805'     | ''          | ''   | '20230504'
 '100PF'    | '100V'  | '5%'      | 'C0805'     | 'EMPTY'   | 'CH1108J0A00'(!)   = ''              | ''                 | ''       | 'CH1108J0A00'     |'C0805'| '(SMC0805AW)'                                                        | 'NA'       | '100V'        | '5%'     | 'IO'       | 'CAP CHIP 100P,100V(+-5%,NPO,0805)'                            | 'CHIP0805'     | ''          | ''   | '20230504'
 '180PF'    | '50V'   | '5%'      | 'C0402'     | 'NPO'     | 'CH1186J0B16'(!)   = ''              | ''                 | ''       | 'CH1186J0B16'     |'C0402'| '(C0402-0201)'                                                       | '180PF'    | '50V'         | '5%'     | 'DISCRETE' | 'CAP CHIP 180P 50V(+-5%,NPO,0402)WTC'                          | 'CHIP0402'     | ''          | ''   | '20230515'
 '180PF'    | '50V'   | '5%'      | 'C0402'     | 'EMPTY'   | 'CH1186J0B16'(!)   = ''              | ''                 | ''       | 'CH1186J0B16'     |'C0402'| '(C0402-0201)'                                                       | 'NA'       | '50V'         | '5%'     | 'IO'       | 'CAP CHIP 180P 50V(+-5%,NPO,0402)WTC'                          | 'CHIP0402'     | ''          | ''   | '20230515'
 '1000PF'   | '100V'  | '10%'     | 'C0603'     | 'X7R'     | 'CH21008K918'(!)   = ''              | ''                 | ''       | 'CH21008K918'     |'C0603'| '(SMC0603AW)'                                                        | '1000PF'   | '100V'        | '10%'    | 'DISCRETE' | 'CAP CHIP 1000P,100V(+-10%,X7R,0603)'                          | 'CHIP0603'     | ''          | ''   | '20230526'
 '1000PF'   | '100V'  | '10%'     | 'C0603'     | 'EMPTY'   | 'CH21008K918'(!)   = ''              | ''                 | ''       | 'CH21008K918'     |'C0603'| '(SMC0603AW)'                                                        | 'NA'       | '100V'        | '10%'    | 'IO'       | 'CAP CHIP 1000P,100V(+-10%,X7R,0603)'                          | 'CHIP0603'     | ''          | ''   | '20230526'
 '47UF'     | '4V'    | '20%'     | 'C0603'     | 'X6S'     | 'CH647KME901'(!)   = ''              | ''                 | ''       | 'CH647KME901'     |'C0603_H40'| '(C0603_BHS-SP)'                                                     | '47UF'     | '4V'          | '20%'    | 'DISCRETE' | 'CAP CHIP 47U 4V(+-20%,X6S,0603)TAY'                           | 'CHIP0603'     | ''          | ''   | '20230606'
 '47UF'     | '4V'    | '20%'     | 'C0603'     | 'EMPTY'   | 'CH647KME901'(!)   = ''              | ''                 | ''       | 'CH647KME901'     |'C0603_H40'| '(C0603_BHS-SP)'                                                     | 'NA'       | '4V'          | '20%'    | 'IO'       | 'CAP CHIP 47U 4V(+-20%,X6S,0603)TAY'                           | 'CHIP0603'     | ''          | ''   | '20230606'
 '330PF'    | '50V'   | '5%'      | 'C0402'     | 'X7R'     | 'CH1336J1B06'(!)   = ''              | ''                 | ''       | 'CH1336J1B06'     |'C0402'| '(C0402-0201)'                                                       | '330PF'    | '50V'         | '5%'     | 'DISCRETE' | 'CAP CHIP 330P 50V(+-5%,X7R,0402)YGO'                          | 'CHIP0402'     | ''          | ''   | '20230608'
 '330PF'    | '50V'   | '5%'      | 'C0402'     | 'EMPTY'   | 'CH1336J1B06'(!)   = ''              | ''                 | ''       | 'CH1336J1B06'     |'C0402'| '(C0402-0201)'                                                       | 'NA'       | '50V'         | '5%'     | 'IO'       | 'CAP CHIP 330P 50V(+-5%,X7R,0402)YGO'                          | 'CHIP0402'     | ''          | ''   | '20230608'
 '220PF'    | '50V'   | '10%'     | 'C0402'     | 'X7R'     | 'CH1226K1B19'(!)   = ''              | ''                 | ''       | 'CH1226K1B19'     |'C0402'| '(C0402-0201)'                                                       | '220PF'    | '50V'         | '10%'    | 'DISCRETE' | 'CAP CHIP 220P 50V(+-10%,X7R,0402)WTC'                         | 'CHIP0402'     | ''          | ''   | '20230608'
 '220PF'    | '50V'   | '10%'     | 'C0402'     | 'EMPTY'   | 'CH1226K1B19'(!)   = ''              | ''                 | ''       | 'CH1226K1B19'     |'C0402'| '(C0402-0201)'                                                       | 'NA'       | '50V'         | '10%'    | 'IO'       | 'CAP CHIP 220P 50V(+-10%,X7R,0402)WTC'                         | 'CHIP0402'     | ''          | ''   | '20230608'
 '0.33UF'   | '6.3V'  | '10%'     | 'C0402'     | 'X5R'     | 'CH4331K9B08'(!)   = ''              | ''                 | ''       | 'CH4331K9B08'     |'C0402'| '(C0402-0201)'                                                       | '0.33UF'   | '6.3V'        | '10%'    | 'DISCRETE' | 'CAP CHIP 0.33U 6.3V(10%,X5R,0402)MUR'                         | 'CHIP0402'     | ''          | ''   | '20230621'
 '0.33UF'   | '6.3V'  | '10%'     | 'C0402'     | 'EMPTY'   | 'CH4331K9B08'(!)   = ''              | ''                 | ''       | 'CH4331K9B08'     |'C0402'| '(C0402-0201)'                                                       | 'NA'       | '6.3V'        | '10%'    | 'IO'       | 'CAP CHIP 0.33U 6.3V(10%,X5R,0402)MUR'                         | 'CHIP0402'     | ''          | ''   | '20230621'
 '0.33UF'   | '6.3V'  | '10%'     | 'C0402'     | 'X5R'     | 'CH4331K9B10'(!)   = ''              | ''                 | ''       | 'CH4331K9B10'     |'C0402'| '(C0402-0201)'                                                       | '0.33UF'   | '6.3V'        | '10%'    | 'DISCRETE' | 'CAP CHIP 0.33U 6.3V(10%,X5R,0402)YGO'                         | 'CHIP0402'     | ''          | ''   | '20230626'
 '0.33UF'   | '6.3V'  | '10%'     | 'C0402'     | 'EMPTY'   | 'CH4331K9B10'(!)   = ''              | ''                 | ''       | 'CH4331K9B10'     |'C0402'| '(C0402-0201)'                                                       | 'NA'       | '6.3V'        | '10%'    | 'IO'       | 'CAP CHIP 0.33U 6.3V(10%,X5R,0402)YGO'                         | 'CHIP0402'     | ''          | ''   | '20230626'
 '2.2UF'    | '25V'   | '20%'     | 'C0402'     | 'X6S'     | 'CH5224MEB06'(!)   = ''              | ''                 | ''       | 'CH5224MEB06'     |'C0402_H28'| '(C0402-0201_H28)'                                                   | '2.2UF'    | '25V'         | '20%'    | 'DISCRETE' | 'CAP CHIP 2.2U 25V(+-20%,X6S,0402)SAM'                         | 'CHIP0402'     | ''          | ''   | '20230626'
 '2.2UF'    | '25V'   | '20%'     | 'C0402'     | 'EMPTY'   | 'CH5224MEB06'(!)   = ''              | ''                 | ''       | 'CH5224MEB06'     |'C0402_H28'| '(C0402-0201_H28)'                                                   | 'NA'       | '25V'         | '20%'    | 'IO'       | 'CAP CHIP 2.2U 25V(+-20%,X6S,0402)SAM'                         | 'CHIP0402'     | ''          | ''   | '20230626'
 '2.2UF'    | '25V'   | '20%'     | 'C0402'     | 'X6S'     | 'CH5224MEB05'(!)   = ''              | ''                 | ''       | 'CH5224MEB05'     |'C0402_H28'| '(C0402-0201_H28)'                                                   | '2.2UF'    | '25V'         | '20%'    | 'DISCRETE' | 'CAP CHIP 2.2UF 25V(+-20%,X6S,0402)MUR'                        | 'CHIP0402'     | ''          | ''   | '20230705'
 '2.2UF'    | '25V'   | '20%'     | 'C0402'     | 'EMPTY'   | 'CH5224MEB05'(!)   = ''              | ''                 | ''       | 'CH5224MEB05'     |'C0402_H28'| '(C0402-0201_H28)'                                                   | 'NA'       | '25V'         | '20%'    | 'IO'       | 'CAP CHIP 2.2UF 25V(+-20%,X6S,0402)MUR'                        | 'CHIP0402'     | ''          | ''   | '20230705'
 '10PF'     | '50V'   | '2%'      | 'C0402'     | 'NPO'     | 'CH0106G0B03SEL1'(!) = ''              | ''                 | ''       | 'CH0106G0B03SEL1' |'C0402'| '(C0402-0201)'                                                       | '10PF'     | '50V'         | '2%'     | 'DISCRETE' | 'CAP CHIP 10P 50V(+-2%,NPO,0402)MURSELA'                       | 'CHIP0402'     | ''          | ''   | '20230713'
 '10PF'     | '50V'   | '2%'      | 'C0402'     | 'EMPTY'   | 'CH0106G0B03SEL1'(!) = ''              | ''                 | ''       | 'CH0106G0B03SEL1' |'C0402'| '(C0402-0201)'                                                       | 'NA'       | '50V'         | '2%'     | 'IO'       | 'CAP CHIP 10P 50V(+-2%,NPO,0402)MURSELA'                       | 'CHIP0402'     | ''          | ''   | '20230713'
 '10PF'     | '50V'   | '5%'      | 'C0402'     | 'C0G'     | 'CH0106J0B18SEL1'(!) = ''              | ''                 | ''       | 'CH0106J0B18SEL1' |'C0402'| '(C0402-0201)'                                                       | '10PF'     | '50V'         | '5%'     | 'DISCRETE' | 'CAP CHIP 10P 50V(+-5%,C0G,0402)YGOSELASN'                     | 'CHIP0402'     | ''          | ''   | '20230713'
 '10PF'     | '50V'   | '5%'      | 'C0402'     | 'EMPTY'   | 'CH0106J0B18SEL1'(!) = ''              | ''                 | ''       | 'CH0106J0B18SEL1' |'C0402'| '(C0402-0201)'                                                       | 'NA'       | '50V'         | '5%'     | 'IO'       | 'CAP CHIP 10P 50V(+-5%,C0G,0402)YGOSELASN'                     | 'CHIP0402'     | ''          | ''   | '20230713'
 '12PF'     | '50V'   | '5%'      | 'C0402'     | 'C0G'     | 'CH0126J0B13SEL1'(!) = ''              | ''                 | ''       | 'CH0126J0B13SEL1' |'C0402'| '(C0402-0201)'                                                       | '12PF'     | '50V'         | '5%'     | 'DISCRETE' | 'CAP CHIP 12P 50V(+-5%,C0G,0402)MURSELA'                       | 'CHIP0402'     | ''          | ''   | '20230713'
 '12PF'     | '50V'   | '5%'      | 'C0402'     | 'EMPTY'   | 'CH0126J0B13SEL1'(!) = ''              | ''                 | ''       | 'CH0126J0B13SEL1' |'C0402'| '(C0402-0201)'                                                       | 'NA'       | '50V'         | '5%'     | 'IO'       | 'CAP CHIP 12P 50V(+-5%,C0G,0402)MURSELA'                       | 'CHIP0402'     | ''          | ''   | '20230713'
 '15PF'     | '50V'   | '5%'      | 'C0402'     | 'C0G'     | 'CH0156J0B07SEL1'(!) = ''              | ''                 | ''       | 'CH0156J0B07SEL1' |'C0402'| '(C0402-0201)'                                                       | '15PF'     | '50V'         | '5%'     | 'DISCRETE' | 'CAP CHIP 15P 50V(+-5% C0G 0402)MURSELA'                       | 'CHIP0402'     | ''          | ''   | '20230713'
 '15PF'     | '50V'   | '5%'      | 'C0402'     | 'EMPTY'   | 'CH0156J0B07SEL1'(!) = ''              | ''                 | ''       | 'CH0156J0B07SEL1' |'C0402'| '(C0402-0201)'                                                       | 'NA'       | '50V'         | '5%'     | 'IO'       | 'CAP CHIP 15P 50V(+-5% C0G 0402)MURSELA'                       | 'CHIP0402'     | ''          | ''   | '20230713'
 '18PF'     | '50V'   | '5%'      | 'C0402'     | 'C0G'     | 'CH0186J0B05SEL1'(!) = ''              | ''                 | ''       | 'CH0186J0B05SEL1' |'C0402'| '(C0402-0201)'                                                       | '18PF'     | '50V'         | '5%'     | 'DISCRETE' | 'CAP CHIP 18P 50V(+-5% C0G 0402)MURSELA'                       | 'CHIP0402'     | ''          | ''   | '20230713'
 '18PF'     | '50V'   | '5%'      | 'C0402'     | 'EMPTY'   | 'CH0186J0B05SEL1'(!) = ''              | ''                 | ''       | 'CH0186J0B05SEL1' |'C0402'| '(C0402-0201)'                                                       | 'NA'       | '50V'         | '5%'     | 'IO'       | 'CAP CHIP 18P 50V(+-5% C0G 0402)MURSELA'                       | 'CHIP0402'     | ''          | ''   | '20230713'
 '22PF'     | '50V'   | '5%'      | 'C0402'     | 'NPO'     | 'CH0226J0B16SEL1'(!) = ''              | ''                 | ''       | 'CH0226J0B16SEL1' |'C0402'| '(C0402-0201)'                                                       | '22PF'     | '50V'         | '5%'     | 'DISCRETE' | 'CAP CHIP 22P 50V(+-5%,NPO,0402)MURSELASN'                     | 'CHIP0402'     | ''          | ''   | '20230713'
 '22PF'     | '50V'   | '5%'      | 'C0402'     | 'EMPTY'   | 'CH0226J0B16SEL1'(!) = ''              | ''                 | ''       | 'CH0226J0B16SEL1' |'C0402'| '(C0402-0201)'                                                       | 'NA'       | '50V'         | '5%'     | 'IO'       | 'CAP CHIP 22P 50V(+-5%,NPO,0402)MURSELASN'                     | 'CHIP0402'     | ''          | ''   | '20230713'
 '27PF'     | '50V'   | '5%'      | 'C0402'     | 'NPO'     | 'CH0276J0B09SEL1'(!) = ''              | ''                 | ''       | 'CH0276J0B09SEL1' |'C0402'| '(C0402-0201)'                                                       | '27PF'     | '50V'         | '5%'     | 'DISCRETE' | 'CAP CHIP 27P 50V(+-5%,NPO,0402)MURSELA'                       | 'CHIP0402'     | ''          | ''   | '20230713'
 '27PF'     | '50V'   | '5%'      | 'C0402'     | 'EMPTY'   | 'CH0276J0B09SEL1'(!) = ''              | ''                 | ''       | 'CH0276J0B09SEL1' |'C0402'| '(C0402-0201)'                                                       | 'NA'       | '50V'         | '5%'     | 'IO'       | 'CAP CHIP 27P 50V(+-5%,NPO,0402)MURSELA'                       | 'CHIP0402'     | ''          | ''   | '20230713'
 '47PF'     | '50V'   | '5%'      | 'C0402'     | 'NPO'     | 'CH0476J0B11SEL1'(!) = ''              | ''                 | ''       | 'CH0476J0B11SEL1' |'C0402'| '(C0402-0201)'                                                       | '47PF'     | '50V'         | '5%'     | 'DISCRETE' | 'CAP CHIP 47P 50V(+-5%,NPO,0402)SAMSELASN'                     | 'CHIP0402'     | ''          | ''   | '20230713'
 '47PF'     | '50V'   | '5%'      | 'C0402'     | 'EMPTY'   | 'CH0476J0B11SEL1'(!) = ''              | ''                 | ''       | 'CH0476J0B11SEL1' |'C0402'| '(C0402-0201)'                                                       | 'NA'       | '50V'         | '5%'     | 'IO'       | 'CAP CHIP 47P 50V(+-5%,NPO,0402)SAMSELASN'                     | 'CHIP0402'     | ''          | ''   | '20230713'
 '47PF'     | '50V'   | '5%'      | 'C0402'     | 'NPO'     | 'CH0476J0B12SEL1'(!) = ''              | ''                 | ''       | 'CH0476J0B12SEL1' |'C0402'| '(C0402-0201)'                                                       | '47PF'     | '50V'         | '5%'     | 'DISCRETE' | 'CAP CHIP 47P 50V(+-5%,NPO,0402)MURSELASN'                     | 'CHIP0402'     | ''          | ''   | '20230713'
 '47PF'     | '50V'   | '5%'      | 'C0402'     | 'EMPTY'   | 'CH0476J0B12SEL1'(!) = ''              | ''                 | ''       | 'CH0476J0B12SEL1' |'C0402'| '(C0402-0201)'                                                       | 'NA'       | '50V'         | '5%'     | 'IO'       | 'CAP CHIP 47P 50V(+-5%,NPO,0402)MURSELASN'                     | 'CHIP0402'     | ''          | ''   | '20230713'
 '100PF'    | '50V'   | '5%'      | 'C0402'     | 'NPO'     | 'CH1106J0B16SEL1'(!) = ''              | ''                 | ''       | 'CH1106J0B16SEL1' |'C0402'| '(C0402-0201)'                                                       | '100PF'    | '50V'         | '5%'     | 'DISCRETE' | 'CAP CHIP 100P 50V(5%,NPO,0402)MURSELASN'                      | 'CHIP0402'     | ''          | ''   | '20230713'
 '100PF'    | '50V'   | '5%'      | 'C0402'     | 'EMPTY'   | 'CH1106J0B16SEL1'(!) = ''              | ''                 | ''       | 'CH1106J0B16SEL1' |'C0402'| '(C0402-0201)'                                                       | 'NA'       | '50V'         | '5%'     | 'IO'       | 'CAP CHIP 100P 50V(5%,NPO,0402)MURSELASN'                      | 'CHIP0402'     | ''          | ''   | '20230713'
 '100PF'    | '50V'   | '5%'      | 'C0402'     | 'NPO'     | 'CH1106J0B23SEL1'(!) = ''              | ''                 | ''       | 'CH1106J0B23SEL1' |'C0402'| '(C0402-0201)'                                                       | '100PF'    | '50V'         | '5%'     | 'DISCRETE' | 'CAP CHIP 100P 50V(+-5%,NPO,0402)YGOSELA'                      | 'CHIP0402'     | ''          | ''   | '20230713'
 '100PF'    | '50V'   | '5%'      | 'C0402'     | 'EMPTY'   | 'CH1106J0B23SEL1'(!) = ''              | ''                 | ''       | 'CH1106J0B23SEL1' |'C0402'| '(C0402-0201)'                                                       | 'NA'       | '50V'         | '5%'     | 'IO'       | 'CAP CHIP 100P 50V(+-5%,NPO,0402)YGOSELA'                      | 'CHIP0402'     | ''          | ''   | '20230713'
 '220PF'    | '50V'   | '5%'      | 'C0402'     | 'COG'     | 'CH1226J0B03SEL1'(!) = ''              | ''                 | ''       | 'CH1226J0B03SEL1' |'C0402'| '(C0402-0201)'                                                       | '220PF'    | '50V'         | '5%'     | 'DISCRETE' | 'CAP CHIP 220P 50V(+-5%,COG,0402)MURSELA'                      | 'CHIP0402'     | ''          | ''   | '20230713'
 '220PF'    | '50V'   | '5%'      | 'C0402'     | 'EMPTY'   | 'CH1226J0B03SEL1'(!) = ''              | ''                 | ''       | 'CH1226J0B03SEL1' |'C0402'| '(C0402-0201)'                                                       | 'NA'       | '50V'         | '5%'     | 'IO'       | 'CAP CHIP 220P 50V(+-5%,COG,0402)MURSELA'                      | 'CHIP0402'     | ''          | ''   | '20230713'
 '220PF'    | '50V'   | '5%'      | 'C0402'     | 'C0G'     | 'CH1226J0B04SEL1'(!) = ''              | ''                 | ''       | 'CH1226J0B04SEL1' |'C0402'| '(C0402-0201)'                                                       | '220PF'    | '50V'         | '5%'     | 'DISCRETE' | 'CAP CHIP 220P 50V(+-5%,C0G,0402)SAMSELA'                      | 'CHIP0402'     | ''          | ''   | '20230713'
 '220PF'    | '50V'   | '5%'      | 'C0402'     | 'EMPTY'   | 'CH1226J0B04SEL1'(!) = ''              | ''                 | ''       | 'CH1226J0B04SEL1' |'C0402'| '(C0402-0201)'                                                       | 'NA'       | '50V'         | '5%'     | 'IO'       | 'CAP CHIP 220P 50V(+-5%,C0G,0402)SAMSELA'                      | 'CHIP0402'     | ''          | ''   | '20230713'
 '220PF'    | '50V'   | '10%'     | 'C0402'     | 'X7R'     | 'CH1226K1B10SEL1'(!) = ''              | ''                 | ''       | 'CH1226K1B10SEL1' |'C0402'| '(C0402-0201)'                                                       | '220PF'    | '50V'         | '10%'    | 'DISCRETE' | 'CAP CHIP 220PF 50V(10%,X7R,0402)MURSELA'                      | 'CHIP0402'     | ''          | ''   | '20230713'
 '220PF'    | '50V'   | '10%'     | 'C0402'     | 'EMPTY'   | 'CH1226K1B10SEL1'(!) = ''              | ''                 | ''       | 'CH1226K1B10SEL1' |'C0402'| '(C0402-0201)'                                                       | 'NA'       | '50V'         | '10%'    | 'IO'       | 'CAP CHIP 220PF 50V(10%,X7R,0402)MURSELA'                      | 'CHIP0402'     | ''          | ''   | '20230713'
 '330PF'    | '50V'   | '5%'      | 'C0402'     | 'NPO'     | 'CH1336J0B10SEL1'(!) = ''              | ''                 | ''       | 'CH1336J0B10SEL1' |'C0402'| '(C0402-0201)'                                                       | '330PF'    | '50V'         | '5%'     | 'DISCRETE' | 'CAP CHIP 330P 50V(5%,NPO,0402)MURSELASN'                      | 'CHIP0402'     | ''          | ''   | '20230713'
 '330PF'    | '50V'   | '5%'      | 'C0402'     | 'EMPTY'   | 'CH1336J0B10SEL1'(!) = ''              | ''                 | ''       | 'CH1336J0B10SEL1' |'C0402'| '(C0402-0201)'                                                       | 'NA'       | '50V'         | '5%'     | 'IO'       | 'CAP CHIP 330P 50V(5%,NPO,0402)MURSELASN'                      | 'CHIP0402'     | ''          | ''   | '20230713'
 '330PF'    | '50V'   | '10%'     | 'C0402'     | 'X7R'     | 'CH1336K1B06SEL1'(!) = ''              | ''                 | ''       | 'CH1336K1B06SEL1' |'C0402'| '(C0402-0201)'                                                       | '330PF'    | '50V'         | '10%'    | 'DISCRETE' | 'CAP CHIP 330P 50V(+-10%,X7R,0402)MURSELA'                     | 'CHIP0402'     | ''          | ''   | '20230713'
 '330PF'    | '50V'   | '10%'     | 'C0402'     | 'EMPTY'   | 'CH1336K1B06SEL1'(!) = ''              | ''                 | ''       | 'CH1336K1B06SEL1' |'C0402'| '(C0402-0201)'                                                       | 'NA'       | '50V'         | '10%'    | 'IO'       | 'CAP CHIP 330P 50V(+-10%,X7R,0402)MURSELA'                     | 'CHIP0402'     | ''          | ''   | '20230713'
 '470PF'    | '50V'   | '5%'      | 'C0402'     | 'NPO'     | 'CH1476J0B04SEL1'(!) = ''              | ''                 | ''       | 'CH1476J0B04SEL1' |'C0402'| '(C0402-0201)'                                                       | '470PF'    | '50V'         | '5%'     | 'DISCRETE' | 'CAP CHIP 470P,50V(+-5%,NPO,0402)MURSELA'                      | 'CHIP0402'     | ''          | ''   | '20230713'
 '470PF'    | '50V'   | '5%'      | 'C0402'     | 'EMPTY'   | 'CH1476J0B04SEL1'(!) = ''              | ''                 | ''       | 'CH1476J0B04SEL1' |'C0402'| '(C0402-0201)'                                                       | 'NA'       | '50V'         | '5%'     | 'IO'       | 'CAP CHIP 470P,50V(+-5%,NPO,0402)MURSELA'                      | 'CHIP0402'     | ''          | ''   | '20230713'
 '470PF'    | '50V'   | '10%'     | 'C0402'     | 'X7R'     | 'CH1476K1B11SEL1'(!) = ''              | ''                 | ''       | 'CH1476K1B11SEL1' |'C0402'| '(C0402-0201)'                                                       | '470PF'    | '50V'         | '10%'    | 'DISCRETE' | 'CAP CHIP 470P 50V(10%,X7R,0402)MURSELASN'                     | 'CHIP0402'     | ''          | ''   | '20230713'
 '470PF'    | '50V'   | '10%'     | 'C0402'     | 'EMPTY'   | 'CH1476K1B11SEL1'(!) = ''              | ''                 | ''       | 'CH1476K1B11SEL1' |'C0402'| '(C0402-0201)'                                                       | 'NA'       | '50V'         | '10%'    | 'IO'       | 'CAP CHIP 470P 50V(10%,X7R,0402)MURSELASN'                     | 'CHIP0402'     | ''          | ''   | '20230713'
 '470PF'    | '50V'   | '10%'     | 'C0402'     | 'X7R'     | 'CH1476K1B14SEL1'(!) = ''              | ''                 | ''       | 'CH1476K1B14SEL1' |'C0402'| '(C0402-0201)'                                                       | '470PF'    | '50V'         | '10%'    | 'DISCRETE' | 'CAP CHIP 470P 50V(10%,X7R,0402)SAMSELASN'                     | 'CHIP0402'     | ''          | ''   | '20230713'
 '470PF'    | '50V'   | '10%'     | 'C0402'     | 'EMPTY'   | 'CH1476K1B14SEL1'(!) = ''              | ''                 | ''       | 'CH1476K1B14SEL1' |'C0402'| '(C0402-0201)'                                                       | 'NA'       | '50V'         | '10%'    | 'IO'       | 'CAP CHIP 470P 50V(10%,X7R,0402)SAMSELASN'                     | 'CHIP0402'     | ''          | ''   | '20230713'
 '680PF'    | '50V'   | '5%'      | 'C0402'     | 'C0G'     | 'CH1686J0B03SEL1'(!) = ''              | ''                 | ''       | 'CH1686J0B03SEL1' |'C0402'| '(C0402-0201)'                                                       | '680PF'    | '50V'         | '5%'     | 'DISCRETE' | 'CAP CHIP 680P 50V(+-5%,C0G,0402)MURSELA'                      | 'CHIP0402'     | ''          | ''   | '20230713'
 '680PF'    | '50V'   | '5%'      | 'C0402'     | 'EMPTY'   | 'CH1686J0B03SEL1'(!) = ''              | ''                 | ''       | 'CH1686J0B03SEL1' |'C0402'| '(C0402-0201)'                                                       | 'NA'       | '50V'         | '5%'     | 'IO'       | 'CAP CHIP 680P 50V(+-5%,C0G,0402)MURSELA'                      | 'CHIP0402'     | ''          | ''   | '20230713'
 '1000PF'   | '16V'   | '10%'     | 'C0402'     | 'X7R'     | 'CH2103K1B03SEL1'(!) = ''              | ''                 | ''       | 'CH2103K1B03SEL1' |'C0402'| '(C0402-0201)'                                                       | '1000PF'   | '16V'         | '10%'    | 'DISCRETE' | 'CAP CHIP 1000P 16V (10%,X7R,0402)MURSELA'                     | 'CHIP0402'     | ''          | ''   | '20230713'
 '1000PF'   | '16V'   | '10%'     | 'C0402'     | 'EMPTY'   | 'CH2103K1B03SEL1'(!) = ''              | ''                 | ''       | 'CH2103K1B03SEL1' |'C0402'| '(C0402-0201)'                                                       | 'NA'       | '16V'         | '10%'    | 'IO'       | 'CAP CHIP 1000P 16V (10%,X7R,0402)MURSELA'                     | 'CHIP0402'     | ''          | ''   | '20230713'
 '1NF'      | '25V'   | '10%'     | 'C0201'     | 'X7R'     | 'CH2104K1E04SEL1'(!) = ''              | ''                 | ''       | 'CH2104K1E04SEL1' |'C0201'| '(SMC0201AW)'                                                        | '1NF'      | '25V'         | '10%'    | 'DISCRETE' | 'CAP CHIP 1NF 25V(+-10%,X7R,0201)MURSELA'                      | 'CHIP0201'     | ''          | ''   | '20230713'
 '1NF'      | '25V'   | '10%'     | 'C0201'     | 'EMPTY'   | 'CH2104K1E04SEL1'(!) = ''              | ''                 | ''       | 'CH2104K1E04SEL1' |'C0201'| '(SMC0201AW)'                                                        | 'NA'       | '25V'         | '10%'    | 'IO'       | 'CAP CHIP 1NF 25V(+-10%,X7R,0201)MURSELA'                      | 'CHIP0201'     | ''          | ''   | '20230713'
 '1000PF'   | '50V'   | '5%'      | 'C0402'     | 'X7R'     | 'CH2106J1B04SEL1'(!) = ''              | ''                 | ''       | 'CH2106J1B04SEL1' |'C0402'| '(C0402-0201)'                                                       | '1000PF'   | '50V'         | '5%'     | 'DISCRETE' | 'CAP CHIP 1000P 50V(+-5%,X7R,0402)MURSELA'                     | 'CHIP0402'     | ''          | ''   | '20230713'
 '1000PF'   | '50V'   | '5%'      | 'C0402'     | 'EMPTY'   | 'CH2106J1B04SEL1'(!) = ''              | ''                 | ''       | 'CH2106J1B04SEL1' |'C0402'| '(C0402-0201)'                                                       | 'NA'       | '50V'         | '5%'     | 'IO'       | 'CAP CHIP 1000P 50V(+-5%,X7R,0402)MURSELA'                     | 'CHIP0402'     | ''          | ''   | '20230713'
 '2200PF'   | '50V'   | '5%'      | 'C0402'     | 'C0G'     | 'CH2226J0B01SEL1'(!) = ''              | ''                 | ''       | 'CH2226J0B01SEL1' |'C0402'| '(C0402-0201)'                                                       | '2200PF'   | '50V'         | '5%'     | 'DISCRETE' | 'CAP CHIP 2200P 50V(+-5%,C0G,0402)MURSELA'                     | 'CHIP0402'     | ''          | ''   | '20230713'
 '2200PF'   | '50V'   | '5%'      | 'C0402'     | 'EMPTY'   | 'CH2226J0B01SEL1'(!) = ''              | ''                 | ''       | 'CH2226J0B01SEL1' |'C0402'| '(C0402-0201)'                                                       | 'NA'       | '50V'         | '5%'     | 'IO'       | 'CAP CHIP 2200P 50V(+-5%,C0G,0402)MURSELA'                     | 'CHIP0402'     | ''          | ''   | '20230713'
 '2200PF'   | '50V'   | '10%'     | 'C0402'     | 'X7R'     | 'CH2226K1B06SEL1'(!) = ''              | ''                 | ''       | 'CH2226K1B06SEL1' |'C0402'| '(C0402-0201)'                                                       | '2200PF'   | '50V'         | '10%'    | 'DISCRETE' | 'CAP CHIP 2200P 50V(10%,X7R,0402)MURSELA'                      | 'CHIP0402'     | ''          | ''   | '20230713'
 '2200PF'   | '50V'   | '10%'     | 'C0402'     | 'EMPTY'   | 'CH2226K1B06SEL1'(!) = ''              | ''                 | ''       | 'CH2226K1B06SEL1' |'C0402'| '(C0402-0201)'                                                       | 'NA'       | '50V'         | '10%'    | 'IO'       | 'CAP CHIP 2200P 50V(10%,X7R,0402)MURSELA'                      | 'CHIP0402'     | ''          | ''   | '20230713'
 '3300PF'   | '50V'   | '10%'     | 'C0402'     | 'X7R'     | 'CH2336K1B06SEL1'(!) = ''              | ''                 | ''       | 'CH2336K1B06SEL1' |'C0402'| '(C0402-0201)'                                                       | '3300PF'   | '50V'         | '10%'    | 'DISCRETE' | 'CAP CHIP 3300P 50V(10%,X7R,0402)MURSELA'                      | 'CHIP0402'     | ''          | ''   | '20230713'
 '3300PF'   | '50V'   | '10%'     | 'C0402'     | 'EMPTY'   | 'CH2336K1B06SEL1'(!) = ''              | ''                 | ''       | 'CH2336K1B06SEL1' |'C0402'| '(C0402-0201)'                                                       | 'NA'       | '50V'         | '10%'    | 'IO'       | 'CAP CHIP 3300P 50V(10%,X7R,0402)MURSELA'                      | 'CHIP0402'     | ''          | ''   | '20230713'
 '3900PF'   | '50V'   | '10%'     | 'C0402'     | 'X7R'     | 'CH2396K1B07SEL1'(!) = ''              | ''                 | ''       | 'CH2396K1B07SEL1' |'C0402'| '(C0402-0201)'                                                       | '3900PF'   | '50V'         | '10%'    | 'DISCRETE' | 'CAP CHIP 3900P 50V(10%,X7R,0402)MURSELA'                      | 'CHIP0402'     | ''          | ''   | '20230713'
 '3900PF'   | '50V'   | '10%'     | 'C0402'     | 'EMPTY'   | 'CH2396K1B07SEL1'(!) = ''              | ''                 | ''       | 'CH2396K1B07SEL1' |'C0402'| '(C0402-0201)'                                                       | 'NA'       | '50V'         | '10%'    | 'IO'       | 'CAP CHIP 3900P 50V(10%,X7R,0402)MURSELA'                      | 'CHIP0402'     | ''          | ''   | '20230713'
 '4700PF'   | '50V'   | '5%'      | 'C0603'     | 'C0G'     | 'CH2476J0902SEL1'(!) = ''              | ''                 | ''       | 'CH2476J0902SEL1' |'C0603_H40'| '(SMC0603AW)'                                                        | '4700PF'   | '50V'         | '5%'     | 'DISCRETE' | 'CAP CHIP 4700P 50V(+-5%,C0G,0603)MURSELA'                     | 'CHIP0603'     | ''          | ''   | '20230713'
 '4700PF'   | '50V'   | '5%'      | 'C0603'     | 'EMPTY'   | 'CH2476J0902SEL1'(!) = ''              | ''                 | ''       | 'CH2476J0902SEL1' |'C0603_H40'| '(SMC0603AW)'                                                        | 'NA'       | '50V'         | '5%'     | 'IO'       | 'CAP CHIP 4700P 50V(+-5%,C0G,0603)MURSELA'                     | 'CHIP0603'     | ''          | ''   | '20230713'
 '4700PF'   | '50V'   | '5%'      | 'C0402'     | 'C0G'     | 'CH2476J0B01SEL1'(!) = ''              | ''                 | ''       | 'CH2476J0B01SEL1' |'C0402_H28'| '(C0402-0201_H28)'                                                   | '4700PF'   | '50V'         | '5%'     | 'DISCRETE' | 'CAP CHIP 4700P 50V(+-5%,C0G,0402)MURSELA'                     | 'CHIP0402'     | ''          | ''   | '20230713'
 '4700PF'   | '50V'   | '5%'      | 'C0402'     | 'EMPTY'   | 'CH2476J0B01SEL1'(!) = ''              | ''                 | ''       | 'CH2476J0B01SEL1' |'C0402_H28'| '(C0402-0201_H28)'                                                   | 'NA'       | '50V'         | '5%'     | 'IO'       | 'CAP CHIP 4700P 50V(+-5%,C0G,0402)MURSELA'                     | 'CHIP0402'     | ''          | ''   | '20230713'
 '5600PF'   | '50V'   | '10%'     | 'C0402'     | 'X7R'     | 'CH2566K1B06SEL1'(!) = ''              | ''                 | ''       | 'CH2566K1B06SEL1' |'C0402'| '(C0402-0201)'                                                       | '5600PF'   | '50V'         | '10%'    | 'DISCRETE' | 'CAP CHIP 5600PF 50V(10%,X7R,0402)SAMSELA'                     | 'CHIP0402'     | ''          | ''   | '20230713'
 '5600PF'   | '50V'   | '10%'     | 'C0402'     | 'EMPTY'   | 'CH2566K1B06SEL1'(!) = ''              | ''                 | ''       | 'CH2566K1B06SEL1' |'C0402'| '(C0402-0201)'                                                       | 'NA'       | '50V'         | '10%'    | 'IO'       | 'CAP CHIP 5600PF 50V(10%,X7R,0402)SAMSELA'                     | 'CHIP0402'     | ''          | ''   | '20230713'
 '0.01UF'   | '50V'   | '10%'     | 'C0402'     | 'X7R'     | 'CH31006KB00SEL1'(!) = ''              | ''                 | ''       | 'CH31006KB00SEL1' |'C0402'| '(C0402-0201)'                                                       | '0.01UF'   | '50V'         | '10%'    | 'DISCRETE' | 'CAP CHIP 0.01U 50V(10%,X7R,0402)MURSELA'                      | 'CHIP0402'     | ''          | ''   | '20230713'
 '0.01UF'   | '50V'   | '10%'     | 'C0402'     | 'EMPTY'   | 'CH31006KB00SEL1'(!) = ''              | ''                 | ''       | 'CH31006KB00SEL1' |'C0402'| '(C0402-0201)'                                                       | 'NA'       | '50V'         | '10%'    | 'IO'       | 'CAP CHIP 0.01U 50V(10%,X7R,0402)MURSELA'                      | 'CHIP0402'     | ''          | ''   | '20230713'
 '0.01UF'   | '16V'   | '10%'     | 'C0402'     | 'X7R'     | 'CH3103K1B16SEL1'(!) = ''              | ''                 | ''       | 'CH3103K1B16SEL1' |'C0402'| '(C0402-0201)'                                                       | '0.01UF'   | '16V'         | '10%'    | 'DISCRETE' | 'CAP CHIP 0.01U 16V(10%,X7R,0402)MURSELA'                      | 'CHIP0402'     | ''          | ''   | '20230713'
 '0.01UF'   | '16V'   | '10%'     | 'C0402'     | 'EMPTY'   | 'CH3103K1B16SEL1'(!) = ''              | ''                 | ''       | 'CH3103K1B16SEL1' |'C0402'| '(C0402-0201)'                                                       | 'NA'       | '16V'         | '10%'    | 'IO'       | 'CAP CHIP 0.01U 16V(10%,X7R,0402)MURSELA'                      | 'CHIP0402'     | ''          | ''   | '20230713'
 '0.01UF'   | '16V'   | '10%'     | 'C0402'     | 'X7R'     | 'CH3103K1B26SEL1'(!) = ''              | ''                 | ''       | 'CH3103K1B26SEL1' |'C0402'| '(C0402-0201)'                                                       | '0.01UF'   | '16V'         | '10%'    | 'DISCRETE' | 'CAP CHIP 0.01U 16V(10%,X7R,0402)YGOSELA'                      | 'CHIP0402'     | ''          | ''   | '20230713'
 '0.01UF'   | '16V'   | '10%'     | 'C0402'     | 'EMPTY'   | 'CH3103K1B26SEL1'(!) = ''              | ''                 | ''       | 'CH3103K1B26SEL1' |'C0402'| '(C0402-0201)'                                                       | 'NA'       | '16V'         | '10%'    | 'IO'       | 'CAP CHIP 0.01U 16V(10%,X7R,0402)YGOSELA'                      | 'CHIP0402'     | ''          | ''   | '20230713'
 '0.01UF'   | '25V'   | '10%'     | 'C0402'     | 'X7R'     | 'CH3104K1B11SEL1'(!) = ''              | ''                 | ''       | 'CH3104K1B11SEL1' |'C0402'| '(C0402-0201)'                                                       | '0.01UF'   | '25V'         | '10%'    | 'DISCRETE' | 'CAP CHIP 0.01U 25V(10%,X7R,0402)MURSELA'                      | 'CHIP0402'     | ''          | ''   | '20230713'
 '0.01UF'   | '25V'   | '10%'     | 'C0402'     | 'EMPTY'   | 'CH3104K1B11SEL1'(!) = ''              | ''                 | ''       | 'CH3104K1B11SEL1' |'C0402'| '(C0402-0201)'                                                       | 'NA'       | '25V'         | '10%'    | 'IO'       | 'CAP CHIP 0.01U 25V(10%,X7R,0402)MURSELA'                      | 'CHIP0402'     | ''          | ''   | '20230713'
 '0.01UF'   | '50V'   | '10%'     | 'C0402'     | 'X7R'     | 'CH3106K1B06SEL1'(!) = ''              | ''                 | ''       | 'CH3106K1B06SEL1' |'C0402'| '(C0402-0201)'                                                       | '0.01UF'   | '50V'         | '10%'    | 'DISCRETE' | 'CAP CHIP 0.01U 50V(10%,X7R,0402)SAMSELA'                      | 'CHIP0402'     | ''          | ''   | '20230713'
 '0.01UF'   | '50V'   | '10%'     | 'C0402'     | 'EMPTY'   | 'CH3106K1B06SEL1'(!) = ''              | ''                 | ''       | 'CH3106K1B06SEL1' |'C0402'| '(C0402-0201)'                                                       | 'NA'       | '50V'         | '10%'    | 'IO'       | 'CAP CHIP 0.01U 50V(10%,X7R,0402)SAMSELA'                      | 'CHIP0402'     | ''          | ''   | '20230713'
 '0.01UF'   | '50V'   | '10%'     | 'C0402'     | 'X7R'     | 'CH3106K1B10SEL1'(!) = ''              | ''                 | ''       | 'CH3106K1B10SEL1' |'C0402'| '(C0402-0201)'                                                       | '0.01UF'   | '50V'         | '10%'    | 'DISCRETE' | 'CAP CHIP 0.01U 50V(10%,X7R,0402)MURSELA'                      | 'CHIP0402'     | ''          | ''   | '20230713'
 '0.01UF'   | '50V'   | '10%'     | 'C0402'     | 'EMPTY'   | 'CH3106K1B10SEL1'(!) = ''              | ''                 | ''       | 'CH3106K1B10SEL1' |'C0402'| '(C0402-0201)'                                                       | 'NA'       | '50V'         | '10%'    | 'IO'       | 'CAP CHIP 0.01U 50V(10%,X7R,0402)MURSELA'                      | 'CHIP0402'     | ''          | ''   | '20230713'
 '0.01UF'   | '1KV'   | '10%'     | 'C1206'     | 'X7R'     | 'CH310FK1202SEL1'(!) = ''              | ''                 | ''       | 'CH310FK1202SEL1' |'C1206_H76'| '(SMC1206AW)'                                                        | '0.01UF'   | '1KV'         | '10%'    | 'DISCRETE' | 'CAP CHIP 0.01U 1KV(10%,X7R,1206)MURSELA'                      | 'CHIP1206'     | ''          | ''   | '20230713'
 '0.01UF'   | '1KV'   | '10%'     | 'C1206'     | 'EMPTY'   | 'CH310FK1202SEL1'(!) = ''              | ''                 | ''       | 'CH310FK1202SEL1' |'C1206_H76'| '(SMC1206AW)'                                                        | 'NA'       | '1KV'         | '10%'    | 'IO'       | 'CAP CHIP 0.01U 1KV(10%,X7R,1206)MURSELA'                      | 'CHIP1206'     | ''          | ''   | '20230713'
 '0.022UF'  | '50V'   | '10%'     | 'C0402'     | 'X7R'     | 'CH3226K1B08SEL1'(!) = ''              | ''                 | ''       | 'CH3226K1B08SEL1' |'C0402'| '(C0402-0201)'                                                       | '0.022UF'  | '50V'         | '10%'    | 'DISCRETE' | 'CAP CHIP 0.022U 50V(10%,X7R,0402)MURSELA'                     | 'CHIP0402'     | ''          | ''   | '20230713'
 '0.022UF'  | '50V'   | '10%'     | 'C0402'     | 'EMPTY'   | 'CH3226K1B08SEL1'(!) = ''              | ''                 | ''       | 'CH3226K1B08SEL1' |'C0402'| '(C0402-0201)'                                                       | 'NA'       | '50V'         | '10%'    | 'IO'       | 'CAP CHIP 0.022U 50V(10%,X7R,0402)MURSELA'                     | 'CHIP0402'     | ''          | ''   | '20230713'
 '0.047UF'  | '50V'   | '10%'     | 'C0402'     | 'X7R'     | 'CH3476K1B10SEL1'(!) = ''              | ''                 | ''       | 'CH3476K1B10SEL1' |'C0402'| '(C0402-0201)'                                                       | '0.047UF'  | '50V'         | '10%'    | 'DISCRETE' | 'CAP CHIP 0.047U 50V(10%,X7R,0402)MURSELA'                     | 'CHIP0402'     | ''          | ''   | '20230713'
 '0.047UF'  | '50V'   | '10%'     | 'C0402'     | 'EMPTY'   | 'CH3476K1B10SEL1'(!) = ''              | ''                 | ''       | 'CH3476K1B10SEL1' |'C0402'| '(C0402-0201)'                                                       | 'NA'       | '50V'         | '10%'    | 'IO'       | 'CAP CHIP 0.047U 50V(10%,X7R,0402)MURSELA'                     | 'CHIP0402'     | ''          | ''   | '20230713'
 '0.047UF'  | '100V'  | '10%'     | 'C0805'     | 'X7R'     | 'CH3478K1A01SEL1'(!) = ''              | ''                 | ''       | 'CH3478K1A01SEL1' |'C0805_H57'| '(SMC0805AW)'                                                        | '0.047UF'  | '100V'        | '10%'    | 'DISCRETE' | 'CAPCHIP 0.047U 100V(10%,X7R,0805)MURSELA'                     | 'CHIP0805'     | ''          | ''   | '20230713'
 '0.047UF'  | '100V'  | '10%'     | 'C0805'     | 'EMPTY'   | 'CH3478K1A01SEL1'(!) = ''              | ''                 | ''       | 'CH3478K1A01SEL1' |'C0805_H57'| '(SMC0805AW)'                                                        | 'NA'       | '100V'        | '10%'    | 'IO'       | 'CAPCHIP 0.047U 100V(10%,X7R,0805)MURSELA'                     | 'CHIP0805'     | ''          | ''   | '20230713'
 '0.068UF'  | '16V'   | '10%'     | 'C0402'     | 'X7R'     | 'CH3683K1B02SEL1'(!) = ''              | ''                 | ''       | 'CH3683K1B02SEL1' |'C0402'| '(C0402-0201)'                                                       | '0.068UF'  | '16V'         | '10%'    | 'DISCRETE' | 'CAP CHIP 0.068U 16V(10%,X7R 0402)MURSELA'                     | 'CHIP0402'     | ''          | ''   | '20230713'
 '0.068UF'  | '16V'   | '10%'     | 'C0402'     | 'EMPTY'   | 'CH3683K1B02SEL1'(!) = ''              | ''                 | ''       | 'CH3683K1B02SEL1' |'C0402'| '(C0402-0201)'                                                       | 'NA'       | '16V'         | '10%'    | 'IO'       | 'CAP CHIP 0.068U 16V(10%,X7R 0402)MURSELA'                     | 'CHIP0402'     | ''          | ''   | '20230713'
 '0.1UF'    | '6.3V'  | '10%'     | 'C0402'     | 'X7R'     | 'CH4101K1B01SEL1'(!) = ''              | ''                 | ''       | 'CH4101K1B01SEL1' |'C0402'| '(C0402-0201)'                                                       | '0.1UF'    | '6.3V'        | '10%'    | 'DISCRETE' | 'CAP CHIP 0.1UF 6.3V(10%,X7R,0402)MURSELA'                     | 'CHIP0402'     | ''          | ''   | '20230713'
 '0.1UF'    | '6.3V'  | '10%'     | 'C0402'     | 'EMPTY'   | 'CH4101K1B01SEL1'(!) = ''              | ''                 | ''       | 'CH4101K1B01SEL1' |'C0402'| '(C0402-0201)'                                                       | 'NA'       | '6.3V'        | '10%'    | 'IO'       | 'CAP CHIP 0.1UF 6.3V(10%,X7R,0402)MURSELA'                     | 'CHIP0402'     | ''          | ''   | '20230713'
 '0.1UF'    | '6.3V'  | '10%'     | 'C0201'     | 'X6S'     | 'CH4101KEE02SEL1'(!) = ''              | ''                 | ''       | 'CH4101KEE02SEL1' |'C0201'| '(SMC0201AW)'                                                        | '0.1UF'    | '6.3V'        | '10%'    | 'DISCRETE' | 'CAP CHIP 0.1UF 6.3V(10%,X6S,0201)SAMSELA'                     | 'CHIP0201'     | ''          | ''   | '20230713'
 '0.1UF'    | '6.3V'  | '10%'     | 'C0201'     | 'EMPTY'   | 'CH4101KEE02SEL1'(!) = ''              | ''                 | ''       | 'CH4101KEE02SEL1' |'C0201'| '(SMC0201AW)'                                                        | 'NA'       | '6.3V'        | '10%'    | 'IO'       | 'CAP CHIP 0.1UF 6.3V(10%,X6S,0201)SAMSELA'                     | 'CHIP0201'     | ''          | ''   | '20230713'
 '0.1UF'    | '16V'   | '10%'     | 'C0402'     | 'X7R'     | 'CH4103K1B13SEL1'(!) = ''              | ''                 | ''       | 'CH4103K1B13SEL1' |'C0402'| '(C0402-0201)'                                                       | '0.1UF'    | '16V'         | '10%'    | 'DISCRETE' | 'CAP CHIP 0.1U 16V(10%,X7R,0402)MURSELA'                       | 'CHIP0402'     | ''          | ''   | '20230713'
 '0.1UF'    | '16V'   | '10%'     | 'C0402'     | 'EMPTY'   | 'CH4103K1B13SEL1'(!) = ''              | ''                 | ''       | 'CH4103K1B13SEL1' |'C0402'| '(C0402-0201)'                                                       | 'NA'       | '16V'         | '10%'    | 'IO'       | 'CAP CHIP 0.1U 16V(10%,X7R,0402)MURSELA'                       | 'CHIP0402'     | ''          | ''   | '20230713'
 '0.1UF'    | '16V'   | '10%'     | 'C0402'     | 'X7R'     | 'CH4103K1B14SEL1'(!) = ''              | ''                 | ''       | 'CH4103K1B14SEL1' |'C0402'| '(C0402-0201)'                                                       | '0.1UF'    | '16V'         | '10%'    | 'DISCRETE' | 'CAP CHIP 0.1U 16V(10%,X7R,0402)MURSELA'                       | 'CHIP0402'     | ''          | ''   | '20230713'
 '0.1UF'    | '16V'   | '10%'     | 'C0402'     | 'EMPTY'   | 'CH4103K1B14SEL1'(!) = ''              | ''                 | ''       | 'CH4103K1B14SEL1' |'C0402'| '(C0402-0201)'                                                       | 'NA'       | '16V'         | '10%'    | 'IO'       | 'CAP CHIP 0.1U 16V(10%,X7R,0402)MURSELA'                       | 'CHIP0402'     | ''          | ''   | '20230713'
 '0.1UF'    | '16V'   | '10%'     | 'C0402'     | 'X7R'     | 'CH4103K1B19SEL1'(!) = ''              | ''                 | ''       | 'CH4103K1B19SEL1' |'C0402'| '(C0402-0201)'                                                       | '0.1UF'    | '16V'         | '10%'    | 'DISCRETE' | 'CAP CHIP 0.1U 16V(10%,X7R,0402)SAMSELA'                       | 'CHIP0402'     | ''          | ''   | '20230713'
 '0.1UF'    | '16V'   | '10%'     | 'C0402'     | 'EMPTY'   | 'CH4103K1B19SEL1'(!) = ''              | ''                 | ''       | 'CH4103K1B19SEL1' |'C0402'| '(C0402-0201)'                                                       | 'NA'       | '16V'         | '10%'    | 'IO'       | 'CAP CHIP 0.1U 16V(10%,X7R,0402)SAMSELA'                       | 'CHIP0402'     | ''          | ''   | '20230713'
 '0.1UF'    | '16V'   | '10%'     | 'C0201'     | 'X6S'     | 'CH4103KEE03SEL1'(!) = ''              | ''                 | ''       | 'CH4103KEE03SEL1' |'C0201'| '(SMC0201AW)'                                                        | '0.1UF'    | '16V'         | '10%'    | 'DISCRETE' | 'CAP CHIP 0.1UF 16V(10%,X6S,0201)MURSELA'                      | 'CHIP0201'     | ''          | ''   | '20230713'
 '0.1UF'    | '16V'   | '10%'     | 'C0201'     | 'EMPTY'   | 'CH4103KEE03SEL1'(!) = ''              | ''                 | ''       | 'CH4103KEE03SEL1' |'C0201'| '(SMC0201AW)'                                                        | 'NA'       | '16V'         | '10%'    | 'IO'       | 'CAP CHIP 0.1UF 16V(10%,X6S,0201)MURSELA'                      | 'CHIP0201'     | ''          | ''   | '20230713'
 '0.1UF'    | '25V'   | '10%'     | 'C0603'     | 'X7R'     | 'CH4104K1909SEL1'(!) = ''              | ''                 | ''       | 'CH4104K1909SEL1' |'C0603'| '(SMC0603AW)'                                                        | '0.1UF'    | '25V'         | '10%'    | 'DISCRETE' | 'CAP CHIP 0.1UF 25V(10%,X7R,0603)MURSELA'                      | 'CHIP0603'     | ''          | ''   | '20230713'
 '0.1UF'    | '25V'   | '10%'     | 'C0603'     | 'EMPTY'   | 'CH4104K1909SEL1'(!) = ''              | ''                 | ''       | 'CH4104K1909SEL1' |'C0603'| '(SMC0603AW)'                                                        | 'NA'       | '25V'         | '10%'    | 'IO'       | 'CAP CHIP 0.1UF 25V(10%,X7R,0603)MURSELA'                      | 'CHIP0603'     | ''          | ''   | '20230713'
 '0.1UF'    | '25V'   | '10%'     | 'C0402'     | 'X7R'     | 'CH4104K1B03SEL1'(!) = ''              | ''                 | ''       | 'CH4104K1B03SEL1' |'C0402'| '(C0402-0201)'                                                       | '0.1UF'    | '25V'         | '10%'    | 'DISCRETE' | 'CAP CHIP 0.1U 25V(+-10%,X7R,0402)MURSELA'                     | 'CHIP0402'     | ''          | ''   | '20230713'
 '0.1UF'    | '25V'   | '10%'     | 'C0402'     | 'EMPTY'   | 'CH4104K1B03SEL1'(!) = ''              | ''                 | ''       | 'CH4104K1B03SEL1' |'C0402'| '(C0402-0201)'                                                       | 'NA'       | '25V'         | '10%'    | 'IO'       | 'CAP CHIP 0.1U 25V(+-10%,X7R,0402)MURSELA'                     | 'CHIP0402'     | ''          | ''   | '20230713'
 '100NF'    | '50V'   | '10%'     | 'C0402'     | 'X7R'     | 'CH4106K1B20SEL1'(!) = ''              | ''                 | ''       | 'CH4106K1B20SEL1' |'C0402'| '(C0402-0201)'                                                       | '100NF'    | '50V'         | '10%'    | 'DISCRETE' | 'CAP CHIP 100NF 50V(10%,X7R,0402)SAMSELA'                      | 'CHIP0402'     | ''          | ''   | '20230713'
 '100NF'    | '50V'   | '10%'     | 'C0402'     | 'EMPTY'   | 'CH4106K1B20SEL1'(!) = ''              | ''                 | ''       | 'CH4106K1B20SEL1' |'C0402'| '(C0402-0201)'                                                       | 'NA'       | '50V'         | '10%'    | 'IO'       | 'CAP CHIP 100NF 50V(10%,X7R,0402)SAMSELA'                      | 'CHIP0402'     | ''          | ''   | '20230713'
 '0.1UF'    | '100V'  | '10%'     | 'C1206'     | 'X7R'     | 'CH4108K1208SEL1'(!) = ''              | ''                 | ''       | 'CH4108K1208SEL1' |'C1206_H76'| '(SMC1206AW)'                                                        | '0.1UF'    | '100V'        | '10%'    | 'DISCRETE' | 'CAP CHIP 0.1UF 100V(10%,X7R,1206)TAYSELA'                     | 'CHIP1206'     | ''          | ''   | '20230713'
 '0.1UF'    | '100V'  | '10%'     | 'C1206'     | 'EMPTY'   | 'CH4108K1208SEL1'(!) = ''              | ''                 | ''       | 'CH4108K1208SEL1' |'C1206_H76'| '(SMC1206AW)'                                                        | 'NA'       | '100V'        | '10%'    | 'IO'       | 'CAP CHIP 0.1UF 100V(10%,X7R,1206)TAYSELA'                     | 'CHIP1206'     | ''          | ''   | '20230713'
 '0.1UF'    | '100V'  | '10%'     | 'C0805'     | 'X7R'     | 'CH4108K1A01SEL1'(!) = ''              | ''                 | ''       | 'CH4108K1A01SEL1' |'C0805_H61'| '(SMC0805AW)'                                                        | '0.1UF'    | '100V'        | '10%'    | 'DISCRETE' | 'CAP CHIP 0.1UF 100V(10%,X7R,0805)MURSELA'                     | 'CHIP0805'     | ''          | ''   | '20230713'
 '0.1UF'    | '100V'  | '10%'     | 'C0805'     | 'EMPTY'   | 'CH4108K1A01SEL1'(!) = ''              | ''                 | ''       | 'CH4108K1A01SEL1' |'C0805_H61'| '(SMC0805AW)'                                                        | 'NA'       | '100V'        | '10%'    | 'IO'       | 'CAP CHIP 0.1UF 100V(10%,X7R,0805)MURSELA'                     | 'CHIP0805'     | ''          | ''   | '20230713'
 '0.22UF'   | '6.3V'  | '10%'     | 'C0201'     | 'X6S'     | 'CH4221KEE01SEL1'(!) = ''              | ''                 | ''       | 'CH4221KEE01SEL1' |'C0201'| '(SMC0201AW)'                                                        | '0.22UF'   | '6.3V'        | '10%'    | 'DISCRETE' | 'CAP CHIP 0.22U 6.3V(10%,X6S,0201)MURSELA'                     | 'CHIP0201'     | ''          | ''   | '20230713'
 '0.22UF'   | '6.3V'  | '10%'     | 'C0201'     | 'EMPTY'   | 'CH4221KEE01SEL1'(!) = ''              | ''                 | ''       | 'CH4221KEE01SEL1' |'C0201'| '(SMC0201AW)'                                                        | 'NA'       | '6.3V'        | '10%'    | 'IO'       | 'CAP CHIP 0.22U 6.3V(10%,X6S,0201)MURSELA'                     | 'CHIP0201'     | ''          | ''   | '20230713'
 '0.22UF'   | '16V'   | '10%'     | 'C0402'     | 'X7R'     | 'CH4223K1B04SEL1'(!) = ''              | ''                 | ''       | 'CH4223K1B04SEL1' |'C0402'| '(C0402-0201)'                                                       | '0.22UF'   | '16V'         | '10%'    | 'DISCRETE' | 'CAP CHIP 0.22U 16V(10%,X7R,0402)MURSELA'                      | 'CHIP0402'     | ''          | ''   | '20230713'
 '0.22UF'   | '16V'   | '10%'     | 'C0402'     | 'EMPTY'   | 'CH4223K1B04SEL1'(!) = ''              | ''                 | ''       | 'CH4223K1B04SEL1' |'C0402'| '(C0402-0201)'                                                       | 'NA'       | '16V'         | '10%'    | 'IO'       | 'CAP CHIP 0.22U 16V(10%,X7R,0402)MURSELA'                      | 'CHIP0402'     | ''          | ''   | '20230713'
 '0.22UF'   | '25V'   | '10%'     | 'C0402'     | 'X7R'     | 'CH4224K1B03SEL1'(!) = ''              | ''                 | ''       | 'CH4224K1B03SEL1' |'C0402'| '(C0402-0201)'                                                       | '0.22UF'   | '25V'         | '10%'    | 'DISCRETE' | 'CAP CHIP 0.22UF 25V(10%,X7R,0402)MURSELA'                     | 'CHIP0402'     | ''          | ''   | '20230713'
 '0.22UF'   | '25V'   | '10%'     | 'C0402'     | 'EMPTY'   | 'CH4224K1B03SEL1'(!) = ''              | ''                 | ''       | 'CH4224K1B03SEL1' |'C0402'| '(C0402-0201)'                                                       | 'NA'       | '25V'         | '10%'    | 'IO'       | 'CAP CHIP 0.22UF 25V(10%,X7R,0402)MURSELA'                     | 'CHIP0402'     | ''          | ''   | '20230713'
 '0.47UF'   | '16V'   | '10%'     | 'C0603'     | 'X7R'     | 'CH4473K1904SEL1'(!) = ''              | ''                 | ''       | 'CH4473K1904SEL1' |'C0603'| '(SMC0603AW)'                                                        | '0.47UF'   | '16V'         | '10%'    | 'DISCRETE' | 'CAP CHIP 0.47U 16V (10%,X7R,0603)MURSELA'                     | 'CHIP0603'     | ''          | ''   | '20230713'
 '0.47UF'   | '16V'   | '10%'     | 'C0603'     | 'EMPTY'   | 'CH4473K1904SEL1'(!) = ''              | ''                 | ''       | 'CH4473K1904SEL1' |'C0603'| '(SMC0603AW)'                                                        | 'NA'       | '16V'         | '10%'    | 'IO'       | 'CAP CHIP 0.47U 16V (10%,X7R,0603)MURSELA'                     | 'CHIP0603'     | ''          | ''   | '20230713'
 '0.47UF'   | '100V'  | '10%'     | 'C0805'     | 'X7R'     | 'CH4478K1A01SEL1'(!) = ''              | ''                 | ''       | 'CH4478K1A01SEL1' |'C0805_H61'| '(SMC0805AW)'                                                        | '0.47UF'   | '100V'        | '10%'    | 'DISCRETE' | 'CAP CHIP 0.47U 100V(10%,X7R,0805)MURSELA'                     | 'CHIP0805'     | ''          | ''   | '20230713'
 '0.47UF'   | '100V'  | '10%'     | 'C0805'     | 'EMPTY'   | 'CH4478K1A01SEL1'(!) = ''              | ''                 | ''       | 'CH4478K1A01SEL1' |'C0805_H61'| '(SMC0805AW)'                                                        | 'NA'       | '100V'        | '10%'    | 'IO'       | 'CAP CHIP 0.47U 100V(10%,X7R,0805)MURSELA'                     | 'CHIP0805'     | ''          | ''   | '20230713'
 '1UF'      | '6.3V'  | '10%'     | 'C0402'     | 'X7R'     | 'CH5101K1B05SEL1'(!) = ''              | ''                 | ''       | 'CH5101K1B05SEL1' |'C0402'| '(C0402-0201)'                                                       | '1UF'      | '6.3V'        | '10%'    | 'DISCRETE' | 'CAP CHIP 1U,6.3V(+-10%,X7R,0402)MURSELA'                      | 'CHIP0402'     | ''          | ''   | '20230713'
 '1UF'      | '6.3V'  | '10%'     | 'C0402'     | 'EMPTY'   | 'CH5101K1B05SEL1'(!) = ''              | ''                 | ''       | 'CH5101K1B05SEL1' |'C0402'| '(C0402-0201)'                                                       | 'NA'       | '6.3V'        | '10%'    | 'IO'       | 'CAP CHIP 1U,6.3V(+-10%,X7R,0402)MURSELA'                      | 'CHIP0402'     | ''          | ''   | '20230713'
 '1UF'      | '10V'   | '10%'     | 'C0402'     | 'X6S'     | 'CH5102KEB02SEL1'(!) = ''              | ''                 | ''       | 'CH5102KEB02SEL1' |'C0402'| '(C0402-0201)'                                                       | '1UF'      | '10V'         | '10%'    | 'DISCRETE' | 'CAP CHIP 1UF 10V(+-10%,X6S,0402)MURSELA'                      | 'CHIP0402'     | ''          | ''   | '20230713'
 '1UF'      | '10V'   | '10%'     | 'C0402'     | 'EMPTY'   | 'CH5102KEB02SEL1'(!) = ''              | ''                 | ''       | 'CH5102KEB02SEL1' |'C0402'| '(C0402-0201)'                                                       | 'NA'       | '10V'         | '10%'    | 'IO'       | 'CAP CHIP 1UF 10V(+-10%,X6S,0402)MURSELA'                      | 'CHIP0402'     | ''          | ''   | '20230713'
 '1UF'      | '16V'   | '10%'     | 'C0402'     | 'X6S'     | 'CH5103KEB03SEL1'(!) = ''              | ''                 | ''       | 'CH5103KEB03SEL1' |'C0402'| '(C0402-0201)'                                                       | '1UF'      | '16V'         | '10%'    | 'DISCRETE' | 'CAP CHIP 1UF 16V(10%,X6S,0402)MURSELA'                        | 'CHIP0402'     | ''          | ''   | '20230713'
 '1UF'      | '16V'   | '10%'     | 'C0402'     | 'EMPTY'   | 'CH5103KEB03SEL1'(!) = ''              | ''                 | ''       | 'CH5103KEB03SEL1' |'C0402'| '(C0402-0201)'                                                       | 'NA'       | '16V'         | '10%'    | 'IO'       | 'CAP CHIP 1UF 16V(10%,X6S,0402)MURSELA'                        | 'CHIP0402'     | ''          | ''   | '20230713'
 '1UF'      | '25V'   | '10%'     | 'C0603'     | 'X7R'     | 'CH5104K1903SEL1'(!) = ''              | ''                 | ''       | 'CH5104K1903SEL1' |'C0603'| '(SMC0603AW)'                                                        | '1UF'      | '25V'         | '10%'    | 'DISCRETE' | 'CAP CHIP 1U 25V(+-10%.X7R.0603)MURSELA'                       | 'CHIP0603'     | ''          | ''   | '20230713'
 '1UF'      | '25V'   | '10%'     | 'C0603'     | 'EMPTY'   | 'CH5104K1903SEL1'(!) = ''              | ''                 | ''       | 'CH5104K1903SEL1' |'C0603'| '(SMC0603AW)'                                                        | 'NA'       | '25V'         | '10%'    | 'IO'       | 'CAP CHIP 1U 25V(+-10%.X7R.0603)MURSELA'                       | 'CHIP0603'     | ''          | ''   | '20230713'
 '1UF'      | '25V'   | '10%'     | 'C0402'     | 'X6S'     | 'CH5104KEB03SEL1'(!) = ''              | ''                 | ''       | 'CH5104KEB03SEL1' |'C0402'| '(C0402-0201)'                                                       | '1UF'      | '25V'         | '10%'    | 'DISCRETE' | 'CAP CHIP 1UF 25V(+-10%,X6S,0402)MURSELA'                      | 'CHIP0402'     | ''          | ''   | '20230713'
 '1UF'      | '25V'   | '10%'     | 'C0402'     | 'EMPTY'   | 'CH5104KEB03SEL1'(!) = ''              | ''                 | ''       | 'CH5104KEB03SEL1' |'C0402'| '(C0402-0201)'                                                       | 'NA'       | '25V'         | '10%'    | 'IO'       | 'CAP CHIP 1UF 25V(+-10%,X6S,0402)MURSELA'                      | 'CHIP0402'     | ''          | ''   | '20230713'
 '1UF'      | '25V'   | '10%'     | 'C0402'     | 'X6S'     | 'CH5104KEB04SEL1'(!) = ''              | ''                 | ''       | 'CH5104KEB04SEL1' |'C0402'| '(C0402-0201)'                                                       | '1UF'      | '25V'         | '10%'    | 'DISCRETE' | 'CAP CHIP 1UF 25V(+-10%,X6S,0402)SAMSELA'                      | 'CHIP0402'     | ''          | ''   | '20230713'
 '1UF'      | '25V'   | '10%'     | 'C0402'     | 'EMPTY'   | 'CH5104KEB04SEL1'(!) = ''              | ''                 | ''       | 'CH5104KEB04SEL1' |'C0402'| '(C0402-0201)'                                                       | 'NA'       | '25V'         | '10%'    | 'IO'       | 'CAP CHIP 1UF 25V(+-10%,X6S,0402)SAMSELA'                      | 'CHIP0402'     | ''          | ''   | '20230713'
 '1UF'      | '100V'  | '10%'     | 'C1206'     | 'X7R'     | 'CH5108K1201SEL1'(!) = ''              | ''                 | ''       | 'CH5108K1201SEL1' |'C1206_H66'| '(SMC1206AW)'                                                        | '1UF'      | '100V'        | '10%'    | 'DISCRETE' | 'CAP CHIP 1U 100V(10%.1206.X7R)MURSELA'                        | 'CHIP1206'     | ''          | ''   | '20230713'
 '1UF'      | '100V'  | '10%'     | 'C1206'     | 'EMPTY'   | 'CH5108K1201SEL1'(!) = ''              | ''                 | ''       | 'CH5108K1201SEL1' |'C1206_H66'| '(SMC1206AW)'                                                        | 'NA'       | '100V'        | '10%'    | 'IO'       | 'CAP CHIP 1U 100V(10%.1206.X7R)MURSELA'                        | 'CHIP1206'     | ''          | ''   | '20230713'
 '2.2UF'    | '6.3V'  | '20%'     | 'C0402'     | 'X6S'     | 'CH5221MEB03SEL1'(!) = ''              | ''                 | ''       | 'CH5221MEB03SEL1' |'C0402'| '(C0402-0201)'                                                       | '2.2UF'    | '6.3V'        | '20%'    | 'DISCRETE' | 'CAP CHIP 2.2U 6.3V(20%,X6S,0402)MURSELA'                      | 'CHIP0402'     | ''          | ''   | '20230713'
 '2.2UF'    | '6.3V'  | '20%'     | 'C0402'     | 'EMPTY'   | 'CH5221MEB03SEL1'(!) = ''              | ''                 | ''       | 'CH5221MEB03SEL1' |'C0402'| '(C0402-0201)'                                                       | 'NA'       | '6.3V'        | '20%'    | 'IO'       | 'CAP CHIP 2.2U 6.3V(20%,X6S,0402)MURSELA'                      | 'CHIP0402'     | ''          | ''   | '20230713'
 '2.2UF'    | '10V'   | '10%'     | 'C0603'     | 'X7R'     | 'CH5222K1904SEL1'(!) = ''              | ''                 | ''       | 'CH5222K1904SEL1' |'C0603'| '(SMC0603AW)'                                                        | '2.2UF'    | '10V'         | '10%'    | 'DISCRETE' | 'CAP CHIP 2.2UF 10V(10%,X7R,0603)MURSELA'                      | 'CHIP0603'     | ''          | ''   | '20230713'
 '2.2UF'    | '10V'   | '10%'     | 'C0603'     | 'EMPTY'   | 'CH5222K1904SEL1'(!) = ''              | ''                 | ''       | 'CH5222K1904SEL1' |'C0603'| '(SMC0603AW)'                                                        | 'NA'       | '10V'         | '10%'    | 'IO'       | 'CAP CHIP 2.2UF 10V(10%,X7R,0603)MURSELA'                      | 'CHIP0603'     | ''          | ''   | '20230713'
 '2.2UF'    | '10V'   | '10%'     | 'C0402'     | 'X6S'     | 'CH5222KEB02SEL1'(!) = ''              | ''                 | ''       | 'CH5222KEB02SEL1' |'C0402_H28'| '(C0402-0201_H28)'                                                   | '2.2UF'    | '10V'         | '10%'    | 'DISCRETE' | 'CAP CHIP 2.2UF 10V(10%,X6S,0402)MURSELA'                      | 'CHIP0402'     | ''          | ''   | '20230713'
 '2.2UF'    | '10V'   | '10%'     | 'C0402'     | 'EMPTY'   | 'CH5222KEB02SEL1'(!) = ''              | ''                 | ''       | 'CH5222KEB02SEL1' |'C0402_H28'| '(C0402-0201_H28)'                                                   | 'NA'       | '10V'         | '10%'    | 'IO'       | 'CAP CHIP 2.2UF 10V(10%,X6S,0402)MURSELA'                      | 'CHIP0402'     | ''          | ''   | '20230713'
 '2.2UF'    | '16V'   | '20%'     | 'C0402'     | 'X6S'     | 'CH5223MEB01SEL1'(!) = ''              | ''                 | ''       | 'CH5223MEB01SEL1' |'C0402'| '(C0402-0201)'                                                       | '2.2UF'    | '16V'         | '20%'    | 'DISCRETE' | 'CAP CHIP 2.2U 16V(20%,X6S,0402)MURSELASN'                     | 'CHIP0402'     | ''          | ''   | '20230713'
 '2.2UF'    | '16V'   | '20%'     | 'C0402'     | 'EMPTY'   | 'CH5223MEB01SEL1'(!) = ''              | ''                 | ''       | 'CH5223MEB01SEL1' |'C0402'| '(C0402-0201)'                                                       | 'NA'       | '16V'         | '20%'    | 'IO'       | 'CAP CHIP 2.2U 16V(20%,X6S,0402)MURSELASN'                     | 'CHIP0402'     | ''          | ''   | '20230713'
 '2.2UF'    | '100V'  | '10%'     | 'C1206'     | 'X7R'     | 'CH5228K1207SEL1'(!) = ''              | ''                 | ''       | 'CH5228K1207SEL1' |'C1206_H66'| '(SMC1206AW)'                                                        | '2.2UF'    | '100V'        | '10%'    | 'DISCRETE' | 'CAP CHIP 2.2UF 100V(10%,X7R,1206)MURSELA'                     | 'CHIP1206'     | ''          | ''   | '20230713'
 '2.2UF'    | '100V'  | '10%'     | 'C1206'     | 'EMPTY'   | 'CH5228K1207SEL1'(!) = ''              | ''                 | ''       | 'CH5228K1207SEL1' |'C1206_H66'| '(SMC1206AW)'                                                        | 'NA'       | '100V'        | '10%'    | 'IO'       | 'CAP CHIP 2.2UF 100V(10%,X7R,1206)MURSELA'                     | 'CHIP1206'     | ''          | ''   | '20230713'
 '2.2UF'    | '100V'  | '10%'     | 'C1206'     | 'X7R'     | 'CH5228K1208SEL1'(!) = ''              | ''                 | ''       | 'CH5228K1208SEL1' |'C1206_H66'| '(SMC1206AW)'                                                        | '2.2UF'    | '100V'        | '10%'    | 'DISCRETE' | 'CAP CHIP 2.2UF 100V(10%,X7R,1206)SAMSELA'                     | 'CHIP1206'     | ''          | ''   | '20230713'
 '2.2UF'    | '100V'  | '10%'     | 'C1206'     | 'EMPTY'   | 'CH5228K1208SEL1'(!) = ''              | ''                 | ''       | 'CH5228K1208SEL1' |'C1206_H66'| '(SMC1206AW)'                                                        | 'NA'       | '100V'        | '10%'    | 'IO'       | 'CAP CHIP 2.2UF 100V(10%,X7R,1206)SAMSELA'                     | 'CHIP1206'     | ''          | ''   | '20230713'
 '4.7UF'    | '6.3V'  | '20%'     | 'C0402'     | 'X6S'     | 'CH5471MEB02SEL1'(!) = ''              | ''                 | ''       | 'CH5471MEB02SEL1' |'C0402'| '(C0402-0201)'                                                       | '4.7UF'    | '6.3V'        | '20%'    | 'DISCRETE' | 'CAP CHIP 4.7UF 6.3V(20%,X6S,0402)MURSELA'                     | 'CHIP0402'     | ''          | ''   | '20230713'
 '4.7UF'    | '6.3V'  | '20%'     | 'C0402'     | 'EMPTY'   | 'CH5471MEB02SEL1'(!) = ''              | ''                 | ''       | 'CH5471MEB02SEL1' |'C0402'| '(C0402-0201)'                                                       | 'NA'       | '6.3V'        | '20%'    | 'IO'       | 'CAP CHIP 4.7UF 6.3V(20%,X6S,0402)MURSELA'                     | 'CHIP0402'     | ''          | ''   | '20230713'
 '4.7UF'    | '16V'   | '10%'     | 'C0603'     | 'X6S'     | 'CH5473KE903SEL1'(!) = ''              | ''                 | ''       | 'CH5473KE903SEL1' |'C0603_H40'| '(SMC0603AW)'                                                        | '4.7UF'    | '16V'         | '10%'    | 'DISCRETE' | 'CAP CHIP 4.7UF 16V(10%,X6S,0603)MURSELA'                      | 'CHIP0603'     | ''          | ''   | '20230713'
 '4.7UF'    | '16V'   | '10%'     | 'C0603'     | 'EMPTY'   | 'CH5473KE903SEL1'(!) = ''              | ''                 | ''       | 'CH5473KE903SEL1' |'C0603_H40'| '(SMC0603AW)'                                                        | 'NA'       | '16V'         | '10%'    | 'IO'       | 'CAP CHIP 4.7UF 16V(10%,X6S,0603)MURSELA'                      | 'CHIP0603'     | ''          | ''   | '20230713'
 '4.7UF'    | '25V'   | '10%'     | 'C0603'     | 'X6S'     | 'CH5474KE902SEL1'(!) = ''              | ''                 | ''       | 'CH5474KE902SEL1' |'C0603'| '(SMC0603AW)'                                                        | '4.7UF'    | '25V'         | '10%'    | 'DISCRETE' | 'CAP CHIP 4.7UF 25V(10%,X6S,0603)MURSELA'                      | 'CHIP0603'     | ''          | ''   | '20230713'
 '4.7UF'    | '25V'   | '10%'     | 'C0603'     | 'EMPTY'   | 'CH5474KE902SEL1'(!) = ''              | ''                 | ''       | 'CH5474KE902SEL1' |'C0603'| '(SMC0603AW)'                                                        | 'NA'       | '25V'         | '10%'    | 'IO'       | 'CAP CHIP 4.7UF 25V(10%,X6S,0603)MURSELA'                      | 'CHIP0603'     | ''          | ''   | '20230713'
 '10UF'     | '6.3V'  | '20%'     | 'C0603'     | 'X6S'     | 'CH6101ME902SEL1'(!) = ''              | ''                 | ''       | 'CH6101ME902SEL1' |'C0603'| '(SMC0603AW)'                                                        | '10UF'     | '6.3V'        | '20%'    | 'DISCRETE' | 'CAP CHIP 10U 6.3V(+-20%,X6S,0603)MURSELA'                     | 'CHIP0603'     | ''          | ''   | '20230713'
 '10UF'     | '6.3V'  | '20%'     | 'C0603'     | 'EMPTY'   | 'CH6101ME902SEL1'(!) = ''              | ''                 | ''       | 'CH6101ME902SEL1' |'C0603'| '(SMC0603AW)'                                                        | 'NA'       | '6.3V'        | '20%'    | 'IO'       | 'CAP CHIP 10U 6.3V(+-20%,X6S,0603)MURSELA'                     | 'CHIP0603'     | ''          | ''   | '20230713'
 '10UF'     | '6.3V'  | '20%'     | 'C0402'     | 'X6S'     | 'CH6101MEB03SEL1'(!) = ''              | ''                 | ''       | 'CH6101MEB03SEL1' |'C0402'| '(C0402-0201)'                                                       | '10UF'     | '6.3V'        | '20%'    | 'DISCRETE' | 'CAP CHIP 10UF 6.3V(20%,X6S,0402)MURSELA'                      | 'CHIP0402'     | ''          | ''   | '20230713'
 '10UF'     | '6.3V'  | '20%'     | 'C0402'     | 'EMPTY'   | 'CH6101MEB03SEL1'(!) = ''              | ''                 | ''       | 'CH6101MEB03SEL1' |'C0402'| '(C0402-0201)'                                                       | 'NA'       | '6.3V'        | '20%'    | 'IO'       | 'CAP CHIP 10UF 6.3V(20%,X6S,0402)MURSELA'                      | 'CHIP0402'     | ''          | ''   | '20230713'
 '10UF'     | '6.3V'  | '20%'     | 'C0402'     | 'X6S'     | 'CH6101MEB08SEL1'(!) = ''              | ''                 | ''       | 'CH6101MEB08SEL1' |'C0402_H28'| '(C0402-0201_H28)'                                                   | '10UF'     | '6.3V'        | '20%'    | 'DISCRETE' | 'CAP CHIP 10UF 6.3V(20%,X6S,0402)SAMSELA'                      | 'CHIP0402'     | ''          | ''   | '20230713'
 '10UF'     | '6.3V'  | '20%'     | 'C0402'     | 'EMPTY'   | 'CH6101MEB08SEL1'(!) = ''              | ''                 | ''       | 'CH6101MEB08SEL1' |'C0402_H28'| '(C0402-0201_H28)'                                                   | 'NA'       | '6.3V'        | '20%'    | 'IO'       | 'CAP CHIP 10UF 6.3V(20%,X6S,0402)SAMSELA'                      | 'CHIP0402'     | ''          | ''   | '20230713'
 '10UF'     | '16V'   | '10%'     | 'C0805'     | 'X7R'     | 'CH6103K1A01SEL1'(!) = ''              | ''                 | ''       | 'CH6103K1A01SEL1' |'C0805_H61'| '(SMC0805AW)'                                                        | '10UF'     | '16V'         | '10%'    | 'DISCRETE' | 'CAP CHIP 10UF 16V(+-10%,X7R,0805)SAMSELA'                     | 'CHIP0805'     | ''          | ''   | '20230713'
 '10UF'     | '16V'   | '10%'     | 'C0805'     | 'EMPTY'   | 'CH6103K1A01SEL1'(!) = ''              | ''                 | ''       | 'CH6103K1A01SEL1' |'C0805_H61'| '(SMC0805AW)'                                                        | 'NA'       | '16V'         | '10%'    | 'IO'       | 'CAP CHIP 10UF 16V(+-10%,X7R,0805)SAMSELA'                     | 'CHIP0805'     | ''          | ''   | '20230713'
 '10UF'     | '16V'   | '10%'     | 'C0805'     | 'X6S'     | 'CH6103KEA01SEL1'(!) = ''              | ''                 | ''       | 'CH6103KEA01SEL1' |'C0805_H57'| '(SMC0805AW)'                                                        | '10UF'     | '16V'         | '10%'    | 'DISCRETE' | 'CAP CHIP 10UF 16V(+-10%,X6S,0805)MURSELA'                     | 'CHIP0805'     | ''          | ''   | '20230713'
 '10UF'     | '16V'   | '10%'     | 'C0805'     | 'EMPTY'   | 'CH6103KEA01SEL1'(!) = ''              | ''                 | ''       | 'CH6103KEA01SEL1' |'C0805_H57'| '(SMC0805AW)'                                                        | 'NA'       | '16V'         | '10%'    | 'IO'       | 'CAP CHIP 10UF 16V(+-10%,X6S,0805)MURSELA'                     | 'CHIP0805'     | ''          | ''   | '20230713'
 '10UF'     | '16V'   | '20%'     | 'C0603'     | 'X6S'     | 'CH6103ME904SEL1'(!) = ''              | ''                 | ''       | 'CH6103ME904SEL1' |'C0603'| '(SMC0603AW)'                                                        | '10UF'     | '16V'         | '20%'    | 'DISCRETE' | 'CAP CHIP 10UF 16V(20%,X6S,0603)MURSELASN'                     | 'CHIP0603'     | ''          | ''   | '20230713'
 '10UF'     | '16V'   | '20%'     | 'C0603'     | 'EMPTY'   | 'CH6103ME904SEL1'(!) = ''              | ''                 | ''       | 'CH6103ME904SEL1' |'C0603'| '(SMC0603AW)'                                                        | 'NA'       | '16V'         | '20%'    | 'IO'       | 'CAP CHIP 10UF 16V(20%,X6S,0603)MURSELASN'                     | 'CHIP0603'     | ''          | ''   | '20230713'
 '10UF'     | '25V'   | '10%'     | 'C0805'     | 'X6S'     | 'CH6104KEA03SEL1'(!) = ''              | ''                 | ''       | 'CH6104KEA03SEL1' |'C0805_H61'| '(SMC0805AW)'                                                        | '10UF'     | '25V'         | '10%'    | 'DISCRETE' | 'CAP CHIP 10U 25V(10%,X6S,0805)MURSELASN'                      | 'CHIP0805'     | ''          | ''   | '20230713'
 '10UF'     | '25V'   | '10%'     | 'C0805'     | 'EMPTY'   | 'CH6104KEA03SEL1'(!) = ''              | ''                 | ''       | 'CH6104KEA03SEL1' |'C0805_H61'| '(SMC0805AW)'                                                        | 'NA'       | '25V'         | '10%'    | 'IO'       | 'CAP CHIP 10U 25V(10%,X6S,0805)MURSELASN'                      | 'CHIP0805'     | ''          | ''   | '20230713'
 '10UF'     | '25V'   | '10%'     | 'C0805'     | 'X6S'     | 'CH6104KEA08SEL1'(!) = ''              | ''                 | ''       | 'CH6104KEA08SEL1' |'C0805_H57'| '(SMC0805AW)'                                                        | '10UF'     | '25V'         | '10%'    | 'DISCRETE' | 'CAP CHIP 10U 25V(10%,X6S,0805)TAYSELASN'                      | 'CHIP0805'     | ''          | ''   | '20230713'
 '10UF'     | '25V'   | '10%'     | 'C0805'     | 'EMPTY'   | 'CH6104KEA08SEL1'(!) = ''              | ''                 | ''       | 'CH6104KEA08SEL1' |'C0805_H57'| '(SMC0805AW)'                                                        | 'NA'       | '25V'         | '10%'    | 'IO'       | 'CAP CHIP 10U 25V(10%,X6S,0805)TAYSELASN'                      | 'CHIP0805'     | ''          | ''   | '20230713'
 '10UF'     | '50V'   | '10%'     | 'C1210'     | 'X7R'     | 'CH6106K1303SEL1'(!) = ''              | ''                 | ''       | 'CH6106K1303SEL1' |'C1210_GRM32E'| '(SMC1210AW)'                                                        | '10UF'     | '50V'         | '10%'    | 'DISCRETE' | 'CAP CHIP 10U 50V(10%,X7R,1210)MURSELASN'                      | 'CHIP1210'     | ''          | ''   | '20230713'
 '10UF'     | '50V'   | '10%'     | 'C1210'     | 'EMPTY'   | 'CH6106K1303SEL1'(!) = ''              | ''                 | ''       | 'CH6106K1303SEL1' |'C1210_GRM32E'| '(SMC1210AW)'                                                        | 'NA'       | '50V'         | '10%'    | 'IO'       | 'CAP CHIP 10U 50V(10%,X7R,1210)MURSELASN'                      | 'CHIP1210'     | ''          | ''   | '20230713'
 '10UF'     | '100V'  | '10%'     | 'C1210'     | 'X7S'     | 'CH6108K6300SEL1'(!) = ''              | ''                 | ''       | 'CH6108K6300SEL1' |'C1210_GRM32E'| '(SMC1210AW)'                                                        | '10UF'     | '100V'        | '10%'    | 'DISCRETE' | 'CAP CHIP 10UF 100V(10%,X7S,1210)MURSELA'                      | 'CHIP1210'     | ''          | ''   | '20230713'
 '10UF'     | '100V'  | '10%'     | 'C1210'     | 'EMPTY'   | 'CH6108K6300SEL1'(!) = ''              | ''                 | ''       | 'CH6108K6300SEL1' |'C1210_GRM32E'| '(SMC1210AW)'                                                        | 'NA'       | '100V'        | '10%'    | 'IO'       | 'CAP CHIP 10UF 100V(10%,X7S,1210)MURSELA'                      | 'CHIP1210'     | ''          | ''   | '20230713'
 '22UF'     | '6.3V'  | '20%'     | 'C0603'     | 'X6S'     | 'CH6221ME901SEL1'(!) = ''              | ''                 | ''       | 'CH6221ME901SEL1' |'C0603'| '(SMC0603AW)'                                                        | '22UF'     | '6.3V'        | '20%'    | 'DISCRETE' | 'CAP CHIP 22U 6.3V(20%,X6S,0603)MURSELASN'                     | 'CHIP0603'     | ''          | ''   | '20230713'
 '22UF'     | '6.3V'  | '20%'     | 'C0603'     | 'EMPTY'   | 'CH6221ME901SEL1'(!) = ''              | ''                 | ''       | 'CH6221ME901SEL1' |'C0603'| '(SMC0603AW)'                                                        | 'NA'       | '6.3V'        | '20%'    | 'IO'       | 'CAP CHIP 22U 6.3V(20%,X6S,0603)MURSELASN'                     | 'CHIP0603'     | ''          | ''   | '20230713'
 '22UF'     | '6.3V'  | '20%'     | 'C0603'     | 'X6S'     | 'CH6221ME907SEL1'(!) = ''              | ''                 | ''       | 'CH6221ME907SEL1' |'C0603_H40'| '(SMC0603AW)'                                                        | '22UF'     | '6.3V'        | '20%'    | 'DISCRETE' | 'CAP CHIP 22U 6.3V(20%,X6S,0603)SAMSELASN'                     | 'CHIP0603'     | ''          | ''   | '20230713'
 '22UF'     | '6.3V'  | '20%'     | 'C0603'     | 'EMPTY'   | 'CH6221ME907SEL1'(!) = ''              | ''                 | ''       | 'CH6221ME907SEL1' |'C0603_H40'| '(SMC0603AW)'                                                        | 'NA'       | '6.3V'        | '20%'    | 'IO'       | 'CAP CHIP 22U 6.3V(20%,X6S,0603)SAMSELASN'                     | 'CHIP0603'     | ''          | ''   | '20230713'
 '22UF'     | '6.3V'  | '20%'     | 'C0805'     | 'X6S'     | 'CH6221MEA04SEL1'(!) = ''              | ''                 | ''       | 'CH6221MEA04SEL1' |'C0805_H61'| '(SMC0805AW)'                                                        | '22UF'     | '6.3V'        | '20%'    | 'DISCRETE' | 'CAP CHIP 22U 6.3V(+-20%,X6S,0805)MURSELA'                     | 'CHIP0805'     | ''          | ''   | '20230713'
 '22UF'     | '6.3V'  | '20%'     | 'C0805'     | 'EMPTY'   | 'CH6221MEA04SEL1'(!) = ''              | ''                 | ''       | 'CH6221MEA04SEL1' |'C0805_H61'| '(SMC0805AW)'                                                        | 'NA'       | '6.3V'        | '20%'    | 'IO'       | 'CAP CHIP 22U 6.3V(+-20%,X6S,0805)MURSELA'                     | 'CHIP0805'     | ''          | ''   | '20230713'
 '22UF'     | '6.3V'  | '20%'     | 'C0805'     | 'X6S'     | 'CH6221MEA06SEL1'(!) = ''              | ''                 | ''       | 'CH6221MEA06SEL1' |'C0805_H57'| '(SMC0805AW)'                                                        | '22UF'     | '6.3V'        | '20%'    | 'DISCRETE' | 'CAP CHIP 22U 6.3V(+-20%,X6S,0805)SAMSELA'                     | 'CHIP0805'     | ''          | ''   | '20230713'
 '22UF'     | '6.3V'  | '20%'     | 'C0805'     | 'EMPTY'   | 'CH6221MEA06SEL1'(!) = ''              | ''                 | ''       | 'CH6221MEA06SEL1' |'C0805_H57'| '(SMC0805AW)'                                                        | 'NA'       | '6.3V'        | '20%'    | 'IO'       | 'CAP CHIP 22U 6.3V(+-20%,X6S,0805)SAMSELA'                     | 'CHIP0805'     | ''          | ''   | '20230713'
 '22UF'     | '10V'   | '20%'     | 'C0805'     | 'X6S'     | 'CH6222MEA01SEL1'(!) = ''              | ''                 | ''       | 'CH6222MEA01SEL1' |'C0805_H61'| '(SMC0805AW)'                                                        | '22UF'     | '10V'         | '20%'    | 'DISCRETE' | 'CAP CHIP 22U 10V(20%,X6S,0805)MURSELASN'                      | 'CHIP0805'     | ''          | ''   | '20230713'
 '22UF'     | '10V'   | '20%'     | 'C0805'     | 'EMPTY'   | 'CH6222MEA01SEL1'(!) = ''              | ''                 | ''       | 'CH6222MEA01SEL1' |'C0805_H61'| '(SMC0805AW)'                                                        | 'NA'       | '10V'         | '20%'    | 'IO'       | 'CAP CHIP 22U 10V(20%,X6S,0805)MURSELASN'                      | 'CHIP0805'     | ''          | ''   | '20230713'
 '22UF'     | '16V'   | '20%'     | 'C0805'     | 'X6S'     | 'CH6223MEA01SEL1'(!) = ''              | ''                 | ''       | 'CH6223MEA01SEL1' |'C0805_H57'| '(SMC0805AW)'                                                        | '22UF'     | '16V'         | '20%'    | 'DISCRETE' | 'CAP CHIP 22UF 16V(+-20%,X6S,0805)MURSELA'                     | 'CHIP0805'     | ''          | ''   | '20230713'
 '22UF'     | '16V'   | '20%'     | 'C0805'     | 'EMPTY'   | 'CH6223MEA01SEL1'(!) = ''              | ''                 | ''       | 'CH6223MEA01SEL1' |'C0805_H57'| '(SMC0805AW)'                                                        | 'NA'       | '16V'         | '20%'    | 'IO'       | 'CAP CHIP 22UF 16V(+-20%,X6S,0805)MURSELA'                     | 'CHIP0805'     | ''          | ''   | '20230713'
 '22UF'     | '25V'   | '20%'     | 'C0805'     | 'X5R'     | 'CH6224M9A05SEL1'(!) = ''              | ''                 | ''       | 'CH6224M9A05SEL1' |'C0805_H57'| '(SMC0805AW)'                                                        | '22UF'     | '25V'         | '20%'    | 'DISCRETE' | 'CAP CHIP 22U 25V(20%,X5R,0805)MURSELASN'                      | 'CHIP0805'     | ''          | ''   | '20230713'
 '22UF'     | '25V'   | '20%'     | 'C0805'     | 'EMPTY'   | 'CH6224M9A05SEL1'(!) = ''              | ''                 | ''       | 'CH6224M9A05SEL1' |'C0805_H57'| '(SMC0805AW)'                                                        | 'NA'       | '25V'         | '20%'    | 'IO'       | 'CAP CHIP 22U 25V(20%,X5R,0805)MURSELASN'                      | 'CHIP0805'     | ''          | ''   | '20230713'
 '22UF'     | '4V'    | '20%'     | 'C0603'     | 'X6S'     | 'CH622KME905SEL1'(!) = ''              | ''                 | ''       | 'CH622KME905SEL1' |'C0603'| '(SMC0603AW)'                                                        | '22UF'     | '4V'          | '20%'    | 'DISCRETE' | 'CAP CHIP 22UF 4V(+-20%,X6S,0603)MURSELA'                      | 'CHIP0603'     | ''          | ''   | '20230713'
 '22UF'     | '4V'    | '20%'     | 'C0603'     | 'EMPTY'   | 'CH622KME905SEL1'(!) = ''              | ''                 | ''       | 'CH622KME905SEL1' |'C0603'| '(SMC0603AW)'                                                        | 'NA'       | '4V'          | '20%'    | 'IO'       | 'CAP CHIP 22UF 4V(+-20%,X6S,0603)MURSELA'                      | 'CHIP0603'     | ''          | ''   | '20230713'
 '22UF'     | '4V'    | '20%'     | 'C0805'     | 'X6S'     | 'CH622KMEA03SEL1'(!) = ''              | ''                 | ''       | 'CH622KMEA03SEL1' |'C0805_H61'| '(SMC0805AW)'                                                        | '22UF'     | '4V'          | '20%'    | 'DISCRETE' | 'CAP CHIP 22U 4V(+-20%,X6S,0805)MURSELA'                       | 'CHIP0805'     | ''          | ''   | '20230713'
 '22UF'     | '4V'    | '20%'     | 'C0805'     | 'EMPTY'   | 'CH622KMEA03SEL1'(!) = ''              | ''                 | ''       | 'CH622KMEA03SEL1' |'C0805_H61'| '(SMC0805AW)'                                                        | 'NA'       | '4V'          | '20%'    | 'IO'       | 'CAP CHIP 22U 4V(+-20%,X6S,0805)MURSELA'                       | 'CHIP0805'     | ''          | ''   | '20230713'
 '22UF'     | '4V'    | '20%'     | 'C0805'     | 'X6S'     | 'CH622KMEA04SEL1'(!) = ''              | ''                 | ''       | 'CH622KMEA04SEL1' |'C0805_H57'| '(SMC0805AW)'                                                        | '22UF'     | '4V'          | '20%'    | 'DISCRETE' | 'CAP CHIP 22U 4V(+-20%,X6S,0805)SAMSELA'                       | 'CHIP0805'     | ''          | ''   | '20230713'
 '22UF'     | '4V'    | '20%'     | 'C0805'     | 'EMPTY'   | 'CH622KMEA04SEL1'(!) = ''              | ''                 | ''       | 'CH622KMEA04SEL1' |'C0805_H57'| '(SMC0805AW)'                                                        | 'NA'       | '4V'          | '20%'    | 'IO'       | 'CAP CHIP 22U 4V(+-20%,X6S,0805)SAMSELA'                       | 'CHIP0805'     | ''          | ''   | '20230713'
 '22UF'     | '4V'    | '20%'     | 'C0402'     | 'X6S'     | 'CH622KMEB01SEL1'(!) = ''              | ''                 | ''       | 'CH622KMEB01SEL1' |'C0402_H32'| '(C0402-0201_H32)'                                                   | '22UF'     | '4V'          | '20%'    | 'DISCRETE' | 'CAP CHIP 22UF 4V(+-20%,X6S,0402)MURSELA'                      | 'CHIP0402'     | ''          | ''   | '20230713'
 '22UF'     | '4V'    | '20%'     | 'C0402'     | 'EMPTY'   | 'CH622KMEB01SEL1'(!) = ''              | ''                 | ''       | 'CH622KMEB01SEL1' |'C0402_H32'| '(C0402-0201_H32)'                                                   | 'NA'       | '4V'          | '20%'    | 'IO'       | 'CAP CHIP 22UF 4V(+-20%,X6S,0402)MURSELA'                      | 'CHIP0402'     | ''          | ''   | '20230713'
 '47UF'     | '6.3V'  | '20%'     | 'C0805'     | 'X5R'     | 'CH6471M9A08SEL1'(!) = ''              | ''                 | ''       | 'CH6471M9A08SEL1' |'C0805_H57'| '(SMC0805AW)'                                                        | '47UF'     | '6.3V'        | '20%'    | 'DISCRETE' | 'CAP CHIP 47U 6.3V(20%,X5R,0805)MURSELASN'                     | 'CHIP0805'     | ''          | ''   | '20230713'
 '47UF'     | '6.3V'  | '20%'     | 'C0805'     | 'EMPTY'   | 'CH6471M9A08SEL1'(!) = ''              | ''                 | ''       | 'CH6471M9A08SEL1' |'C0805_H57'| '(SMC0805AW)'                                                        | 'NA'       | '6.3V'        | '20%'    | 'IO'       | 'CAP CHIP 47U 6.3V(20%,X5R,0805)MURSELASN'                     | 'CHIP0805'     | ''          | ''   | '20230713'
 '47UF'     | '4V'    | '20%'     | 'C0805'     | 'X6S'     | 'CH647KMEA04SEL1'(!) = ''              | ''                 | ''       | 'CH647KMEA04SEL1' |'C0805_H57'| '(SMC0805AW)'                                                        | '47UF'     | '4V'          | '20%'    | 'DISCRETE' | 'CAP CHIP 47U 4V(+-20%,X6S,0805)MURSELA'                       | 'CHIP0805'     | ''          | ''   | '20230713'
 '47UF'     | '4V'    | '20%'     | 'C0805'     | 'EMPTY'   | 'CH647KMEA04SEL1'(!) = ''              | ''                 | ''       | 'CH647KMEA04SEL1' |'C0805_H57'| '(SMC0805AW)'                                                        | 'NA'       | '4V'          | '20%'    | 'IO'       | 'CAP CHIP 47U 4V(+-20%,X6S,0805)MURSELA'                       | 'CHIP0805'     | ''          | ''   | '20230713'
 '47UF'     | '2.5V'  | '20%'     | 'C0603'     | 'X6S'     | 'CH647LME900SEL1'(!) = ''              | ''                 | ''       | 'CH647LME900SEL1' |'C0603'| '(SMC0603AW)'                                                        | '47UF'     | '2.5V'        | '20%'    | 'DISCRETE' | 'CAP CHIP 47U 2.5V(20%,X6S,0603)MURSELASN'                     | 'CHIP0603'     | ''          | ''   | '20230713'
 '47UF'     | '2.5V'  | '20%'     | 'C0603'     | 'EMPTY'   | 'CH647LME900SEL1'(!) = ''              | ''                 | ''       | 'CH647LME900SEL1' |'C0603'| '(SMC0603AW)'                                                        | 'NA'       | '2.5V'        | '20%'    | 'IO'       | 'CAP CHIP 47U 2.5V(20%,X6S,0603)MURSELASN'                     | 'CHIP0603'     | ''          | ''   | '20230713'
 '100UF'    | '4V'    | '20%'     | 'C0805'     | 'X6S'     | 'CH710KMEA01SEL1'(!) = ''              | ''                 | ''       | 'CH710KMEA01SEL1' |'C0805_H61'| '(SMC0805AW)'                                                        | '100UF'    | '4V'          | '20%'    | 'DISCRETE' | 'CAP CHIP 100U 4V(20%,X6S,0805)MURSELASN'                      | 'CHIP0805'     | ''          | ''   | '20230713'
 '100UF'    | '4V'    | '20%'     | 'C0805'     | 'EMPTY'   | 'CH710KMEA01SEL1'(!) = ''              | ''                 | ''       | 'CH710KMEA01SEL1' |'C0805_H61'| '(SMC0805AW)'                                                        | 'NA'       | '4V'          | '20%'    | 'IO'       | 'CAP CHIP 100U 4V(20%,X6S,0805)MURSELASN'                      | 'CHIP0805'     | ''          | ''   | '20230713'
 '4.7UF'    | '2.5V'  | '20%'     | 'C0201'     | 'X6S'     | 'CH547LMEE00'(!)   = ''              | ''                 | ''       | 'CH547LMEE00'     |'C0201_H16'| '(SMC0201AW)'                                                        | '4.7UF'    | '2.5V'        | '20%'    | 'DISCRETE' | 'CAP CHIP 4.7U 2.5V(+-20%,X6S,0201)'                           | 'CHIP0201'     | ''          | ''   | '20230801'
 '4.7UF'    | '2.5V'  | '20%'     | 'C0201'     | 'EMPTY'   | 'CH547LMEE00'(!)   = ''              | ''                 | ''       | 'CH547LMEE00'     |'C0201_H16'| '(SMC0201AW)'                                                        | 'NA'       | '2.5V'        | '20%'    | 'IO'       | 'CAP CHIP 4.7U 2.5V(+-20%,X6S,0201)'                           | 'CHIP0201'     | ''          | ''   | '20230801'
 '180PF'    | '50V'   | '5%'      | 'C0402'     | 'NPO'     | 'CH1186J0B17'(!)   = ''              | ''                 | ''       | 'CH1186J0B17'     |'C0402'| '(C0402-0201)'                                                       | '180PF'    | '50V'         | '5%'     | 'DISCRETE' | 'CAP CHIP 180P 50V(+-5%,NPO,0402)YGO'                          | 'CHIP0402'     | ''          | ''   | '20230801'
 '180PF'    | '50V'   | '5%'      | 'C0402'     | 'EMPTY'   | 'CH1186J0B17'(!)   = ''              | ''                 | ''       | 'CH1186J0B17'     |'C0402'| '(C0402-0201)'                                                       | 'NA'       | '50V'         | '5%'     | 'IO'       | 'CAP CHIP 180P 50V(+-5%,NPO,0402)YGO'                          | 'CHIP0402'     | ''          | ''   | '20230801'
 '2700PF'   | '50V'   | '10%'     | 'C0402'     | 'X7R'     | 'CH2276K1B10'(!)   = ''              | ''                 | ''       | 'CH2276K1B10'     |'C0402'| '(C0402-0201)'                                                       | '2700PF'   | '50V'         | '10%'    | 'DISCRETE' | 'CAP CHIP 2700P 50V(+-10%,X7R,0402)YGO'                        | 'CHIP0402'     | ''          | ''   | '20230802'
 '2700PF'   | '50V'   | '10%'     | 'C0402'     | 'EMPTY'   | 'CH2276K1B10'(!)   = ''              | ''                 | ''       | 'CH2276K1B10'     |'C0402'| '(C0402-0201)'                                                       | 'NA'       | '50V'         | '10%'    | 'IO'       | 'CAP CHIP 2700P 50V(+-10%,X7R,0402)YGO'                        | 'CHIP0402'     | ''          | ''   | '20230802'
 '4.7UF'    | '2.5V'  | '20%'     | 'C0201'     | 'X6S'     | 'CH547LMEE01'(!)   = ''               | ''               | ''       | 'CH547LMEE01'     |'C0201_H22'| '(SMC0201AW)'                                                        | '4.7UF'    | '2.5V'        | '20%'    | 'DISCRETE' | 'CAP CHIP 4.7U 2.5V(+-20%,X6S,0201,H0.55)'                     | 'CHIP0201'     | ''          | ''   | '20230816'
 '4.7UF'    | '2.5V'  | '20%'     | 'C0201'     | 'EMPTY'   | 'CH547LMEE01'(!)   = ''               | ''               | ''       | 'CH547LMEE01'     |'C0201_H22'| '(SMC0201AW)'                                                        | 'NA'       | '2.5V'        | '20%'    | 'IO'       | 'CAP CHIP 4.7U 2.5V(+-20%,X6S,0201,H0.55)'                     | 'CHIP0201'     | ''          | ''   | '20230816'

END_PART

END.

